G04 ================== begin FILE IDENTIFICATION RECORD ==================*
G04 Layout Name:  DAT6MTH3AD0_t6m_cm_d_brd_103112_274.brd*
G04 Film Name:    fab.art*
G04 File Format:  Gerber RS274X*
G04 File Origin:  Cadence Allegro 16.3-S048*
G04 Origin Date:  Tue Nov 26 10:18:25 2013*
G04 *
G04 Layer:  MANUFACTURING/NCLEGEND-1-10*
G04 Layer:  MANUFACTURING/PHOTOPLOT_OUTLINE*
G04 Layer:  MANUFACTURING/NCDRILL_LEGEND*
G04 Layer:  MANUFACTURING/NCDRILL_FIGURE*
G04 Layer:  MANUFACTURING/DIMENSION*
G04 Layer:  MANUFACTURING/DETAILS*
G04 Layer:  DRAWING FORMAT/TITLE_BLOCK*
G04 Layer:  DRAWING FORMAT/TITLE_DATA_FAB*
G04 Layer:  BOARD GEOMETRY/OUTLINE*
G04 *
G04 Offset:    (0.00 0.00)*
G04 Mirror:    No*
G04 Mode:      Positive*
G04 Rotation:  0*
G04 FullContactRelief:  No*
G04 UndefLineWidth:     6.00*
G04 ================== end FILE IDENTIFICATION RECORD ====================*
%FSLAX25Y25*MOIN*%
%IR0*IPPOS*OFA0.00000B0.00000*MIA0B0*SFA1.00000B1.00000*%
%AMMACRO15*
1,1,.006,.06,0.0*
20,1,.006,.06,0.0,0.0,-.06,0.0*
1,1,.006,0.0,-.06*
20,1,.006,0.0,-.06,-.06,0.0,0.0*
1,1,.006,-.06,0.0*
20,1,.006,-.06,0.0,0.0,.06,0.0*
1,1,.006,0.0,.06*
20,1,.006,0.0,.06,.06,0.0,0.0*
1,1,.006,.06,0.0*
1,1,.006,-.042,-.05*
20,1,.006,-.042,-.05,-.042,.01,0.0*
1,1,.006,-.042,.01*
1,1,.006,-.042,.001*
20,1,.006,-.042,.001,-.047,.006,0.0*
1,1,.006,-.047,.006*
20,1,.006,-.047,.006,-.053,.009,0.0*
1,1,.006,-.053,.009*
20,1,.006,-.053,.009,-.06,.01,0.0*
1,1,.006,-.06,.01*
20,1,.006,-.06,.01,-.066,.009,0.0*
1,1,.006,-.066,.009*
20,1,.006,-.066,.009,-.073,.004,0.0*
1,1,.006,-.073,.004*
20,1,.006,-.073,.004,-.077,-.003,0.0*
1,1,.006,-.077,-.003*
20,1,.006,-.077,-.003,-.078,-.01,0.0*
1,1,.006,-.078,-.01*
20,1,.006,-.078,-.01,-.077,-.017,0.0*
1,1,.006,-.077,-.017*
20,1,.006,-.077,-.017,-.073,-.024,0.0*
1,1,.006,-.073,-.024*
20,1,.006,-.073,-.024,-.066,-.029,0.0*
1,1,.006,-.066,-.029*
20,1,.006,-.066,-.029,-.06,-.03,0.0*
1,1,.006,-.06,-.03*
20,1,.006,-.06,-.03,-.053,-.029,0.0*
1,1,.006,-.053,-.029*
20,1,.006,-.053,-.029,-.047,-.026,0.0*
1,1,.006,-.047,-.026*
20,1,.006,-.047,-.026,-.042,-.021,0.0*
1,1,.006,-.042,-.021*
1,1,.006,-.02499,.01*
20,1,.006,-.02499,.01,-.01299,-.03,0.0*
1,1,.006,-.01299,-.03*
20,1,.006,-.01299,-.03,.00001,.01,0.0*
1,1,.006,.00001,.01*
20,1,.006,.00001,.01,.01301,-.03,0.0*
1,1,.006,.01301,-.03*
20,1,.006,.01301,-.03,.02501,.01,0.0*
1,1,.006,.02501,.01*
1,1,.006,.04202,-.05*
20,1,.006,.04202,-.05,.04202,.01,0.0*
1,1,.006,.04202,.01*
1,1,.006,.04202,.001*
20,1,.006,.04202,.001,.04702,.006,0.0*
1,1,.006,.04702,.006*
20,1,.006,.04702,.006,.05202,.009,0.0*
1,1,.006,.05202,.009*
20,1,.006,.05202,.009,.06002,.01,0.0*
1,1,.006,.06002,.01*
20,1,.006,.06002,.01,.06702,.009,0.0*
1,1,.006,.06702,.009*
20,1,.006,.06702,.009,.07402,.004,0.0*
1,1,.006,.07402,.004*
20,1,.006,.07402,.004,.07702,-.003,0.0*
1,1,.006,.07702,-.003*
20,1,.006,.07702,-.003,.07802,-.01,0.0*
1,1,.006,.07802,-.01*
20,1,.006,.07802,-.01,.07702,-.017,0.0*
1,1,.006,.07702,-.017*
20,1,.006,.07702,-.017,.07402,-.024,0.0*
1,1,.006,.07402,-.024*
20,1,.006,.07402,-.024,.06802,-.028,0.0*
1,1,.006,.06802,-.028*
20,1,.006,.06802,-.028,.06002,-.03,0.0*
1,1,.006,.06002,-.03*
20,1,.006,.06002,-.03,.05302,-.029,0.0*
1,1,.006,.05302,-.029*
20,1,.006,.05302,-.029,.04602,-.026,0.0*
1,1,.006,.04602,-.026*
20,1,.006,.04602,-.026,.04202,-.022,0.0*
1,1,.006,.04202,-.022*
%
%ADD15MACRO15*%
%AMMACRO23*
1,1,.006,.059,0.0*
20,1,.006,.059,0.0,0.0,-.059,0.0*
1,1,.006,0.0,-.059*
20,1,.006,0.0,-.059,-.059,0.0,0.0*
1,1,.006,-.059,0.0*
20,1,.006,-.059,0.0,0.0,.059,0.0*
1,1,.006,0.0,.059*
20,1,.006,0.0,.059,.059,0.0,0.0*
1,1,.006,.059,0.0*
1,1,.006,-.0413,-.04917*
20,1,.006,-.0413,-.04917,-.0413,.00983,0.0*
1,1,.006,-.0413,.00983*
1,1,.006,-.0413,.00098*
20,1,.006,-.0413,.00098,-.04622,.0059,0.0*
1,1,.006,-.04622,.0059*
20,1,.006,-.04622,.0059,-.05212,.00885,0.0*
1,1,.006,-.05212,.00885*
20,1,.006,-.05212,.00885,-.059,.00983,0.0*
1,1,.006,-.059,.00983*
20,1,.006,-.059,.00983,-.0649,.00885,0.0*
1,1,.006,-.0649,.00885*
20,1,.006,-.0649,.00885,-.07178,.00393,0.0*
1,1,.006,-.07178,.00393*
20,1,.006,-.07178,.00393,-.07572,-.00295,0.0*
1,1,.006,-.07572,-.00295*
20,1,.006,-.07572,-.00295,-.0767,-.00983,0.0*
1,1,.006,-.0767,-.00983*
20,1,.006,-.0767,-.00983,-.07572,-.01672,0.0*
1,1,.006,-.07572,-.01672*
20,1,.006,-.07572,-.01672,-.07178,-.0236,0.0*
1,1,.006,-.07178,-.0236*
20,1,.006,-.07178,-.0236,-.0649,-.02852,0.0*
1,1,.006,-.0649,-.02852*
20,1,.006,-.0649,-.02852,-.059,-.0295,0.0*
1,1,.006,-.059,-.0295*
20,1,.006,-.059,-.0295,-.05212,-.02852,0.0*
1,1,.006,-.05212,-.02852*
20,1,.006,-.05212,-.02852,-.04622,-.02557,0.0*
1,1,.006,-.04622,-.02557*
20,1,.006,-.04622,-.02557,-.0413,-.02065,0.0*
1,1,.006,-.0413,-.02065*
1,1,.006,.01771,-.04917*
20,1,.006,.01771,-.04917,.01771,.00983,0.0*
1,1,.006,.01771,.00983*
1,1,.006,.01771,.00098*
20,1,.006,.01771,.00098,.01279,.0059,0.0*
1,1,.006,.01279,.0059*
20,1,.006,.01279,.0059,.00689,.00885,0.0*
1,1,.006,.00689,.00885*
20,1,.006,.00689,.00885,.00001,.00983,0.0*
1,1,.006,.00001,.00983*
20,1,.006,.00001,.00983,-.00589,.00885,0.0*
1,1,.006,-.00589,.00885*
20,1,.006,-.00589,.00885,-.01277,.00393,0.0*
1,1,.006,-.01277,.00393*
20,1,.006,-.01277,.00393,-.01671,-.00295,0.0*
1,1,.006,-.01671,-.00295*
20,1,.006,-.01671,-.00295,-.01769,-.00983,0.0*
1,1,.006,-.01769,-.00983*
20,1,.006,-.01769,-.00983,-.01671,-.01672,0.0*
1,1,.006,-.01671,-.01672*
20,1,.006,-.01671,-.01672,-.01277,-.0236,0.0*
1,1,.006,-.01277,-.0236*
20,1,.006,-.01277,-.0236,-.00589,-.02852,0.0*
1,1,.006,-.00589,-.02852*
20,1,.006,-.00589,-.02852,.00001,-.0295,0.0*
1,1,.006,.00001,-.0295*
20,1,.006,.00001,-.0295,.00689,-.02852,0.0*
1,1,.006,.00689,-.02852*
20,1,.006,.00689,-.02852,.01279,-.02557,0.0*
1,1,.006,.01279,-.02557*
20,1,.006,.01279,-.02557,.01771,-.02065,0.0*
1,1,.006,.01771,-.02065*
1,1,.006,.05902,.00983*
20,1,.006,.05902,.00983,.05902,-.0295,0.0*
1,1,.006,.05902,-.0295*
1,1,.006,.05902,.02557*
20,1,.006,.05902,.02557,.05705,.02655,0.0*
1,1,.006,.05705,.02655*
20,1,.006,.05705,.02655,.05705,.02852,0.0*
1,1,.006,.05705,.02852*
20,1,.006,.05705,.02852,.05902,.0295,0.0*
1,1,.006,.05902,.0295*
20,1,.006,.05902,.0295,.06099,.02852,0.0*
1,1,.006,.06099,.02852*
20,1,.006,.06099,.02852,.06099,.02655,0.0*
1,1,.006,.06099,.02655*
20,1,.006,.06099,.02655,.05902,.02557,0.0*
1,1,.006,.05902,.02557*
%
%ADD23MACRO23*%
%AMMACRO31*
1,1,.006,.1065,0.0*
20,1,.006,.1065,0.0,.104882,-.018494,0.0*
1,1,.006,.104882,-.018494*
20,1,.006,.104882,-.018494,.100077,-.036425,0.0*
1,1,.006,.100077,-.036425*
20,1,.006,.100077,-.036425,.092232,-.05325,0.0*
1,1,.006,.092232,-.05325*
20,1,.006,.092232,-.05325,.081584,-.068457,0.0*
1,1,.006,.081584,-.068457*
20,1,.006,.081584,-.068457,.068457,-.081584,0.0*
1,1,.006,.068457,-.081584*
20,1,.006,.068457,-.081584,.05325,-.092232,0.0*
1,1,.006,.05325,-.092232*
20,1,.006,.05325,-.092232,.036425,-.100077,0.0*
1,1,.006,.036425,-.100077*
20,1,.006,.036425,-.100077,.018494,-.104882,0.0*
1,1,.006,.018494,-.104882*
20,1,.006,.018494,-.104882,0.0,-.1065,0.0*
1,1,.006,0.0,-.1065*
20,1,.006,0.0,-.1065,-.018494,-.104882,0.0*
1,1,.006,-.018494,-.104882*
20,1,.006,-.018494,-.104882,-.036425,-.100077,0.0*
1,1,.006,-.036425,-.100077*
20,1,.006,-.036425,-.100077,-.05325,-.092232,0.0*
1,1,.006,-.05325,-.092232*
20,1,.006,-.05325,-.092232,-.068457,-.081584,0.0*
1,1,.006,-.068457,-.081584*
20,1,.006,-.068457,-.081584,-.081584,-.068457,0.0*
1,1,.006,-.081584,-.068457*
20,1,.006,-.081584,-.068457,-.092232,-.05325,0.0*
1,1,.006,-.092232,-.05325*
20,1,.006,-.092232,-.05325,-.100077,-.036425,0.0*
1,1,.006,-.100077,-.036425*
20,1,.006,-.100077,-.036425,-.104882,-.018494,0.0*
1,1,.006,-.104882,-.018494*
20,1,.006,-.104882,-.018494,-.1065,0.0,0.0*
1,1,.006,-.1065,0.0*
20,1,.006,-.1065,0.0,-.104882,.018494,0.0*
1,1,.006,-.104882,.018494*
20,1,.006,-.104882,.018494,-.100077,.036425,0.0*
1,1,.006,-.100077,.036425*
20,1,.006,-.100077,.036425,-.092232,.05325,0.0*
1,1,.006,-.092232,.05325*
20,1,.006,-.092232,.05325,-.081584,.068457,0.0*
1,1,.006,-.081584,.068457*
20,1,.006,-.081584,.068457,-.068457,.081584,0.0*
1,1,.006,-.068457,.081584*
20,1,.006,-.068457,.081584,-.05325,.092232,0.0*
1,1,.006,-.05325,.092232*
20,1,.006,-.05325,.092232,-.036425,.100077,0.0*
1,1,.006,-.036425,.100077*
20,1,.006,-.036425,.100077,-.018494,.104882,0.0*
1,1,.006,-.018494,.104882*
20,1,.006,-.018494,.104882,0.0,.1065,0.0*
1,1,.006,0.0,.1065*
20,1,.006,0.0,.1065,.018494,.104882,0.0*
1,1,.006,.018494,.104882*
20,1,.006,.018494,.104882,.036425,.100077,0.0*
1,1,.006,.036425,.100077*
20,1,.006,.036425,.100077,.05325,.092232,0.0*
1,1,.006,.05325,.092232*
20,1,.006,.05325,.092232,.068457,.081584,0.0*
1,1,.006,.068457,.081584*
20,1,.006,.068457,.081584,.081584,.068457,0.0*
1,1,.006,.081584,.068457*
20,1,.006,.081584,.068457,.092232,.05325,0.0*
1,1,.006,.092232,.05325*
20,1,.006,.092232,.05325,.100077,.036425,0.0*
1,1,.006,.100077,.036425*
20,1,.006,.100077,.036425,.104882,.018494,0.0*
1,1,.006,.104882,.018494*
20,1,.006,.104882,.018494,.1065,0.0,0.0*
1,1,.006,.1065,0.0*
1,1,.006,-.14023,.0355*
20,1,.006,-.14023,.0355,-.12957,.04615,0.0*
1,1,.006,-.12957,.04615*
20,1,.006,-.12957,.04615,-.11715,.05148,0.0*
1,1,.006,-.11715,.05148*
20,1,.006,-.11715,.05148,-.10295,.05325,0.0*
1,1,.006,-.10295,.05325*
20,1,.006,-.10295,.05325,-.0852,.0497,0.0*
1,1,.006,-.0852,.0497*
20,1,.006,-.0852,.0497,-.07277,.04082,0.0*
1,1,.006,-.07277,.04082*
20,1,.006,-.07277,.04082,-.06922,.03018,0.0*
1,1,.006,-.06922,.03018*
20,1,.006,-.06922,.03018,-.071,.01952,0.0*
1,1,.006,-.071,.01952*
20,1,.006,-.071,.01952,-.0781,.01065,0.0*
1,1,.006,-.0781,.01065*
20,1,.006,-.0781,.01065,-.1136,-.0071,0.0*
1,1,.006,-.1136,-.0071*
20,1,.006,-.1136,-.0071,-.12957,-.01953,0.0*
1,1,.006,-.12957,-.01953*
20,1,.006,-.12957,-.01953,-.14023,-.03728,0.0*
1,1,.006,-.14023,-.03728*
20,1,.006,-.14023,-.03728,-.14378,-.05325,0.0*
1,1,.006,-.14378,-.05325*
20,1,.006,-.14378,-.05325,-.06922,-.05325,0.0*
1,1,.006,-.06922,-.05325*
1,1,.006,.00001,-.05325*
20,1,.006,.00001,-.05325,.00001,.05325,0.0*
1,1,.006,.00001,.05325*
20,1,.006,.00001,.05325,-.02129,.03195,0.0*
1,1,.006,-.02129,.03195*
1,1,.006,-.02129,-.05325*
20,1,.006,-.02129,-.05325,.02131,-.05325,0.0*
1,1,.006,.02131,-.05325*
1,1,.006,.06747,-.03195*
20,1,.006,.06747,-.03195,.07812,-.04438,0.0*
1,1,.006,.07812,-.04438*
20,1,.006,.07812,-.04438,.09232,-.05148,0.0*
1,1,.006,.09232,-.05148*
20,1,.006,.09232,-.05148,.1083,-.05325,0.0*
1,1,.006,.1083,-.05325*
20,1,.006,.1083,-.05325,.1225,-.05148,0.0*
1,1,.006,.1225,-.05148*
20,1,.006,.1225,-.05148,.1367,-.0426,0.0*
1,1,.006,.1367,-.0426*
20,1,.006,.1367,-.0426,.14557,-.03195,0.0*
1,1,.006,.14557,-.03195*
20,1,.006,.14557,-.03195,.14734,-.0213,0.0*
1,1,.006,.14734,-.0213*
20,1,.006,.14734,-.0213,.1438,-.00888,0.0*
1,1,.006,.1438,-.00888*
20,1,.006,.1438,-.00888,.13137,0.0,0.0*
1,1,.006,.13137,0.0*
20,1,.006,.13137,0.0,.11894,.00355,0.0*
1,1,.006,.11894,.00355*
20,1,.006,.11894,.00355,.10297,.00355,0.0*
1,1,.006,.10297,.00355*
1,1,.006,.11894,.00355*
20,1,.006,.11894,.00355,.12959,.00887,0.0*
1,1,.006,.12959,.00887*
20,1,.006,.12959,.00887,.13847,.01775,0.0*
1,1,.006,.13847,.01775*
20,1,.006,.13847,.01775,.14202,.0284,0.0*
1,1,.006,.14202,.0284*
20,1,.006,.14202,.0284,.13847,.03905,0.0*
1,1,.006,.13847,.03905*
20,1,.006,.13847,.03905,.12959,.04792,0.0*
1,1,.006,.12959,.04792*
20,1,.006,.12959,.04792,.11362,.05325,0.0*
1,1,.006,.11362,.05325*
20,1,.006,.11362,.05325,.09765,.05148,0.0*
1,1,.006,.09765,.05148*
20,1,.006,.09765,.05148,.08167,.04437,0.0*
1,1,.006,.08167,.04437*
%
%ADD31MACRO31*%
%AMMACRO25*
1,1,.006,.035,0.0*
20,1,.006,.035,0.0,.034468,-.006078,0.0*
1,1,.006,.034468,-.006078*
20,1,.006,.034468,-.006078,.032889,-.011971,0.0*
1,1,.006,.032889,-.011971*
20,1,.006,.032889,-.011971,.030311,-.0175,0.0*
1,1,.006,.030311,-.0175*
20,1,.006,.030311,-.0175,.026812,-.022498,0.0*
1,1,.006,.026812,-.022498*
20,1,.006,.026812,-.022498,.022498,-.026812,0.0*
1,1,.006,.022498,-.026812*
20,1,.006,.022498,-.026812,.0175,-.030311,0.0*
1,1,.006,.0175,-.030311*
20,1,.006,.0175,-.030311,.011971,-.032889,0.0*
1,1,.006,.011971,-.032889*
20,1,.006,.011971,-.032889,.006078,-.034468,0.0*
1,1,.006,.006078,-.034468*
20,1,.006,.006078,-.034468,0.0,-.035,0.0*
1,1,.006,0.0,-.035*
20,1,.006,0.0,-.035,-.006078,-.034468,0.0*
1,1,.006,-.006078,-.034468*
20,1,.006,-.006078,-.034468,-.011971,-.032889,0.0*
1,1,.006,-.011971,-.032889*
20,1,.006,-.011971,-.032889,-.0175,-.030311,0.0*
1,1,.006,-.0175,-.030311*
20,1,.006,-.0175,-.030311,-.022498,-.026812,0.0*
1,1,.006,-.022498,-.026812*
20,1,.006,-.022498,-.026812,-.026812,-.022498,0.0*
1,1,.006,-.026812,-.022498*
20,1,.006,-.026812,-.022498,-.030311,-.0175,0.0*
1,1,.006,-.030311,-.0175*
20,1,.006,-.030311,-.0175,-.032889,-.011971,0.0*
1,1,.006,-.032889,-.011971*
20,1,.006,-.032889,-.011971,-.034468,-.006078,0.0*
1,1,.006,-.034468,-.006078*
20,1,.006,-.034468,-.006078,-.035,0.0,0.0*
1,1,.006,-.035,0.0*
20,1,.006,-.035,0.0,-.034468,.006078,0.0*
1,1,.006,-.034468,.006078*
20,1,.006,-.034468,.006078,-.032889,.011971,0.0*
1,1,.006,-.032889,.011971*
20,1,.006,-.032889,.011971,-.030311,.0175,0.0*
1,1,.006,-.030311,.0175*
20,1,.006,-.030311,.0175,-.026812,.022498,0.0*
1,1,.006,-.026812,.022498*
20,1,.006,-.026812,.022498,-.022498,.026812,0.0*
1,1,.006,-.022498,.026812*
20,1,.006,-.022498,.026812,-.0175,.030311,0.0*
1,1,.006,-.0175,.030311*
20,1,.006,-.0175,.030311,-.011971,.032889,0.0*
1,1,.006,-.011971,.032889*
20,1,.006,-.011971,.032889,-.006078,.034468,0.0*
1,1,.006,-.006078,.034468*
20,1,.006,-.006078,.034468,0.0,.035,0.0*
1,1,.006,0.0,.035*
20,1,.006,0.0,.035,.006078,.034468,0.0*
1,1,.006,.006078,.034468*
20,1,.006,.006078,.034468,.011971,.032889,0.0*
1,1,.006,.011971,.032889*
20,1,.006,.011971,.032889,.0175,.030311,0.0*
1,1,.006,.0175,.030311*
20,1,.006,.0175,.030311,.022498,.026812,0.0*
1,1,.006,.022498,.026812*
20,1,.006,.022498,.026812,.026812,.022498,0.0*
1,1,.006,.026812,.022498*
20,1,.006,.026812,.022498,.030311,.0175,0.0*
1,1,.006,.030311,.0175*
20,1,.006,.030311,.0175,.032889,.011971,0.0*
1,1,.006,.032889,.011971*
20,1,.006,.032889,.011971,.034468,.006078,0.0*
1,1,.006,.034468,.006078*
20,1,.006,.034468,.006078,.035,0.0,0.0*
1,1,.006,.035,0.0*
1,1,.006,-.035,.0175*
20,1,.006,-.035,.0175,-.035,-.0175,0.0*
1,1,.006,-.035,-.0175*
1,1,.006,-.04842,.0175*
20,1,.006,-.04842,.0175,-.02158,.0175,0.0*
1,1,.006,-.02158,.0175*
1,1,.006,-.01166,-.0175*
20,1,.006,-.01166,-.0175,-.01166,.0175,0.0*
1,1,.006,-.01166,.0175*
20,1,.006,-.01166,.0175,.00234,.0175,0.0*
1,1,.006,.00234,.0175*
20,1,.006,.00234,.0175,.00701,.01575,0.0*
1,1,.006,.00701,.01575*
20,1,.006,.00701,.01575,.01051,.01167,0.0*
1,1,.006,.01051,.01167*
20,1,.006,.01051,.01167,.01168,.007,0.0*
1,1,.006,.01168,.007*
20,1,.006,.01168,.007,.01051,.00233,0.0*
1,1,.006,.01051,.00233*
20,1,.006,.01051,.00233,.00759,-.00117,0.0*
1,1,.006,.00759,-.00117*
20,1,.006,.00759,-.00117,.00234,-.00292,0.0*
1,1,.006,.00234,-.00292*
20,1,.006,.00234,-.00292,-.01166,-.00292,0.0*
1,1,.006,-.01166,-.00292*
1,1,.006,.03502,.0175*
20,1,.006,.03502,.0175,.03502,-.0175,0.0*
1,1,.006,.03502,-.0175*
1,1,.006,.0216,.0175*
20,1,.006,.0216,.0175,.04844,.0175,0.0*
1,1,.006,.04844,.0175*
%
%ADD25MACRO25*%
%AMMACRO27*
1,1,.006,.035,.035*
20,1,.006,.035,.035,.035,-.035,0.0*
1,1,.006,.035,-.035*
20,1,.006,.035,-.035,-.035,-.035,0.0*
1,1,.006,-.035,-.035*
20,1,.006,-.035,-.035,-.035,.035,0.0*
1,1,.006,-.035,.035*
20,1,.006,-.035,.035,.035,.035,0.0*
1,1,.006,.035,.035*
1,1,.006,-.035,.0175*
20,1,.006,-.035,.0175,-.03967,.01633,0.0*
1,1,.006,-.03967,.01633*
20,1,.006,-.03967,.01633,-.04317,.01342,0.0*
1,1,.006,-.04317,.01342*
20,1,.006,-.04317,.01342,-.0455,.00992,0.0*
1,1,.006,-.0455,.00992*
20,1,.006,-.0455,.00992,-.04725,.00525,0.0*
1,1,.006,-.04725,.00525*
20,1,.006,-.04725,.00525,-.04783,0.0,0.0*
1,1,.006,-.04783,0.0*
20,1,.006,-.04783,0.0,-.04725,-.00525,0.0*
1,1,.006,-.04725,-.00525*
20,1,.006,-.04725,-.00525,-.0455,-.00992,0.0*
1,1,.006,-.0455,-.00992*
20,1,.006,-.0455,-.00992,-.04317,-.01342,0.0*
1,1,.006,-.04317,-.01342*
20,1,.006,-.04317,-.01342,-.03967,-.01633,0.0*
1,1,.006,-.03967,-.01633*
20,1,.006,-.03967,-.01633,-.035,-.0175,0.0*
1,1,.006,-.035,-.0175*
20,1,.006,-.035,-.0175,-.03033,-.01633,0.0*
1,1,.006,-.03033,-.01633*
20,1,.006,-.03033,-.01633,-.02683,-.01342,0.0*
1,1,.006,-.02683,-.01342*
20,1,.006,-.02683,-.01342,-.0245,-.00992,0.0*
1,1,.006,-.0245,-.00992*
20,1,.006,-.0245,-.00992,-.02275,-.00525,0.0*
1,1,.006,-.02275,-.00525*
20,1,.006,-.02275,-.00525,-.02217,0.0,0.0*
1,1,.006,-.02217,0.0*
20,1,.006,-.02217,0.0,-.02275,.00525,0.0*
1,1,.006,-.02275,.00525*
20,1,.006,-.02275,.00525,-.0245,.00992,0.0*
1,1,.006,-.0245,.00992*
20,1,.006,-.0245,.00992,-.02683,.01342,0.0*
1,1,.006,-.02683,.01342*
20,1,.006,-.02683,.01342,-.03033,.01633,0.0*
1,1,.006,-.03033,.01633*
20,1,.006,-.03033,.01633,-.035,.0175,0.0*
1,1,.006,-.035,.0175*
1,1,.006,-.01107,.01167*
20,1,.006,-.01107,.01167,-.00757,.01517,0.0*
1,1,.006,-.00757,.01517*
20,1,.006,-.00757,.01517,-.00349,.01692,0.0*
1,1,.006,-.00349,.01692*
20,1,.006,-.00349,.01692,.00118,.0175,0.0*
1,1,.006,.00118,.0175*
20,1,.006,.00118,.0175,.00701,.01633,0.0*
1,1,.006,.00701,.01633*
20,1,.006,.00701,.01633,.01109,.01342,0.0*
1,1,.006,.01109,.01342*
20,1,.006,.01109,.01342,.01226,.00992,0.0*
1,1,.006,.01226,.00992*
20,1,.006,.01226,.00992,.01168,.00642,0.0*
1,1,.006,.01168,.00642*
20,1,.006,.01168,.00642,.00934,.0035,0.0*
1,1,.006,.00934,.0035*
20,1,.006,.00934,.0035,-.00232,-.00233,0.0*
1,1,.006,-.00232,-.00233*
20,1,.006,-.00232,-.00233,-.00757,-.00642,0.0*
1,1,.006,-.00757,-.00642*
20,1,.006,-.00757,-.00642,-.01107,-.01225,0.0*
1,1,.006,-.01107,-.01225*
20,1,.006,-.01107,-.01225,-.01224,-.0175,0.0*
1,1,.006,-.01224,-.0175*
20,1,.006,-.01224,-.0175,.01226,-.0175,0.0*
1,1,.006,.01226,-.0175*
1,1,.006,.02394,.01167*
20,1,.006,.02394,.01167,.02744,.01517,0.0*
1,1,.006,.02744,.01517*
20,1,.006,.02744,.01517,.03152,.01692,0.0*
1,1,.006,.03152,.01692*
20,1,.006,.03152,.01692,.03619,.0175,0.0*
1,1,.006,.03619,.0175*
20,1,.006,.03619,.0175,.04202,.01633,0.0*
1,1,.006,.04202,.01633*
20,1,.006,.04202,.01633,.0461,.01342,0.0*
1,1,.006,.0461,.01342*
20,1,.006,.0461,.01342,.04727,.00992,0.0*
1,1,.006,.04727,.00992*
20,1,.006,.04727,.00992,.04669,.00642,0.0*
1,1,.006,.04669,.00642*
20,1,.006,.04669,.00642,.04435,.0035,0.0*
1,1,.006,.04435,.0035*
20,1,.006,.04435,.0035,.03269,-.00233,0.0*
1,1,.006,.03269,-.00233*
20,1,.006,.03269,-.00233,.02744,-.00642,0.0*
1,1,.006,.02744,-.00642*
20,1,.006,.02744,-.00642,.02394,-.01225,0.0*
1,1,.006,.02394,-.01225*
20,1,.006,.02394,-.01225,.02277,-.0175,0.0*
1,1,.006,.02277,-.0175*
20,1,.006,.02277,-.0175,.04727,-.0175,0.0*
1,1,.006,.04727,-.0175*
%
%ADD27MACRO27*%
%AMMACRO14*
1,1,.006,.035,.035*
20,1,.006,.035,.035,.035,-.035,0.0*
1,1,.006,.035,-.035*
20,1,.006,.035,-.035,-.035,-.035,0.0*
1,1,.006,-.035,-.035*
20,1,.006,-.035,-.035,-.035,.035,0.0*
1,1,.006,-.035,.035*
20,1,.006,-.035,.035,.035,.035,0.0*
1,1,.006,.035,.035*
1,1,.006,-.035,.0175*
20,1,.006,-.035,.0175,-.03967,.01633,0.0*
1,1,.006,-.03967,.01633*
20,1,.006,-.03967,.01633,-.04317,.01342,0.0*
1,1,.006,-.04317,.01342*
20,1,.006,-.04317,.01342,-.0455,.00992,0.0*
1,1,.006,-.0455,.00992*
20,1,.006,-.0455,.00992,-.04725,.00525,0.0*
1,1,.006,-.04725,.00525*
20,1,.006,-.04725,.00525,-.04783,0.0,0.0*
1,1,.006,-.04783,0.0*
20,1,.006,-.04783,0.0,-.04725,-.00525,0.0*
1,1,.006,-.04725,-.00525*
20,1,.006,-.04725,-.00525,-.0455,-.00992,0.0*
1,1,.006,-.0455,-.00992*
20,1,.006,-.0455,-.00992,-.04317,-.01342,0.0*
1,1,.006,-.04317,-.01342*
20,1,.006,-.04317,-.01342,-.03967,-.01633,0.0*
1,1,.006,-.03967,-.01633*
20,1,.006,-.03967,-.01633,-.035,-.0175,0.0*
1,1,.006,-.035,-.0175*
20,1,.006,-.035,-.0175,-.03033,-.01633,0.0*
1,1,.006,-.03033,-.01633*
20,1,.006,-.03033,-.01633,-.02683,-.01342,0.0*
1,1,.006,-.02683,-.01342*
20,1,.006,-.02683,-.01342,-.0245,-.00992,0.0*
1,1,.006,-.0245,-.00992*
20,1,.006,-.0245,-.00992,-.02275,-.00525,0.0*
1,1,.006,-.02275,-.00525*
20,1,.006,-.02275,-.00525,-.02217,0.0,0.0*
1,1,.006,-.02217,0.0*
20,1,.006,-.02217,0.0,-.02275,.00525,0.0*
1,1,.006,-.02275,.00525*
20,1,.006,-.02275,.00525,-.0245,.00992,0.0*
1,1,.006,-.0245,.00992*
20,1,.006,-.0245,.00992,-.02683,.01342,0.0*
1,1,.006,-.02683,.01342*
20,1,.006,-.02683,.01342,-.03033,.01633,0.0*
1,1,.006,-.03033,.01633*
20,1,.006,-.03033,.01633,-.035,.0175,0.0*
1,1,.006,-.035,.0175*
1,1,.006,.00701,-.0175*
20,1,.006,.00701,-.0175,.00701,.0175,0.0*
1,1,.006,.00701,.0175*
20,1,.006,.00701,.0175,-.01457,-.00758,0.0*
1,1,.006,-.01457,-.00758*
20,1,.006,-.01457,-.00758,.01459,-.00758,0.0*
1,1,.006,.01459,-.00758*
1,1,.006,.03502,.0175*
20,1,.006,.03502,.0175,.03035,.01633,0.0*
1,1,.006,.03035,.01633*
20,1,.006,.03035,.01633,.02685,.01342,0.0*
1,1,.006,.02685,.01342*
20,1,.006,.02685,.01342,.02452,.00992,0.0*
1,1,.006,.02452,.00992*
20,1,.006,.02452,.00992,.02277,.00525,0.0*
1,1,.006,.02277,.00525*
20,1,.006,.02277,.00525,.02219,0.0,0.0*
1,1,.006,.02219,0.0*
20,1,.006,.02219,0.0,.02277,-.00525,0.0*
1,1,.006,.02277,-.00525*
20,1,.006,.02277,-.00525,.02452,-.00992,0.0*
1,1,.006,.02452,-.00992*
20,1,.006,.02452,-.00992,.02685,-.01342,0.0*
1,1,.006,.02685,-.01342*
20,1,.006,.02685,-.01342,.03035,-.01633,0.0*
1,1,.006,.03035,-.01633*
20,1,.006,.03035,-.01633,.03502,-.0175,0.0*
1,1,.006,.03502,-.0175*
20,1,.006,.03502,-.0175,.03969,-.01633,0.0*
1,1,.006,.03969,-.01633*
20,1,.006,.03969,-.01633,.04319,-.01342,0.0*
1,1,.006,.04319,-.01342*
20,1,.006,.04319,-.01342,.04552,-.00992,0.0*
1,1,.006,.04552,-.00992*
20,1,.006,.04552,-.00992,.04727,-.00525,0.0*
1,1,.006,.04727,-.00525*
20,1,.006,.04727,-.00525,.04785,0.0,0.0*
1,1,.006,.04785,0.0*
20,1,.006,.04785,0.0,.04727,.00525,0.0*
1,1,.006,.04727,.00525*
20,1,.006,.04727,.00525,.04552,.00992,0.0*
1,1,.006,.04552,.00992*
20,1,.006,.04552,.00992,.04319,.01342,0.0*
1,1,.006,.04319,.01342*
20,1,.006,.04319,.01342,.03969,.01633,0.0*
1,1,.006,.03969,.01633*
20,1,.006,.03969,.01633,.03502,.0175,0.0*
1,1,.006,.03502,.0175*
%
%ADD14MACRO14*%
%AMMACRO18*
1,1,.006,.035,.035*
20,1,.006,.035,.035,.035,-.035,0.0*
1,1,.006,.035,-.035*
20,1,.006,.035,-.035,-.035,-.035,0.0*
1,1,.006,-.035,-.035*
20,1,.006,-.035,-.035,-.035,.035,0.0*
1,1,.006,-.035,.035*
20,1,.006,-.035,.035,.035,.035,0.0*
1,1,.006,.035,.035*
1,1,.006,-.035,.0175*
20,1,.006,-.035,.0175,-.03967,.01633,0.0*
1,1,.006,-.03967,.01633*
20,1,.006,-.03967,.01633,-.04317,.01342,0.0*
1,1,.006,-.04317,.01342*
20,1,.006,-.04317,.01342,-.0455,.00992,0.0*
1,1,.006,-.0455,.00992*
20,1,.006,-.0455,.00992,-.04725,.00525,0.0*
1,1,.006,-.04725,.00525*
20,1,.006,-.04725,.00525,-.04783,0.0,0.0*
1,1,.006,-.04783,0.0*
20,1,.006,-.04783,0.0,-.04725,-.00525,0.0*
1,1,.006,-.04725,-.00525*
20,1,.006,-.04725,-.00525,-.0455,-.00992,0.0*
1,1,.006,-.0455,-.00992*
20,1,.006,-.0455,-.00992,-.04317,-.01342,0.0*
1,1,.006,-.04317,-.01342*
20,1,.006,-.04317,-.01342,-.03967,-.01633,0.0*
1,1,.006,-.03967,-.01633*
20,1,.006,-.03967,-.01633,-.035,-.0175,0.0*
1,1,.006,-.035,-.0175*
20,1,.006,-.035,-.0175,-.03033,-.01633,0.0*
1,1,.006,-.03033,-.01633*
20,1,.006,-.03033,-.01633,-.02683,-.01342,0.0*
1,1,.006,-.02683,-.01342*
20,1,.006,-.02683,-.01342,-.0245,-.00992,0.0*
1,1,.006,-.0245,-.00992*
20,1,.006,-.0245,-.00992,-.02275,-.00525,0.0*
1,1,.006,-.02275,-.00525*
20,1,.006,-.02275,-.00525,-.02217,0.0,0.0*
1,1,.006,-.02217,0.0*
20,1,.006,-.02217,0.0,-.02275,.00525,0.0*
1,1,.006,-.02275,.00525*
20,1,.006,-.02275,.00525,-.0245,.00992,0.0*
1,1,.006,-.0245,.00992*
20,1,.006,-.0245,.00992,-.02683,.01342,0.0*
1,1,.006,-.02683,.01342*
20,1,.006,-.02683,.01342,-.03033,.01633,0.0*
1,1,.006,-.03033,.01633*
20,1,.006,-.03033,.01633,-.035,.0175,0.0*
1,1,.006,-.035,.0175*
1,1,.006,-.01282,-.0105*
20,1,.006,-.01282,-.0105,-.00932,-.01458,0.0*
1,1,.006,-.00932,-.01458*
20,1,.006,-.00932,-.01458,-.00466,-.01692,0.0*
1,1,.006,-.00466,-.01692*
20,1,.006,-.00466,-.01692,.00059,-.0175,0.0*
1,1,.006,.00059,-.0175*
20,1,.006,.00059,-.0175,.00526,-.01692,0.0*
1,1,.006,.00526,-.01692*
20,1,.006,.00526,-.01692,.00993,-.014,0.0*
1,1,.006,.00993,-.014*
20,1,.006,.00993,-.014,.01284,-.0105,0.0*
1,1,.006,.01284,-.0105*
20,1,.006,.01284,-.0105,.01343,-.007,0.0*
1,1,.006,.01343,-.007*
20,1,.006,.01343,-.007,.01226,-.00292,0.0*
1,1,.006,.01226,-.00292*
20,1,.006,.01226,-.00292,.00818,0.0,0.0*
1,1,.006,.00818,0.0*
20,1,.006,.00818,0.0,.00409,.00117,0.0*
1,1,.006,.00409,.00117*
20,1,.006,.00409,.00117,-.00116,.00117,0.0*
1,1,.006,-.00116,.00117*
1,1,.006,.00409,.00117*
20,1,.006,.00409,.00117,.00759,.00292,0.0*
1,1,.006,.00759,.00292*
20,1,.006,.00759,.00292,.01051,.00583,0.0*
1,1,.006,.01051,.00583*
20,1,.006,.01051,.00583,.01168,.00933,0.0*
1,1,.006,.01168,.00933*
20,1,.006,.01168,.00933,.01051,.01283,0.0*
1,1,.006,.01051,.01283*
20,1,.006,.01051,.01283,.00759,.01575,0.0*
1,1,.006,.00759,.01575*
20,1,.006,.00759,.01575,.00234,.0175,0.0*
1,1,.006,.00234,.0175*
20,1,.006,.00234,.0175,-.00291,.01692,0.0*
1,1,.006,-.00291,.01692*
20,1,.006,-.00291,.01692,-.00816,.01458,0.0*
1,1,.006,-.00816,.01458*
1,1,.006,.02219,-.0105*
20,1,.006,.02219,-.0105,.02569,-.01458,0.0*
1,1,.006,.02569,-.01458*
20,1,.006,.02569,-.01458,.03035,-.01692,0.0*
1,1,.006,.03035,-.01692*
20,1,.006,.03035,-.01692,.0356,-.0175,0.0*
1,1,.006,.0356,-.0175*
20,1,.006,.0356,-.0175,.04027,-.01692,0.0*
1,1,.006,.04027,-.01692*
20,1,.006,.04027,-.01692,.04494,-.014,0.0*
1,1,.006,.04494,-.014*
20,1,.006,.04494,-.014,.04785,-.0105,0.0*
1,1,.006,.04785,-.0105*
20,1,.006,.04785,-.0105,.04844,-.007,0.0*
1,1,.006,.04844,-.007*
20,1,.006,.04844,-.007,.04727,-.00292,0.0*
1,1,.006,.04727,-.00292*
20,1,.006,.04727,-.00292,.04319,0.0,0.0*
1,1,.006,.04319,0.0*
20,1,.006,.04319,0.0,.0391,.00117,0.0*
1,1,.006,.0391,.00117*
20,1,.006,.0391,.00117,.03385,.00117,0.0*
1,1,.006,.03385,.00117*
1,1,.006,.0391,.00117*
20,1,.006,.0391,.00117,.0426,.00292,0.0*
1,1,.006,.0426,.00292*
20,1,.006,.0426,.00292,.04552,.00583,0.0*
1,1,.006,.04552,.00583*
20,1,.006,.04552,.00583,.04669,.00933,0.0*
1,1,.006,.04669,.00933*
20,1,.006,.04669,.00933,.04552,.01283,0.0*
1,1,.006,.04552,.01283*
20,1,.006,.04552,.01283,.0426,.01575,0.0*
1,1,.006,.0426,.01575*
20,1,.006,.0426,.01575,.03735,.0175,0.0*
1,1,.006,.03735,.0175*
20,1,.006,.03735,.0175,.0321,.01692,0.0*
1,1,.006,.0321,.01692*
20,1,.006,.0321,.01692,.02685,.01458,0.0*
1,1,.006,.02685,.01458*
%
%ADD18MACRO18*%
%AMMACRO37*
1,1,.006,.035,.035*
20,1,.006,.035,.035,.035,-.035,0.0*
1,1,.006,.035,-.035*
20,1,.006,.035,-.035,-.035,-.035,0.0*
1,1,.006,-.035,-.035*
20,1,.006,-.035,-.035,-.035,.035,0.0*
1,1,.006,-.035,.035*
20,1,.006,-.035,.035,.035,.035,0.0*
1,1,.006,.035,.035*
1,1,.006,-.035,.0175*
20,1,.006,-.035,.0175,-.03967,.01633,0.0*
1,1,.006,-.03967,.01633*
20,1,.006,-.03967,.01633,-.04317,.01342,0.0*
1,1,.006,-.04317,.01342*
20,1,.006,-.04317,.01342,-.0455,.00992,0.0*
1,1,.006,-.0455,.00992*
20,1,.006,-.0455,.00992,-.04725,.00525,0.0*
1,1,.006,-.04725,.00525*
20,1,.006,-.04725,.00525,-.04783,0.0,0.0*
1,1,.006,-.04783,0.0*
20,1,.006,-.04783,0.0,-.04725,-.00525,0.0*
1,1,.006,-.04725,-.00525*
20,1,.006,-.04725,-.00525,-.0455,-.00992,0.0*
1,1,.006,-.0455,-.00992*
20,1,.006,-.0455,-.00992,-.04317,-.01342,0.0*
1,1,.006,-.04317,-.01342*
20,1,.006,-.04317,-.01342,-.03967,-.01633,0.0*
1,1,.006,-.03967,-.01633*
20,1,.006,-.03967,-.01633,-.035,-.0175,0.0*
1,1,.006,-.035,-.0175*
20,1,.006,-.035,-.0175,-.03033,-.01633,0.0*
1,1,.006,-.03033,-.01633*
20,1,.006,-.03033,-.01633,-.02683,-.01342,0.0*
1,1,.006,-.02683,-.01342*
20,1,.006,-.02683,-.01342,-.0245,-.00992,0.0*
1,1,.006,-.0245,-.00992*
20,1,.006,-.0245,-.00992,-.02275,-.00525,0.0*
1,1,.006,-.02275,-.00525*
20,1,.006,-.02275,-.00525,-.02217,0.0,0.0*
1,1,.006,-.02217,0.0*
20,1,.006,-.02217,0.0,-.02275,.00525,0.0*
1,1,.006,-.02275,.00525*
20,1,.006,-.02275,.00525,-.0245,.00992,0.0*
1,1,.006,-.0245,.00992*
20,1,.006,-.0245,.00992,-.02683,.01342,0.0*
1,1,.006,-.02683,.01342*
20,1,.006,-.02683,.01342,-.03033,.01633,0.0*
1,1,.006,-.03033,.01633*
20,1,.006,-.03033,.01633,-.035,.0175,0.0*
1,1,.006,-.035,.0175*
1,1,.006,-.01107,.01167*
20,1,.006,-.01107,.01167,-.00757,.01517,0.0*
1,1,.006,-.00757,.01517*
20,1,.006,-.00757,.01517,-.00349,.01692,0.0*
1,1,.006,-.00349,.01692*
20,1,.006,-.00349,.01692,.00118,.0175,0.0*
1,1,.006,.00118,.0175*
20,1,.006,.00118,.0175,.00701,.01633,0.0*
1,1,.006,.00701,.01633*
20,1,.006,.00701,.01633,.01109,.01342,0.0*
1,1,.006,.01109,.01342*
20,1,.006,.01109,.01342,.01226,.00992,0.0*
1,1,.006,.01226,.00992*
20,1,.006,.01226,.00992,.01168,.00642,0.0*
1,1,.006,.01168,.00642*
20,1,.006,.01168,.00642,.00934,.0035,0.0*
1,1,.006,.00934,.0035*
20,1,.006,.00934,.0035,-.00232,-.00233,0.0*
1,1,.006,-.00232,-.00233*
20,1,.006,-.00232,-.00233,-.00757,-.00642,0.0*
1,1,.006,-.00757,-.00642*
20,1,.006,-.00757,-.00642,-.01107,-.01225,0.0*
1,1,.006,-.01107,-.01225*
20,1,.006,-.01107,-.01225,-.01224,-.0175,0.0*
1,1,.006,-.01224,-.0175*
20,1,.006,-.01224,-.0175,.01226,-.0175,0.0*
1,1,.006,.01226,-.0175*
1,1,.006,.02394,-.00292*
20,1,.006,.02394,-.00292,.02802,.00117,0.0*
1,1,.006,.02802,.00117*
20,1,.006,.02802,.00117,.03152,.0035,0.0*
1,1,.006,.03152,.0035*
20,1,.006,.03152,.0035,.03619,.00467,0.0*
1,1,.006,.03619,.00467*
20,1,.006,.03619,.00467,.04027,.0035,0.0*
1,1,.006,.04027,.0035*
20,1,.006,.04027,.0035,.04319,.00117,0.0*
1,1,.006,.04319,.00117*
20,1,.006,.04319,.00117,.04552,-.00233,0.0*
1,1,.006,.04552,-.00233*
20,1,.006,.04552,-.00233,.0461,-.00642,0.0*
1,1,.006,.0461,-.00642*
20,1,.006,.0461,-.00642,.04552,-.00992,0.0*
1,1,.006,.04552,-.00992*
20,1,.006,.04552,-.00992,.04319,-.01342,0.0*
1,1,.006,.04319,-.01342*
20,1,.006,.04319,-.01342,.03969,-.01633,0.0*
1,1,.006,.03969,-.01633*
20,1,.006,.03969,-.01633,.0356,-.0175,0.0*
1,1,.006,.0356,-.0175*
20,1,.006,.0356,-.0175,.03094,-.01633,0.0*
1,1,.006,.03094,-.01633*
20,1,.006,.03094,-.01633,.02685,-.01283,0.0*
1,1,.006,.02685,-.01283*
20,1,.006,.02685,-.01283,.02452,-.00758,0.0*
1,1,.006,.02452,-.00758*
20,1,.006,.02452,-.00758,.02394,-.00175,0.0*
1,1,.006,.02394,-.00175*
20,1,.006,.02394,-.00175,.0251,.00583,0.0*
1,1,.006,.0251,.00583*
20,1,.006,.0251,.00583,.02685,.00992,0.0*
1,1,.006,.02685,.00992*
20,1,.006,.02685,.00992,.02977,.014,0.0*
1,1,.006,.02977,.014*
20,1,.006,.02977,.014,.03385,.01692,0.0*
1,1,.006,.03385,.01692*
20,1,.006,.03385,.01692,.03794,.0175,0.0*
1,1,.006,.03794,.0175*
20,1,.006,.03794,.0175,.04202,.01633,0.0*
1,1,.006,.04202,.01633*
20,1,.006,.04202,.01633,.04494,.01342,0.0*
1,1,.006,.04494,.01342*
%
%ADD37MACRO37*%
%AMMACRO35*
1,1,.006,.035,.035*
20,1,.006,.035,.035,.035,-.035,0.0*
1,1,.006,.035,-.035*
20,1,.006,.035,-.035,-.035,-.035,0.0*
1,1,.006,-.035,-.035*
20,1,.006,-.035,-.035,-.035,.035,0.0*
1,1,.006,-.035,.035*
20,1,.006,-.035,.035,.035,.035,0.0*
1,1,.006,.035,.035*
1,1,.006,-.035,.0175*
20,1,.006,-.035,.0175,-.03967,.01633,0.0*
1,1,.006,-.03967,.01633*
20,1,.006,-.03967,.01633,-.04317,.01342,0.0*
1,1,.006,-.04317,.01342*
20,1,.006,-.04317,.01342,-.0455,.00992,0.0*
1,1,.006,-.0455,.00992*
20,1,.006,-.0455,.00992,-.04725,.00525,0.0*
1,1,.006,-.04725,.00525*
20,1,.006,-.04725,.00525,-.04783,0.0,0.0*
1,1,.006,-.04783,0.0*
20,1,.006,-.04783,0.0,-.04725,-.00525,0.0*
1,1,.006,-.04725,-.00525*
20,1,.006,-.04725,-.00525,-.0455,-.00992,0.0*
1,1,.006,-.0455,-.00992*
20,1,.006,-.0455,-.00992,-.04317,-.01342,0.0*
1,1,.006,-.04317,-.01342*
20,1,.006,-.04317,-.01342,-.03967,-.01633,0.0*
1,1,.006,-.03967,-.01633*
20,1,.006,-.03967,-.01633,-.035,-.0175,0.0*
1,1,.006,-.035,-.0175*
20,1,.006,-.035,-.0175,-.03033,-.01633,0.0*
1,1,.006,-.03033,-.01633*
20,1,.006,-.03033,-.01633,-.02683,-.01342,0.0*
1,1,.006,-.02683,-.01342*
20,1,.006,-.02683,-.01342,-.0245,-.00992,0.0*
1,1,.006,-.0245,-.00992*
20,1,.006,-.0245,-.00992,-.02275,-.00525,0.0*
1,1,.006,-.02275,-.00525*
20,1,.006,-.02275,-.00525,-.02217,0.0,0.0*
1,1,.006,-.02217,0.0*
20,1,.006,-.02217,0.0,-.02275,.00525,0.0*
1,1,.006,-.02275,.00525*
20,1,.006,-.02275,.00525,-.0245,.00992,0.0*
1,1,.006,-.0245,.00992*
20,1,.006,-.0245,.00992,-.02683,.01342,0.0*
1,1,.006,-.02683,.01342*
20,1,.006,-.02683,.01342,-.03033,.01633,0.0*
1,1,.006,-.03033,.01633*
20,1,.006,-.03033,.01633,-.035,.0175,0.0*
1,1,.006,-.035,.0175*
1,1,.006,-.01282,-.0105*
20,1,.006,-.01282,-.0105,-.00932,-.01458,0.0*
1,1,.006,-.00932,-.01458*
20,1,.006,-.00932,-.01458,-.00466,-.01692,0.0*
1,1,.006,-.00466,-.01692*
20,1,.006,-.00466,-.01692,.00059,-.0175,0.0*
1,1,.006,.00059,-.0175*
20,1,.006,.00059,-.0175,.00526,-.01692,0.0*
1,1,.006,.00526,-.01692*
20,1,.006,.00526,-.01692,.00993,-.014,0.0*
1,1,.006,.00993,-.014*
20,1,.006,.00993,-.014,.01284,-.0105,0.0*
1,1,.006,.01284,-.0105*
20,1,.006,.01284,-.0105,.01343,-.007,0.0*
1,1,.006,.01343,-.007*
20,1,.006,.01343,-.007,.01226,-.00292,0.0*
1,1,.006,.01226,-.00292*
20,1,.006,.01226,-.00292,.00818,0.0,0.0*
1,1,.006,.00818,0.0*
20,1,.006,.00818,0.0,.00409,.00117,0.0*
1,1,.006,.00409,.00117*
20,1,.006,.00409,.00117,-.00116,.00117,0.0*
1,1,.006,-.00116,.00117*
1,1,.006,.00409,.00117*
20,1,.006,.00409,.00117,.00759,.00292,0.0*
1,1,.006,.00759,.00292*
20,1,.006,.00759,.00292,.01051,.00583,0.0*
1,1,.006,.01051,.00583*
20,1,.006,.01051,.00583,.01168,.00933,0.0*
1,1,.006,.01168,.00933*
20,1,.006,.01168,.00933,.01051,.01283,0.0*
1,1,.006,.01051,.01283*
20,1,.006,.01051,.01283,.00759,.01575,0.0*
1,1,.006,.00759,.01575*
20,1,.006,.00759,.01575,.00234,.0175,0.0*
1,1,.006,.00234,.0175*
20,1,.006,.00234,.0175,-.00291,.01692,0.0*
1,1,.006,-.00291,.01692*
20,1,.006,-.00291,.01692,-.00816,.01458,0.0*
1,1,.006,-.00816,.01458*
1,1,.006,.02394,-.00292*
20,1,.006,.02394,-.00292,.02802,.00117,0.0*
1,1,.006,.02802,.00117*
20,1,.006,.02802,.00117,.03152,.0035,0.0*
1,1,.006,.03152,.0035*
20,1,.006,.03152,.0035,.03619,.00467,0.0*
1,1,.006,.03619,.00467*
20,1,.006,.03619,.00467,.04027,.0035,0.0*
1,1,.006,.04027,.0035*
20,1,.006,.04027,.0035,.04319,.00117,0.0*
1,1,.006,.04319,.00117*
20,1,.006,.04319,.00117,.04552,-.00233,0.0*
1,1,.006,.04552,-.00233*
20,1,.006,.04552,-.00233,.0461,-.00642,0.0*
1,1,.006,.0461,-.00642*
20,1,.006,.0461,-.00642,.04552,-.00992,0.0*
1,1,.006,.04552,-.00992*
20,1,.006,.04552,-.00992,.04319,-.01342,0.0*
1,1,.006,.04319,-.01342*
20,1,.006,.04319,-.01342,.03969,-.01633,0.0*
1,1,.006,.03969,-.01633*
20,1,.006,.03969,-.01633,.0356,-.0175,0.0*
1,1,.006,.0356,-.0175*
20,1,.006,.0356,-.0175,.03094,-.01633,0.0*
1,1,.006,.03094,-.01633*
20,1,.006,.03094,-.01633,.02685,-.01283,0.0*
1,1,.006,.02685,-.01283*
20,1,.006,.02685,-.01283,.02452,-.00758,0.0*
1,1,.006,.02452,-.00758*
20,1,.006,.02452,-.00758,.02394,-.00175,0.0*
1,1,.006,.02394,-.00175*
20,1,.006,.02394,-.00175,.0251,.00583,0.0*
1,1,.006,.0251,.00583*
20,1,.006,.0251,.00583,.02685,.00992,0.0*
1,1,.006,.02685,.00992*
20,1,.006,.02685,.00992,.02977,.014,0.0*
1,1,.006,.02977,.014*
20,1,.006,.02977,.014,.03385,.01692,0.0*
1,1,.006,.03385,.01692*
20,1,.006,.03385,.01692,.03794,.0175,0.0*
1,1,.006,.03794,.0175*
20,1,.006,.03794,.0175,.04202,.01633,0.0*
1,1,.006,.04202,.01633*
20,1,.006,.04202,.01633,.04494,.01342,0.0*
1,1,.006,.04494,.01342*
%
%ADD35MACRO35*%
%AMMACRO19*
1,1,.006,-.014,-.048*
20,1,.006,-.014,-.048,-.014,.048,0.0*
1,1,.006,-.014,.048*
20,1,.006,-.014,.048,-.013787,.050431,0.0*
1,1,.006,-.013787,.050431*
20,1,.006,-.013787,.050431,-.013156,.052788,0.0*
1,1,.006,-.013156,.052788*
20,1,.006,-.013156,.052788,-.012124,.055,0.0*
1,1,.006,-.012124,.055*
20,1,.006,-.012124,.055,-.010725,.056999,0.0*
1,1,.006,-.010725,.056999*
20,1,.006,-.010725,.056999,-.008999,.058725,0.0*
1,1,.006,-.008999,.058725*
20,1,.006,-.008999,.058725,-.007,.060124,0.0*
1,1,.006,-.007,.060124*
20,1,.006,-.007,.060124,-.004788,.061156,0.0*
1,1,.006,-.004788,.061156*
20,1,.006,-.004788,.061156,-.002431,.061787,0.0*
1,1,.006,-.002431,.061787*
20,1,.006,-.002431,.061787,0.0,.062,0.0*
1,1,.006,0.0,.062*
20,1,.006,0.0,.062,.002431,.061787,0.0*
1,1,.006,.002431,.061787*
20,1,.006,.002431,.061787,.004788,.061156,0.0*
1,1,.006,.004788,.061156*
20,1,.006,.004788,.061156,.007,.060124,0.0*
1,1,.006,.007,.060124*
20,1,.006,.007,.060124,.008999,.058725,0.0*
1,1,.006,.008999,.058725*
20,1,.006,.008999,.058725,.010725,.056999,0.0*
1,1,.006,.010725,.056999*
20,1,.006,.010725,.056999,.012124,.055,0.0*
1,1,.006,.012124,.055*
20,1,.006,.012124,.055,.013156,.052788,0.0*
1,1,.006,.013156,.052788*
20,1,.006,.013156,.052788,.013787,.050431,0.0*
1,1,.006,.013787,.050431*
20,1,.006,.013787,.050431,.014,.048,0.0*
1,1,.006,.014,.048*
20,1,.006,.014,.048,.014,-.048,0.0*
1,1,.006,.014,-.048*
20,1,.006,.014,-.048,.013787,-.050431,0.0*
1,1,.006,.013787,-.050431*
20,1,.006,.013787,-.050431,.013156,-.052788,0.0*
1,1,.006,.013156,-.052788*
20,1,.006,.013156,-.052788,.012124,-.055,0.0*
1,1,.006,.012124,-.055*
20,1,.006,.012124,-.055,.010725,-.056999,0.0*
1,1,.006,.010725,-.056999*
20,1,.006,.010725,-.056999,.008999,-.058725,0.0*
1,1,.006,.008999,-.058725*
20,1,.006,.008999,-.058725,.007,-.060124,0.0*
1,1,.006,.007,-.060124*
20,1,.006,.007,-.060124,.004788,-.061156,0.0*
1,1,.006,.004788,-.061156*
20,1,.006,.004788,-.061156,.002431,-.061787,0.0*
1,1,.006,.002431,-.061787*
20,1,.006,.002431,-.061787,0.0,-.062,0.0*
1,1,.006,0.0,-.062*
20,1,.006,0.0,-.062,-.002431,-.061787,0.0*
1,1,.006,-.002431,-.061787*
20,1,.006,-.002431,-.061787,-.004788,-.061156,0.0*
1,1,.006,-.004788,-.061156*
20,1,.006,-.004788,-.061156,-.007,-.060124,0.0*
1,1,.006,-.007,-.060124*
20,1,.006,-.007,-.060124,-.008999,-.058725,0.0*
1,1,.006,-.008999,-.058725*
20,1,.006,-.008999,-.058725,-.010725,-.056999,0.0*
1,1,.006,-.010725,-.056999*
20,1,.006,-.010725,-.056999,-.012124,-.055,0.0*
1,1,.006,-.012124,-.055*
20,1,.006,-.012124,-.055,-.013156,-.052788,0.0*
1,1,.006,-.013156,-.052788*
20,1,.006,-.013156,-.052788,-.013787,-.050431,0.0*
1,1,.006,-.013787,-.050431*
20,1,.006,-.013787,-.050431,-.014,-.048,0.0*
1,1,.006,-.014,-.048*
1,1,.006,-.01727,-.007*
20,1,.006,-.01727,-.007,-.01727,.00233,0.0*
1,1,.006,-.01727,.00233*
1,1,.006,-.01727,.00047*
20,1,.006,-.01727,.00047,-.0161,.0014,0.0*
1,1,.006,-.0161,.0014*
20,1,.006,-.0161,.0014,-.01493,.0021,0.0*
1,1,.006,-.01493,.0021*
20,1,.006,-.01493,.0021,-.0133,.00233,0.0*
1,1,.006,-.0133,.00233*
20,1,.006,-.0133,.00233,-.01213,.0021,0.0*
1,1,.006,-.01213,.0021*
20,1,.006,-.01213,.0021,-.01073,.0014,0.0*
1,1,.006,-.01073,.0014*
1,1,.006,.00421,-.007*
20,1,.006,.00421,-.007,.00421,.00233,0.0*
1,1,.006,.00421,.00233*
1,1,.006,.00421,.0007*
20,1,.006,.00421,.0007,.00328,.00163,0.0*
1,1,.006,.00328,.00163*
20,1,.006,.00328,.00163,.00188,.0021,0.0*
1,1,.006,.00188,.0021*
20,1,.006,.00188,.0021,.00024,.00233,0.0*
1,1,.006,.00024,.00233*
20,1,.006,.00024,.00233,-.00139,.00187,0.0*
1,1,.006,-.00139,.00187*
20,1,.006,-.00139,.00187,-.00279,.00093,0.0*
1,1,.006,-.00279,.00093*
20,1,.006,-.00279,.00093,-.00372,-.00047,0.0*
1,1,.006,-.00372,-.00047*
20,1,.006,-.00372,-.00047,-.00419,-.00233,0.0*
1,1,.006,-.00419,-.00233*
20,1,.006,-.00419,-.00233,-.00372,-.0042,0.0*
1,1,.006,-.00372,-.0042*
20,1,.006,-.00372,-.0042,-.00279,-.0056,0.0*
1,1,.006,-.00279,-.0056*
20,1,.006,-.00279,-.0056,-.00139,-.00653,0.0*
1,1,.006,-.00139,-.00653*
20,1,.006,-.00139,-.00653,.00024,-.007,0.0*
1,1,.006,.00024,-.007*
20,1,.006,.00024,-.007,.00188,-.00677,0.0*
1,1,.006,.00188,-.00677*
20,1,.006,.00188,-.00677,.00328,-.00607,0.0*
1,1,.006,.00328,-.00607*
20,1,.006,.00328,-.00607,.00421,-.00513,0.0*
1,1,.006,.00421,-.00513*
1,1,.006,.01682,-.007*
20,1,.006,.01682,-.007,.01682,.007,0.0*
1,1,.006,.01682,.007*
20,1,.006,.01682,.007,.00819,-.00303,0.0*
1,1,.006,.00819,-.00303*
20,1,.006,.00819,-.00303,.01985,-.00303,0.0*
1,1,.006,.01985,-.00303*
%
%ADD19MACRO19*%
%AMMACRO39*
1,1,.006,.045,0.0*
20,1,.006,.045,0.0,0.0,-.045,0.0*
1,1,.006,0.0,-.045*
20,1,.006,0.0,-.045,-.045,0.0,0.0*
1,1,.006,-.045,0.0*
20,1,.006,-.045,0.0,0.0,.045,0.0*
1,1,.006,0.0,.045*
20,1,.006,0.0,.045,.045,0.0,0.0*
1,1,.006,.045,0.0*
1,1,.006,-.045,.0225*
20,1,.006,-.045,.0225,-.051,.021,0.0*
1,1,.006,-.051,.021*
20,1,.006,-.051,.021,-.0555,.01725,0.0*
1,1,.006,-.0555,.01725*
20,1,.006,-.0555,.01725,-.0585,.01275,0.0*
1,1,.006,-.0585,.01275*
20,1,.006,-.0585,.01275,-.06075,.00675,0.0*
1,1,.006,-.06075,.00675*
20,1,.006,-.06075,.00675,-.0615,0.0,0.0*
1,1,.006,-.0615,0.0*
20,1,.006,-.0615,0.0,-.06075,-.00675,0.0*
1,1,.006,-.06075,-.00675*
20,1,.006,-.06075,-.00675,-.0585,-.01275,0.0*
1,1,.006,-.0585,-.01275*
20,1,.006,-.0585,-.01275,-.0555,-.01725,0.0*
1,1,.006,-.0555,-.01725*
20,1,.006,-.0555,-.01725,-.051,-.021,0.0*
1,1,.006,-.051,-.021*
20,1,.006,-.051,-.021,-.045,-.0225,0.0*
1,1,.006,-.045,-.0225*
20,1,.006,-.045,-.0225,-.039,-.021,0.0*
1,1,.006,-.039,-.021*
20,1,.006,-.039,-.021,-.0345,-.01725,0.0*
1,1,.006,-.0345,-.01725*
20,1,.006,-.0345,-.01725,-.0315,-.01275,0.0*
1,1,.006,-.0315,-.01275*
20,1,.006,-.0315,-.01275,-.02925,-.00675,0.0*
1,1,.006,-.02925,-.00675*
20,1,.006,-.02925,-.00675,-.0285,0.0,0.0*
1,1,.006,-.0285,0.0*
20,1,.006,-.0285,0.0,-.02925,.00675,0.0*
1,1,.006,-.02925,.00675*
20,1,.006,-.02925,.00675,-.0315,.01275,0.0*
1,1,.006,-.0315,.01275*
20,1,.006,-.0315,.01275,-.0345,.01725,0.0*
1,1,.006,-.0345,.01725*
20,1,.006,-.0345,.01725,-.039,.021,0.0*
1,1,.006,-.039,.021*
20,1,.006,-.039,.021,-.045,.0225,0.0*
1,1,.006,-.045,.0225*
1,1,.006,-.01274,-.01725*
20,1,.006,-.01274,-.01725,-.00749,-.021,0.0*
1,1,.006,-.00749,-.021*
20,1,.006,-.00749,-.021,-.00149,-.0225,0.0*
1,1,.006,-.00149,-.0225*
20,1,.006,-.00149,-.0225,.00451,-.021,0.0*
1,1,.006,.00451,-.021*
20,1,.006,.00451,-.021,.00976,-.0165,0.0*
1,1,.006,.00976,-.0165*
20,1,.006,.00976,-.0165,.01351,-.00975,0.0*
1,1,.006,.01351,-.00975*
20,1,.006,.01351,-.00975,.01501,-.003,0.0*
1,1,.006,.01501,-.003*
20,1,.006,.01501,-.003,.01501,.00525,0.0*
1,1,.006,.01501,.00525*
20,1,.006,.01501,.00525,.01351,.012,0.0*
1,1,.006,.01351,.012*
20,1,.006,.01351,.012,.00976,.018,0.0*
1,1,.006,.00976,.018*
20,1,.006,.00976,.018,.00526,.021,0.0*
1,1,.006,.00526,.021*
20,1,.006,.00526,.021,.00001,.0225,0.0*
1,1,.006,.00001,.0225*
20,1,.006,.00001,.0225,-.00599,.021,0.0*
1,1,.006,-.00599,.021*
20,1,.006,-.00599,.021,-.01049,.018,0.0*
1,1,.006,-.01049,.018*
20,1,.006,-.01049,.018,-.01349,.0135,0.0*
1,1,.006,-.01349,.0135*
20,1,.006,-.01349,.0135,-.01499,.0075,0.0*
1,1,.006,-.01499,.0075*
20,1,.006,-.01499,.0075,-.01349,.00225,0.0*
1,1,.006,-.01349,.00225*
20,1,.006,-.01349,.00225,-.00974,-.003,0.0*
1,1,.006,-.00974,-.003*
20,1,.006,-.00974,-.003,-.00524,-.006,0.0*
1,1,.006,-.00524,-.006*
20,1,.006,-.00524,-.006,.00001,-.00675,0.0*
1,1,.006,.00001,-.00675*
20,1,.006,.00001,-.00675,.00601,-.00525,0.0*
1,1,.006,.00601,-.00525*
20,1,.006,.00601,-.00525,.01051,-.0015,0.0*
1,1,.006,.01051,-.0015*
20,1,.006,.01051,-.0015,.01501,.00525,0.0*
1,1,.006,.01501,.00525*
1,1,.006,.04502,.0225*
20,1,.006,.04502,.0225,.03902,.021,0.0*
1,1,.006,.03902,.021*
20,1,.006,.03902,.021,.03452,.01725,0.0*
1,1,.006,.03452,.01725*
20,1,.006,.03452,.01725,.03152,.01275,0.0*
1,1,.006,.03152,.01275*
20,1,.006,.03152,.01275,.02927,.00675,0.0*
1,1,.006,.02927,.00675*
20,1,.006,.02927,.00675,.02852,0.0,0.0*
1,1,.006,.02852,0.0*
20,1,.006,.02852,0.0,.02927,-.00675,0.0*
1,1,.006,.02927,-.00675*
20,1,.006,.02927,-.00675,.03152,-.01275,0.0*
1,1,.006,.03152,-.01275*
20,1,.006,.03152,-.01275,.03452,-.01725,0.0*
1,1,.006,.03452,-.01725*
20,1,.006,.03452,-.01725,.03902,-.021,0.0*
1,1,.006,.03902,-.021*
20,1,.006,.03902,-.021,.04502,-.0225,0.0*
1,1,.006,.04502,-.0225*
20,1,.006,.04502,-.0225,.05102,-.021,0.0*
1,1,.006,.05102,-.021*
20,1,.006,.05102,-.021,.05552,-.01725,0.0*
1,1,.006,.05552,-.01725*
20,1,.006,.05552,-.01725,.05852,-.01275,0.0*
1,1,.006,.05852,-.01275*
20,1,.006,.05852,-.01275,.06077,-.00675,0.0*
1,1,.006,.06077,-.00675*
20,1,.006,.06077,-.00675,.06152,0.0,0.0*
1,1,.006,.06152,0.0*
20,1,.006,.06152,0.0,.06077,.00675,0.0*
1,1,.006,.06077,.00675*
20,1,.006,.06077,.00675,.05852,.01275,0.0*
1,1,.006,.05852,.01275*
20,1,.006,.05852,.01275,.05552,.01725,0.0*
1,1,.006,.05552,.01725*
20,1,.006,.05552,.01725,.05102,.021,0.0*
1,1,.006,.05102,.021*
20,1,.006,.05102,.021,.04502,.0225,0.0*
1,1,.006,.04502,.0225*
%
%ADD39MACRO39*%
%AMMACRO10*
1,1,.006,.035,0.0*
20,1,.006,.035,0.0,.034468,-.006078,0.0*
1,1,.006,.034468,-.006078*
20,1,.006,.034468,-.006078,.032889,-.011971,0.0*
1,1,.006,.032889,-.011971*
20,1,.006,.032889,-.011971,.030311,-.0175,0.0*
1,1,.006,.030311,-.0175*
20,1,.006,.030311,-.0175,.026812,-.022498,0.0*
1,1,.006,.026812,-.022498*
20,1,.006,.026812,-.022498,.022498,-.026812,0.0*
1,1,.006,.022498,-.026812*
20,1,.006,.022498,-.026812,.0175,-.030311,0.0*
1,1,.006,.0175,-.030311*
20,1,.006,.0175,-.030311,.011971,-.032889,0.0*
1,1,.006,.011971,-.032889*
20,1,.006,.011971,-.032889,.006078,-.034468,0.0*
1,1,.006,.006078,-.034468*
20,1,.006,.006078,-.034468,0.0,-.035,0.0*
1,1,.006,0.0,-.035*
20,1,.006,0.0,-.035,-.006078,-.034468,0.0*
1,1,.006,-.006078,-.034468*
20,1,.006,-.006078,-.034468,-.011971,-.032889,0.0*
1,1,.006,-.011971,-.032889*
20,1,.006,-.011971,-.032889,-.0175,-.030311,0.0*
1,1,.006,-.0175,-.030311*
20,1,.006,-.0175,-.030311,-.022498,-.026812,0.0*
1,1,.006,-.022498,-.026812*
20,1,.006,-.022498,-.026812,-.026812,-.022498,0.0*
1,1,.006,-.026812,-.022498*
20,1,.006,-.026812,-.022498,-.030311,-.0175,0.0*
1,1,.006,-.030311,-.0175*
20,1,.006,-.030311,-.0175,-.032889,-.011971,0.0*
1,1,.006,-.032889,-.011971*
20,1,.006,-.032889,-.011971,-.034468,-.006078,0.0*
1,1,.006,-.034468,-.006078*
20,1,.006,-.034468,-.006078,-.035,0.0,0.0*
1,1,.006,-.035,0.0*
20,1,.006,-.035,0.0,-.034468,.006078,0.0*
1,1,.006,-.034468,.006078*
20,1,.006,-.034468,.006078,-.032889,.011971,0.0*
1,1,.006,-.032889,.011971*
20,1,.006,-.032889,.011971,-.030311,.0175,0.0*
1,1,.006,-.030311,.0175*
20,1,.006,-.030311,.0175,-.026812,.022498,0.0*
1,1,.006,-.026812,.022498*
20,1,.006,-.026812,.022498,-.022498,.026812,0.0*
1,1,.006,-.022498,.026812*
20,1,.006,-.022498,.026812,-.0175,.030311,0.0*
1,1,.006,-.0175,.030311*
20,1,.006,-.0175,.030311,-.011971,.032889,0.0*
1,1,.006,-.011971,.032889*
20,1,.006,-.011971,.032889,-.006078,.034468,0.0*
1,1,.006,-.006078,.034468*
20,1,.006,-.006078,.034468,0.0,.035,0.0*
1,1,.006,0.0,.035*
20,1,.006,0.0,.035,.006078,.034468,0.0*
1,1,.006,.006078,.034468*
20,1,.006,.006078,.034468,.011971,.032889,0.0*
1,1,.006,.011971,.032889*
20,1,.006,.011971,.032889,.0175,.030311,0.0*
1,1,.006,.0175,.030311*
20,1,.006,.0175,.030311,.022498,.026812,0.0*
1,1,.006,.022498,.026812*
20,1,.006,.022498,.026812,.026812,.022498,0.0*
1,1,.006,.026812,.022498*
20,1,.006,.026812,.022498,.030311,.0175,0.0*
1,1,.006,.030311,.0175*
20,1,.006,.030311,.0175,.032889,.011971,0.0*
1,1,.006,.032889,.011971*
20,1,.006,.032889,.011971,.034468,.006078,0.0*
1,1,.006,.034468,.006078*
20,1,.006,.034468,.006078,.035,0.0,0.0*
1,1,.006,.035,0.0*
1,1,.006,-.0175,.0175*
20,1,.006,-.0175,.0175,-.0175,-.0175,0.0*
1,1,.006,-.0175,-.0175*
1,1,.006,-.03092,.0175*
20,1,.006,-.03092,.0175,-.00408,.0175,0.0*
1,1,.006,-.00408,.0175*
1,1,.006,.00584,-.0175*
20,1,.006,.00584,-.0175,.00584,.0175,0.0*
1,1,.006,.00584,.0175*
20,1,.006,.00584,.0175,.01984,.0175,0.0*
1,1,.006,.01984,.0175*
20,1,.006,.01984,.0175,.02451,.01575,0.0*
1,1,.006,.02451,.01575*
20,1,.006,.02451,.01575,.02801,.01167,0.0*
1,1,.006,.02801,.01167*
20,1,.006,.02801,.01167,.02918,.007,0.0*
1,1,.006,.02918,.007*
20,1,.006,.02918,.007,.02801,.00233,0.0*
1,1,.006,.02801,.00233*
20,1,.006,.02801,.00233,.02509,-.00117,0.0*
1,1,.006,.02509,-.00117*
20,1,.006,.02509,-.00117,.01984,-.00292,0.0*
1,1,.006,.01984,-.00292*
20,1,.006,.01984,-.00292,.00584,-.00292,0.0*
1,1,.006,.00584,-.00292*
%
%ADD10MACRO10*%
%AMMACRO13*
1,1,.006,.025,.025*
20,1,.006,.025,.025,.025,-.025,0.0*
1,1,.006,.025,-.025*
20,1,.006,.025,-.025,-.025,-.025,0.0*
1,1,.006,-.025,-.025*
20,1,.006,-.025,-.025,-.025,.025,0.0*
1,1,.006,-.025,.025*
20,1,.006,-.025,.025,.025,.025,0.0*
1,1,.006,.025,.025*
1,1,.006,-.00833,-.0125*
20,1,.006,-.00833,-.0125,-.00833,.0125,0.0*
1,1,.006,-.00833,.0125*
20,1,.006,-.00833,.0125,.00167,.0125,0.0*
1,1,.006,.00167,.0125*
20,1,.006,.00167,.0125,.005,.01125,0.0*
1,1,.006,.005,.01125*
20,1,.006,.005,.01125,.0075,.00833,0.0*
1,1,.006,.0075,.00833*
20,1,.006,.0075,.00833,.00833,.005,0.0*
1,1,.006,.00833,.005*
20,1,.006,.00833,.005,.0075,.00167,0.0*
1,1,.006,.0075,.00167*
20,1,.006,.0075,.00167,.00542,-.00083,0.0*
1,1,.006,.00542,-.00083*
20,1,.006,.00542,-.00083,.00167,-.00208,0.0*
1,1,.006,.00167,-.00208*
20,1,.006,.00167,-.00208,-.00833,-.00208,0.0*
1,1,.006,-.00833,-.00208*
%
%ADD13MACRO13*%
%AMMACRO12*
1,1,.006,.035,0.0*
20,1,.006,.035,0.0,.034468,-.006078,0.0*
1,1,.006,.034468,-.006078*
20,1,.006,.034468,-.006078,.032889,-.011971,0.0*
1,1,.006,.032889,-.011971*
20,1,.006,.032889,-.011971,.030311,-.0175,0.0*
1,1,.006,.030311,-.0175*
20,1,.006,.030311,-.0175,.026812,-.022498,0.0*
1,1,.006,.026812,-.022498*
20,1,.006,.026812,-.022498,.022498,-.026812,0.0*
1,1,.006,.022498,-.026812*
20,1,.006,.022498,-.026812,.0175,-.030311,0.0*
1,1,.006,.0175,-.030311*
20,1,.006,.0175,-.030311,.011971,-.032889,0.0*
1,1,.006,.011971,-.032889*
20,1,.006,.011971,-.032889,.006078,-.034468,0.0*
1,1,.006,.006078,-.034468*
20,1,.006,.006078,-.034468,0.0,-.035,0.0*
1,1,.006,0.0,-.035*
20,1,.006,0.0,-.035,-.006078,-.034468,0.0*
1,1,.006,-.006078,-.034468*
20,1,.006,-.006078,-.034468,-.011971,-.032889,0.0*
1,1,.006,-.011971,-.032889*
20,1,.006,-.011971,-.032889,-.0175,-.030311,0.0*
1,1,.006,-.0175,-.030311*
20,1,.006,-.0175,-.030311,-.022498,-.026812,0.0*
1,1,.006,-.022498,-.026812*
20,1,.006,-.022498,-.026812,-.026812,-.022498,0.0*
1,1,.006,-.026812,-.022498*
20,1,.006,-.026812,-.022498,-.030311,-.0175,0.0*
1,1,.006,-.030311,-.0175*
20,1,.006,-.030311,-.0175,-.032889,-.011971,0.0*
1,1,.006,-.032889,-.011971*
20,1,.006,-.032889,-.011971,-.034468,-.006078,0.0*
1,1,.006,-.034468,-.006078*
20,1,.006,-.034468,-.006078,-.035,0.0,0.0*
1,1,.006,-.035,0.0*
20,1,.006,-.035,0.0,-.034468,.006078,0.0*
1,1,.006,-.034468,.006078*
20,1,.006,-.034468,.006078,-.032889,.011971,0.0*
1,1,.006,-.032889,.011971*
20,1,.006,-.032889,.011971,-.030311,.0175,0.0*
1,1,.006,-.030311,.0175*
20,1,.006,-.030311,.0175,-.026812,.022498,0.0*
1,1,.006,-.026812,.022498*
20,1,.006,-.026812,.022498,-.022498,.026812,0.0*
1,1,.006,-.022498,.026812*
20,1,.006,-.022498,.026812,-.0175,.030311,0.0*
1,1,.006,-.0175,.030311*
20,1,.006,-.0175,.030311,-.011971,.032889,0.0*
1,1,.006,-.011971,.032889*
20,1,.006,-.011971,.032889,-.006078,.034468,0.0*
1,1,.006,-.006078,.034468*
20,1,.006,-.006078,.034468,0.0,.035,0.0*
1,1,.006,0.0,.035*
20,1,.006,0.0,.035,.006078,.034468,0.0*
1,1,.006,.006078,.034468*
20,1,.006,.006078,.034468,.011971,.032889,0.0*
1,1,.006,.011971,.032889*
20,1,.006,.011971,.032889,.0175,.030311,0.0*
1,1,.006,.0175,.030311*
20,1,.006,.0175,.030311,.022498,.026812,0.0*
1,1,.006,.022498,.026812*
20,1,.006,.022498,.026812,.026812,.022498,0.0*
1,1,.006,.026812,.022498*
20,1,.006,.026812,.022498,.030311,.0175,0.0*
1,1,.006,.030311,.0175*
20,1,.006,.030311,.0175,.032889,.011971,0.0*
1,1,.006,.032889,.011971*
20,1,.006,.032889,.011971,.034468,.006078,0.0*
1,1,.006,.034468,.006078*
20,1,.006,.034468,.006078,.035,0.0,0.0*
1,1,.006,.035,0.0*
1,1,.006,-.04958,.0175*
20,1,.006,-.04958,.0175,-.035,-.0175,0.0*
1,1,.006,-.035,-.0175*
20,1,.006,-.035,-.0175,-.02042,.0175,0.0*
1,1,.006,-.02042,.0175*
1,1,.006,.00001,-.0175*
20,1,.006,.00001,-.0175,.00001,.0175,0.0*
1,1,.006,.00001,.0175*
20,1,.006,.00001,.0175,-.00699,.0105,0.0*
1,1,.006,-.00699,.0105*
1,1,.006,-.00699,-.0175*
20,1,.006,-.00699,-.0175,.00701,-.0175,0.0*
1,1,.006,.00701,-.0175*
1,1,.006,.03502,.0175*
20,1,.006,.03502,.0175,.03035,.01633,0.0*
1,1,.006,.03035,.01633*
20,1,.006,.03035,.01633,.02685,.01342,0.0*
1,1,.006,.02685,.01342*
20,1,.006,.02685,.01342,.02452,.00992,0.0*
1,1,.006,.02452,.00992*
20,1,.006,.02452,.00992,.02277,.00525,0.0*
1,1,.006,.02277,.00525*
20,1,.006,.02277,.00525,.02219,0.0,0.0*
1,1,.006,.02219,0.0*
20,1,.006,.02219,0.0,.02277,-.00525,0.0*
1,1,.006,.02277,-.00525*
20,1,.006,.02277,-.00525,.02452,-.00992,0.0*
1,1,.006,.02452,-.00992*
20,1,.006,.02452,-.00992,.02685,-.01342,0.0*
1,1,.006,.02685,-.01342*
20,1,.006,.02685,-.01342,.03035,-.01633,0.0*
1,1,.006,.03035,-.01633*
20,1,.006,.03035,-.01633,.03502,-.0175,0.0*
1,1,.006,.03502,-.0175*
20,1,.006,.03502,-.0175,.03969,-.01633,0.0*
1,1,.006,.03969,-.01633*
20,1,.006,.03969,-.01633,.04319,-.01342,0.0*
1,1,.006,.04319,-.01342*
20,1,.006,.04319,-.01342,.04552,-.00992,0.0*
1,1,.006,.04552,-.00992*
20,1,.006,.04552,-.00992,.04727,-.00525,0.0*
1,1,.006,.04727,-.00525*
20,1,.006,.04727,-.00525,.04785,0.0,0.0*
1,1,.006,.04785,0.0*
20,1,.006,.04785,0.0,.04727,.00525,0.0*
1,1,.006,.04727,.00525*
20,1,.006,.04727,.00525,.04552,.00992,0.0*
1,1,.006,.04552,.00992*
20,1,.006,.04552,.00992,.04319,.01342,0.0*
1,1,.006,.04319,.01342*
20,1,.006,.04319,.01342,.03969,.01633,0.0*
1,1,.006,.03969,.01633*
20,1,.006,.03969,.01633,.03502,.0175,0.0*
1,1,.006,.03502,.0175*
%
%ADD12MACRO12*%
%AMMACRO38*
1,1,.006,.075,0.0*
20,1,.006,.075,0.0,.0375,.064952,0.0*
1,1,.006,.0375,.064952*
20,1,.006,.0375,.064952,-.0375,.064952,0.0*
1,1,.006,-.0375,.064952*
20,1,.006,-.0375,.064952,-.075,0.0,0.0*
1,1,.006,-.075,0.0*
20,1,.006,-.075,0.0,-.0375,-.064952,0.0*
1,1,.006,-.0375,-.064952*
20,1,.006,-.0375,-.064952,.0375,-.064952,0.0*
1,1,.006,.0375,-.064952*
20,1,.006,.0375,-.064952,.075,0.0,0.0*
1,1,.006,.075,0.0*
1,1,.006,-.0525,-.0625*
20,1,.006,-.0525,-.0625,-.0525,.0125,0.0*
1,1,.006,-.0525,.0125*
1,1,.006,-.0525,.00125*
20,1,.006,-.0525,.00125,-.05875,.0075,0.0*
1,1,.006,-.05875,.0075*
20,1,.006,-.05875,.0075,-.06625,.01125,0.0*
1,1,.006,-.06625,.01125*
20,1,.006,-.06625,.01125,-.075,.0125,0.0*
1,1,.006,-.075,.0125*
20,1,.006,-.075,.0125,-.0825,.01125,0.0*
1,1,.006,-.0825,.01125*
20,1,.006,-.0825,.01125,-.09125,.005,0.0*
1,1,.006,-.09125,.005*
20,1,.006,-.09125,.005,-.09625,-.00375,0.0*
1,1,.006,-.09625,-.00375*
20,1,.006,-.09625,-.00375,-.0975,-.0125,0.0*
1,1,.006,-.0975,-.0125*
20,1,.006,-.0975,-.0125,-.09625,-.02125,0.0*
1,1,.006,-.09625,-.02125*
20,1,.006,-.09625,-.02125,-.09125,-.03,0.0*
1,1,.006,-.09125,-.03*
20,1,.006,-.09125,-.03,-.0825,-.03625,0.0*
1,1,.006,-.0825,-.03625*
20,1,.006,-.0825,-.03625,-.075,-.0375,0.0*
1,1,.006,-.075,-.0375*
20,1,.006,-.075,-.0375,-.06625,-.03625,0.0*
1,1,.006,-.06625,-.03625*
20,1,.006,-.06625,-.03625,-.05875,-.0325,0.0*
1,1,.006,-.05875,-.0325*
20,1,.006,-.05875,-.0325,-.0525,-.02625,0.0*
1,1,.006,-.0525,-.02625*
1,1,.006,.00001,.0375*
20,1,.006,.00001,.0375,.00001,-.0375,0.0*
1,1,.006,.00001,-.0375*
1,1,.006,-.01749,.0125*
20,1,.006,-.01749,.0125,.01751,.0125,0.0*
1,1,.006,.01751,.0125*
1,1,.006,.05252,-.0625*
20,1,.006,.05252,-.0625,.05252,.0125,0.0*
1,1,.006,.05252,.0125*
1,1,.006,.05252,.00125*
20,1,.006,.05252,.00125,.05877,.0075,0.0*
1,1,.006,.05877,.0075*
20,1,.006,.05877,.0075,.06502,.01125,0.0*
1,1,.006,.06502,.01125*
20,1,.006,.06502,.01125,.07502,.0125,0.0*
1,1,.006,.07502,.0125*
20,1,.006,.07502,.0125,.08377,.01125,0.0*
1,1,.006,.08377,.01125*
20,1,.006,.08377,.01125,.09252,.005,0.0*
1,1,.006,.09252,.005*
20,1,.006,.09252,.005,.09627,-.00375,0.0*
1,1,.006,.09627,-.00375*
20,1,.006,.09627,-.00375,.09752,-.0125,0.0*
1,1,.006,.09752,-.0125*
20,1,.006,.09752,-.0125,.09627,-.02125,0.0*
1,1,.006,.09627,-.02125*
20,1,.006,.09627,-.02125,.09252,-.03,0.0*
1,1,.006,.09252,-.03*
20,1,.006,.09252,-.03,.08502,-.035,0.0*
1,1,.006,.08502,-.035*
20,1,.006,.08502,-.035,.07502,-.0375,0.0*
1,1,.006,.07502,-.0375*
20,1,.006,.07502,-.0375,.06627,-.03625,0.0*
1,1,.006,.06627,-.03625*
20,1,.006,.06627,-.03625,.05752,-.0325,0.0*
1,1,.006,.05752,-.0325*
20,1,.006,.05752,-.0325,.05252,-.0275,0.0*
1,1,.006,.05252,-.0275*
%
%ADD38MACRO38*%
%AMMACRO22*
1,1,.006,.071,0.0*
20,1,.006,.071,0.0,.0355,.061488,0.0*
1,1,.006,.0355,.061488*
20,1,.006,.0355,.061488,-.0355,.061488,0.0*
1,1,.006,-.0355,.061488*
20,1,.006,-.0355,.061488,-.071,0.0,0.0*
1,1,.006,-.071,0.0*
20,1,.006,-.071,0.0,-.0355,-.061488,0.0*
1,1,.006,-.0355,-.061488*
20,1,.006,-.0355,-.061488,.0355,-.061488,0.0*
1,1,.006,.0355,-.061488*
20,1,.006,.0355,-.061488,.071,0.0,0.0*
1,1,.006,.071,0.0*
1,1,.006,-.0497,-.05917*
20,1,.006,-.0497,-.05917,-.0497,.01183,0.0*
1,1,.006,-.0497,.01183*
1,1,.006,-.0497,.00118*
20,1,.006,-.0497,.00118,-.05562,.0071,0.0*
1,1,.006,-.05562,.0071*
20,1,.006,-.05562,.0071,-.06272,.01065,0.0*
1,1,.006,-.06272,.01065*
20,1,.006,-.06272,.01065,-.071,.01183,0.0*
1,1,.006,-.071,.01183*
20,1,.006,-.071,.01183,-.0781,.01065,0.0*
1,1,.006,-.0781,.01065*
20,1,.006,-.0781,.01065,-.08638,.00473,0.0*
1,1,.006,-.08638,.00473*
20,1,.006,-.08638,.00473,-.09112,-.00355,0.0*
1,1,.006,-.09112,-.00355*
20,1,.006,-.09112,-.00355,-.0923,-.01183,0.0*
1,1,.006,-.0923,-.01183*
20,1,.006,-.0923,-.01183,-.09112,-.02012,0.0*
1,1,.006,-.09112,-.02012*
20,1,.006,-.09112,-.02012,-.08638,-.0284,0.0*
1,1,.006,-.08638,-.0284*
20,1,.006,-.08638,-.0284,-.0781,-.03432,0.0*
1,1,.006,-.0781,-.03432*
20,1,.006,-.0781,-.03432,-.071,-.0355,0.0*
1,1,.006,-.071,-.0355*
20,1,.006,-.071,-.0355,-.06272,-.03432,0.0*
1,1,.006,-.06272,-.03432*
20,1,.006,-.06272,-.03432,-.05562,-.03077,0.0*
1,1,.006,-.05562,-.03077*
20,1,.006,-.05562,-.03077,-.0497,-.02485,0.0*
1,1,.006,-.0497,-.02485*
1,1,.006,-.01656,-.0355*
20,1,.006,-.01656,-.0355,-.01656,.01183,0.0*
1,1,.006,-.01656,.01183*
1,1,.006,-.01656,.00237*
20,1,.006,-.01656,.00237,-.01064,.0071,0.0*
1,1,.006,-.01064,.0071*
20,1,.006,-.01064,.0071,-.00472,.01065,0.0*
1,1,.006,-.00472,.01065*
20,1,.006,-.00472,.01065,.00356,.01183,0.0*
1,1,.006,.00356,.01183*
20,1,.006,.00356,.01183,.00948,.01065,0.0*
1,1,.006,.00948,.01065*
20,1,.006,.00948,.01065,.01658,.0071,0.0*
1,1,.006,.01658,.0071*
1,1,.006,.04144,.01183*
20,1,.006,.04144,.01183,.05564,-.0355,0.0*
1,1,.006,.05564,-.0355*
20,1,.006,.05564,-.0355,.07102,.01183,0.0*
1,1,.006,.07102,.01183*
20,1,.006,.07102,.01183,.0864,-.0355,0.0*
1,1,.006,.0864,-.0355*
20,1,.006,.0864,-.0355,.1006,.01183,0.0*
1,1,.006,.1006,.01183*
%
%ADD22MACRO22*%
%AMMACRO20*
1,1,.006,0.0,.035*
20,1,.006,0.0,.035,.035,-.035,0.0*
1,1,.006,.035,-.035*
20,1,.006,.035,-.035,-.035,-.035,0.0*
1,1,.006,-.035,-.035*
20,1,.006,-.035,-.035,0.0,.035,0.0*
1,1,.006,0.0,.035*
1,1,.006,-.0455,-.02917*
20,1,.006,-.0455,-.02917,-.0455,.00583,0.0*
1,1,.006,-.0455,.00583*
1,1,.006,-.0455,.00058*
20,1,.006,-.0455,.00058,-.04258,.0035,0.0*
1,1,.006,-.04258,.0035*
20,1,.006,-.04258,.0035,-.03967,.00525,0.0*
1,1,.006,-.03967,.00525*
20,1,.006,-.03967,.00525,-.035,.00583,0.0*
1,1,.006,-.035,.00583*
20,1,.006,-.035,.00583,-.03092,.00525,0.0*
1,1,.006,-.03092,.00525*
20,1,.006,-.03092,.00525,-.02683,.00233,0.0*
1,1,.006,-.02683,.00233*
20,1,.006,-.02683,.00233,-.02508,-.00175,0.0*
1,1,.006,-.02508,-.00175*
20,1,.006,-.02508,-.00175,-.0245,-.00583,0.0*
1,1,.006,-.0245,-.00583*
20,1,.006,-.0245,-.00583,-.02508,-.00992,0.0*
1,1,.006,-.02508,-.00992*
20,1,.006,-.02508,-.00992,-.02683,-.014,0.0*
1,1,.006,-.02683,-.014*
20,1,.006,-.02683,-.014,-.03033,-.01633,0.0*
1,1,.006,-.03033,-.01633*
20,1,.006,-.03033,-.01633,-.035,-.0175,0.0*
1,1,.006,-.035,-.0175*
20,1,.006,-.035,-.0175,-.03908,-.01692,0.0*
1,1,.006,-.03908,-.01692*
20,1,.006,-.03908,-.01692,-.04317,-.01517,0.0*
1,1,.006,-.04317,-.01517*
20,1,.006,-.04317,-.01517,-.0455,-.01283,0.0*
1,1,.006,-.0455,-.01283*
1,1,.006,.00001,.0175*
20,1,.006,.00001,.0175,.00001,-.0175,0.0*
1,1,.006,.00001,-.0175*
1,1,.006,-.00816,.00583*
20,1,.006,-.00816,.00583,.00818,.00583,0.0*
1,1,.006,.00818,.00583*
1,1,.006,.03502,-.0175*
20,1,.006,.03502,-.0175,.03152,-.01692,0.0*
1,1,.006,.03152,-.01692*
20,1,.006,.03152,-.01692,.02802,-.01458,0.0*
1,1,.006,.02802,-.01458*
20,1,.006,.02802,-.01458,.02569,-.0105,0.0*
1,1,.006,.02569,-.0105*
20,1,.006,.02569,-.0105,.02452,-.00583,0.0*
1,1,.006,.02452,-.00583*
20,1,.006,.02452,-.00583,.02569,-.00117,0.0*
1,1,.006,.02569,-.00117*
20,1,.006,.02569,-.00117,.02802,.00292,0.0*
1,1,.006,.02802,.00292*
20,1,.006,.02802,.00292,.03152,.00525,0.0*
1,1,.006,.03152,.00525*
20,1,.006,.03152,.00525,.03502,.00583,0.0*
1,1,.006,.03502,.00583*
20,1,.006,.03502,.00583,.03852,.00525,0.0*
1,1,.006,.03852,.00525*
20,1,.006,.03852,.00525,.04202,.00292,0.0*
1,1,.006,.04202,.00292*
20,1,.006,.04202,.00292,.04435,-.00117,0.0*
1,1,.006,.04435,-.00117*
20,1,.006,.04435,-.00117,.04494,-.00583,0.0*
1,1,.006,.04494,-.00583*
20,1,.006,.04494,-.00583,.04435,-.0105,0.0*
1,1,.006,.04435,-.0105*
20,1,.006,.04435,-.0105,.04202,-.01458,0.0*
1,1,.006,.04202,-.01458*
20,1,.006,.04202,-.01458,.03852,-.01692,0.0*
1,1,.006,.03852,-.01692*
20,1,.006,.03852,-.01692,.03502,-.0175,0.0*
1,1,.006,.03502,-.0175*
%
%ADD20MACRO20*%
%AMMACRO29*
1,1,.006,.079,0.0*
20,1,.006,.079,0.0,.0395,.068416,0.0*
1,1,.006,.0395,.068416*
20,1,.006,.0395,.068416,-.0395,.068416,0.0*
1,1,.006,-.0395,.068416*
20,1,.006,-.0395,.068416,-.079,0.0,0.0*
1,1,.006,-.079,0.0*
20,1,.006,-.079,0.0,-.0395,-.068416,0.0*
1,1,.006,-.0395,-.068416*
20,1,.006,-.0395,-.068416,.0395,-.068416,0.0*
1,1,.006,.0395,-.068416*
20,1,.006,.0395,-.068416,.079,0.0,0.0*
1,1,.006,.079,0.0*
1,1,.006,-.0553,-.06583*
20,1,.006,-.0553,-.06583,-.0553,.01317,0.0*
1,1,.006,-.0553,.01317*
1,1,.006,-.0553,.00132*
20,1,.006,-.0553,.00132,-.06188,.0079,0.0*
1,1,.006,-.06188,.0079*
20,1,.006,-.06188,.0079,-.06978,.01185,0.0*
1,1,.006,-.06978,.01185*
20,1,.006,-.06978,.01185,-.079,.01317,0.0*
1,1,.006,-.079,.01317*
20,1,.006,-.079,.01317,-.0869,.01185,0.0*
1,1,.006,-.0869,.01185*
20,1,.006,-.0869,.01185,-.09612,.00527,0.0*
1,1,.006,-.09612,.00527*
20,1,.006,-.09612,.00527,-.10138,-.00395,0.0*
1,1,.006,-.10138,-.00395*
20,1,.006,-.10138,-.00395,-.1027,-.01317,0.0*
1,1,.006,-.1027,-.01317*
20,1,.006,-.1027,-.01317,-.10138,-.02238,0.0*
1,1,.006,-.10138,-.02238*
20,1,.006,-.10138,-.02238,-.09612,-.0316,0.0*
1,1,.006,-.09612,-.0316*
20,1,.006,-.09612,-.0316,-.0869,-.03818,0.0*
1,1,.006,-.0869,-.03818*
20,1,.006,-.0869,-.03818,-.079,-.0395,0.0*
1,1,.006,-.079,-.0395*
20,1,.006,-.079,-.0395,-.06978,-.03818,0.0*
1,1,.006,-.06978,-.03818*
20,1,.006,-.06978,-.03818,-.06188,-.03423,0.0*
1,1,.006,-.06188,-.03423*
20,1,.006,-.06188,-.03423,-.0553,-.02765,0.0*
1,1,.006,-.0553,-.02765*
1,1,.006,.00001,.0395*
20,1,.006,.00001,.0395,.00001,-.0395,0.0*
1,1,.006,.00001,-.0395*
1,1,.006,-.01842,.01317*
20,1,.006,-.01842,.01317,.01844,.01317,0.0*
1,1,.006,.01844,.01317*
1,1,.006,.07902,.01317*
20,1,.006,.07902,.01317,.07902,-.0395,0.0*
1,1,.006,.07902,-.0395*
1,1,.006,.07902,.03423*
20,1,.006,.07902,.03423,.07639,.03555,0.0*
1,1,.006,.07639,.03555*
20,1,.006,.07639,.03555,.07639,.03818,0.0*
1,1,.006,.07639,.03818*
20,1,.006,.07639,.03818,.07902,.0395,0.0*
1,1,.006,.07902,.0395*
20,1,.006,.07902,.0395,.08165,.03818,0.0*
1,1,.006,.08165,.03818*
20,1,.006,.08165,.03818,.08165,.03555,0.0*
1,1,.006,.08165,.03555*
20,1,.006,.08165,.03555,.07902,.03423,0.0*
1,1,.006,.07902,.03423*
%
%ADD29MACRO29*%
%AMMACRO11*
1,1,.006,0.0,.035*
20,1,.006,0.0,.035,.035,-.035,0.0*
1,1,.006,.035,-.035*
20,1,.006,.035,-.035,-.035,-.035,0.0*
1,1,.006,-.035,-.035*
20,1,.006,-.035,-.035,0.0,.035,0.0*
1,1,.006,0.0,.035*
1,1,.006,-.0455,-.02917*
20,1,.006,-.0455,-.02917,-.0455,.00583,0.0*
1,1,.006,-.0455,.00583*
1,1,.006,-.0455,.00058*
20,1,.006,-.0455,.00058,-.04258,.0035,0.0*
1,1,.006,-.04258,.0035*
20,1,.006,-.04258,.0035,-.03967,.00525,0.0*
1,1,.006,-.03967,.00525*
20,1,.006,-.03967,.00525,-.035,.00583,0.0*
1,1,.006,-.035,.00583*
20,1,.006,-.035,.00583,-.03092,.00525,0.0*
1,1,.006,-.03092,.00525*
20,1,.006,-.03092,.00525,-.02683,.00233,0.0*
1,1,.006,-.02683,.00233*
20,1,.006,-.02683,.00233,-.02508,-.00175,0.0*
1,1,.006,-.02508,-.00175*
20,1,.006,-.02508,-.00175,-.0245,-.00583,0.0*
1,1,.006,-.0245,-.00583*
20,1,.006,-.0245,-.00583,-.02508,-.00992,0.0*
1,1,.006,-.02508,-.00992*
20,1,.006,-.02508,-.00992,-.02683,-.014,0.0*
1,1,.006,-.02683,-.014*
20,1,.006,-.02683,-.014,-.03033,-.01633,0.0*
1,1,.006,-.03033,-.01633*
20,1,.006,-.03033,-.01633,-.035,-.0175,0.0*
1,1,.006,-.035,-.0175*
20,1,.006,-.035,-.0175,-.03908,-.01692,0.0*
1,1,.006,-.03908,-.01692*
20,1,.006,-.03908,-.01692,-.04317,-.01517,0.0*
1,1,.006,-.04317,-.01517*
20,1,.006,-.04317,-.01517,-.0455,-.01283,0.0*
1,1,.006,-.0455,-.01283*
1,1,.006,.00001,.0175*
20,1,.006,.00001,.0175,.00001,-.0175,0.0*
1,1,.006,.00001,-.0175*
1,1,.006,-.00816,.00583*
20,1,.006,-.00816,.00583,.00818,.00583,0.0*
1,1,.006,.00818,.00583*
1,1,.006,.02452,-.02917*
20,1,.006,.02452,-.02917,.02452,.00583,0.0*
1,1,.006,.02452,.00583*
1,1,.006,.02452,.00058*
20,1,.006,.02452,.00058,.02744,.0035,0.0*
1,1,.006,.02744,.0035*
20,1,.006,.02744,.0035,.03035,.00525,0.0*
1,1,.006,.03035,.00525*
20,1,.006,.03035,.00525,.03502,.00583,0.0*
1,1,.006,.03502,.00583*
20,1,.006,.03502,.00583,.0391,.00525,0.0*
1,1,.006,.0391,.00525*
20,1,.006,.0391,.00525,.04319,.00233,0.0*
1,1,.006,.04319,.00233*
20,1,.006,.04319,.00233,.04494,-.00175,0.0*
1,1,.006,.04494,-.00175*
20,1,.006,.04494,-.00175,.04552,-.00583,0.0*
1,1,.006,.04552,-.00583*
20,1,.006,.04552,-.00583,.04494,-.00992,0.0*
1,1,.006,.04494,-.00992*
20,1,.006,.04494,-.00992,.04319,-.014,0.0*
1,1,.006,.04319,-.014*
20,1,.006,.04319,-.014,.03969,-.01633,0.0*
1,1,.006,.03969,-.01633*
20,1,.006,.03969,-.01633,.03502,-.0175,0.0*
1,1,.006,.03502,-.0175*
20,1,.006,.03502,-.0175,.03094,-.01692,0.0*
1,1,.006,.03094,-.01692*
20,1,.006,.03094,-.01692,.02685,-.01517,0.0*
1,1,.006,.02685,-.01517*
20,1,.006,.02685,-.01517,.02452,-.01283,0.0*
1,1,.006,.02452,-.01283*
%
%ADD11MACRO11*%
%AMMACRO30*
1,1,.006,0.0,.035*
20,1,.006,0.0,.035,.035,-.035,0.0*
1,1,.006,.035,-.035*
20,1,.006,.035,-.035,-.035,-.035,0.0*
1,1,.006,-.035,-.035*
20,1,.006,-.035,-.035,0.0,.035,0.0*
1,1,.006,0.0,.035*
1,1,.006,-.0455,-.02917*
20,1,.006,-.0455,-.02917,-.0455,.00583,0.0*
1,1,.006,-.0455,.00583*
1,1,.006,-.0455,.00058*
20,1,.006,-.0455,.00058,-.04258,.0035,0.0*
1,1,.006,-.04258,.0035*
20,1,.006,-.04258,.0035,-.03967,.00525,0.0*
1,1,.006,-.03967,.00525*
20,1,.006,-.03967,.00525,-.035,.00583,0.0*
1,1,.006,-.035,.00583*
20,1,.006,-.035,.00583,-.03092,.00525,0.0*
1,1,.006,-.03092,.00525*
20,1,.006,-.03092,.00525,-.02683,.00233,0.0*
1,1,.006,-.02683,.00233*
20,1,.006,-.02683,.00233,-.02508,-.00175,0.0*
1,1,.006,-.02508,-.00175*
20,1,.006,-.02508,-.00175,-.0245,-.00583,0.0*
1,1,.006,-.0245,-.00583*
20,1,.006,-.0245,-.00583,-.02508,-.00992,0.0*
1,1,.006,-.02508,-.00992*
20,1,.006,-.02508,-.00992,-.02683,-.014,0.0*
1,1,.006,-.02683,-.014*
20,1,.006,-.02683,-.014,-.03033,-.01633,0.0*
1,1,.006,-.03033,-.01633*
20,1,.006,-.03033,-.01633,-.035,-.0175,0.0*
1,1,.006,-.035,-.0175*
20,1,.006,-.035,-.0175,-.03908,-.01692,0.0*
1,1,.006,-.03908,-.01692*
20,1,.006,-.03908,-.01692,-.04317,-.01517,0.0*
1,1,.006,-.04317,-.01517*
20,1,.006,-.04317,-.01517,-.0455,-.01283,0.0*
1,1,.006,-.0455,-.01283*
1,1,.006,-.00816,-.0175*
20,1,.006,-.00816,-.0175,-.00816,.00583,0.0*
1,1,.006,-.00816,.00583*
1,1,.006,-.00816,.00117*
20,1,.006,-.00816,.00117,-.00524,.0035,0.0*
1,1,.006,-.00524,.0035*
20,1,.006,-.00524,.0035,-.00232,.00525,0.0*
1,1,.006,-.00232,.00525*
20,1,.006,-.00232,.00525,.00176,.00583,0.0*
1,1,.006,.00176,.00583*
20,1,.006,.00176,.00583,.00468,.00525,0.0*
1,1,.006,.00468,.00525*
20,1,.006,.00468,.00525,.00818,.0035,0.0*
1,1,.006,.00818,.0035*
1,1,.006,.0251,.00583*
20,1,.006,.0251,.00583,.0251,-.0105,0.0*
1,1,.006,.0251,-.0105*
20,1,.006,.0251,-.0105,.02744,-.01458,0.0*
1,1,.006,.02744,-.01458*
20,1,.006,.02744,-.01458,.03094,-.01692,0.0*
1,1,.006,.03094,-.01692*
20,1,.006,.03094,-.01692,.03502,-.0175,0.0*
1,1,.006,.03502,-.0175*
20,1,.006,.03502,-.0175,.0391,-.01692,0.0*
1,1,.006,.0391,-.01692*
20,1,.006,.0391,-.01692,.0426,-.01458,0.0*
1,1,.006,.0426,-.01458*
20,1,.006,.0426,-.01458,.04494,-.0105,0.0*
1,1,.006,.04494,-.0105*
1,1,.006,.04494,-.0175*
20,1,.006,.04494,-.0175,.04494,.00583,0.0*
1,1,.006,.04494,.00583*
%
%ADD30MACRO30*%
%AMMACRO26*
1,1,.006,0.0,.035*
20,1,.006,0.0,.035,.035,-.035,0.0*
1,1,.006,.035,-.035*
20,1,.006,.035,-.035,-.035,-.035,0.0*
1,1,.006,-.035,-.035*
20,1,.006,-.035,-.035,0.0,.035,0.0*
1,1,.006,0.0,.035*
1,1,.006,-.0455,-.02917*
20,1,.006,-.0455,-.02917,-.0455,.00583,0.0*
1,1,.006,-.0455,.00583*
1,1,.006,-.0455,.00058*
20,1,.006,-.0455,.00058,-.04258,.0035,0.0*
1,1,.006,-.04258,.0035*
20,1,.006,-.04258,.0035,-.03967,.00525,0.0*
1,1,.006,-.03967,.00525*
20,1,.006,-.03967,.00525,-.035,.00583,0.0*
1,1,.006,-.035,.00583*
20,1,.006,-.035,.00583,-.03092,.00525,0.0*
1,1,.006,-.03092,.00525*
20,1,.006,-.03092,.00525,-.02683,.00233,0.0*
1,1,.006,-.02683,.00233*
20,1,.006,-.02683,.00233,-.02508,-.00175,0.0*
1,1,.006,-.02508,-.00175*
20,1,.006,-.02508,-.00175,-.0245,-.00583,0.0*
1,1,.006,-.0245,-.00583*
20,1,.006,-.0245,-.00583,-.02508,-.00992,0.0*
1,1,.006,-.02508,-.00992*
20,1,.006,-.02508,-.00992,-.02683,-.014,0.0*
1,1,.006,-.02683,-.014*
20,1,.006,-.02683,-.014,-.03033,-.01633,0.0*
1,1,.006,-.03033,-.01633*
20,1,.006,-.03033,-.01633,-.035,-.0175,0.0*
1,1,.006,-.035,-.0175*
20,1,.006,-.035,-.0175,-.03908,-.01692,0.0*
1,1,.006,-.03908,-.01692*
20,1,.006,-.03908,-.01692,-.04317,-.01517,0.0*
1,1,.006,-.04317,-.01517*
20,1,.006,-.04317,-.01517,-.0455,-.01283,0.0*
1,1,.006,-.0455,-.01283*
1,1,.006,-.00816,-.0175*
20,1,.006,-.00816,-.0175,-.00816,.00583,0.0*
1,1,.006,-.00816,.00583*
1,1,.006,-.00816,.00117*
20,1,.006,-.00816,.00117,-.00524,.0035,0.0*
1,1,.006,-.00524,.0035*
20,1,.006,-.00524,.0035,-.00232,.00525,0.0*
1,1,.006,-.00232,.00525*
20,1,.006,-.00232,.00525,.00176,.00583,0.0*
1,1,.006,.00176,.00583*
20,1,.006,.00176,.00583,.00468,.00525,0.0*
1,1,.006,.00468,.00525*
20,1,.006,.00468,.00525,.00818,.0035,0.0*
1,1,.006,.00818,.0035*
1,1,.006,.02044,.00583*
20,1,.006,.02044,.00583,.02744,-.0175,0.0*
1,1,.006,.02744,-.0175*
20,1,.006,.02744,-.0175,.03502,.00583,0.0*
1,1,.006,.03502,.00583*
20,1,.006,.03502,.00583,.0426,-.0175,0.0*
1,1,.006,.0426,-.0175*
20,1,.006,.0426,-.0175,.0496,.00583,0.0*
1,1,.006,.0496,.00583*
%
%ADD26MACRO26*%
%AMMACRO28*
1,1,.006,0.0,.035*
20,1,.006,0.0,.035,.035,-.035,0.0*
1,1,.006,.035,-.035*
20,1,.006,.035,-.035,-.035,-.035,0.0*
1,1,.006,-.035,-.035*
20,1,.006,-.035,-.035,0.0,.035,0.0*
1,1,.006,0.0,.035*
1,1,.006,-.0455,-.02917*
20,1,.006,-.0455,-.02917,-.0455,.00583,0.0*
1,1,.006,-.0455,.00583*
1,1,.006,-.0455,.00058*
20,1,.006,-.0455,.00058,-.04258,.0035,0.0*
1,1,.006,-.04258,.0035*
20,1,.006,-.04258,.0035,-.03967,.00525,0.0*
1,1,.006,-.03967,.00525*
20,1,.006,-.03967,.00525,-.035,.00583,0.0*
1,1,.006,-.035,.00583*
20,1,.006,-.035,.00583,-.03092,.00525,0.0*
1,1,.006,-.03092,.00525*
20,1,.006,-.03092,.00525,-.02683,.00233,0.0*
1,1,.006,-.02683,.00233*
20,1,.006,-.02683,.00233,-.02508,-.00175,0.0*
1,1,.006,-.02508,-.00175*
20,1,.006,-.02508,-.00175,-.0245,-.00583,0.0*
1,1,.006,-.0245,-.00583*
20,1,.006,-.0245,-.00583,-.02508,-.00992,0.0*
1,1,.006,-.02508,-.00992*
20,1,.006,-.02508,-.00992,-.02683,-.014,0.0*
1,1,.006,-.02683,-.014*
20,1,.006,-.02683,-.014,-.03033,-.01633,0.0*
1,1,.006,-.03033,-.01633*
20,1,.006,-.03033,-.01633,-.035,-.0175,0.0*
1,1,.006,-.035,-.0175*
20,1,.006,-.035,-.0175,-.03908,-.01692,0.0*
1,1,.006,-.03908,-.01692*
20,1,.006,-.03908,-.01692,-.04317,-.01517,0.0*
1,1,.006,-.04317,-.01517*
20,1,.006,-.04317,-.01517,-.0455,-.01283,0.0*
1,1,.006,-.0455,-.01283*
1,1,.006,-.00816,-.0175*
20,1,.006,-.00816,-.0175,-.00816,.00583,0.0*
1,1,.006,-.00816,.00583*
1,1,.006,-.00816,.00117*
20,1,.006,-.00816,.00117,-.00524,.0035,0.0*
1,1,.006,-.00524,.0035*
20,1,.006,-.00524,.0035,-.00232,.00525,0.0*
1,1,.006,-.00232,.00525*
20,1,.006,-.00232,.00525,.00176,.00583,0.0*
1,1,.006,.00176,.00583*
20,1,.006,.00176,.00583,.00468,.00525,0.0*
1,1,.006,.00468,.00525*
20,1,.006,.00468,.00525,.00818,.0035,0.0*
1,1,.006,.00818,.0035*
1,1,.006,.02277,-.028*
20,1,.006,.02277,-.028,.02627,-.02917,0.0*
1,1,.006,.02627,-.02917*
20,1,.006,.02627,-.02917,.03094,-.028,0.0*
1,1,.006,.03094,-.028*
20,1,.006,.03094,-.028,.03385,-.02567,0.0*
1,1,.006,.03385,-.02567*
20,1,.006,.03385,-.02567,.03619,-.02275,0.0*
1,1,.006,.03619,-.02275*
20,1,.006,.03619,-.02275,.03969,-.01342,0.0*
1,1,.006,.03969,-.01342*
20,1,.006,.03969,-.01342,.04727,.00583,0.0*
1,1,.006,.04727,.00583*
1,1,.006,.0286,.00583*
20,1,.006,.0286,.00583,.03969,-.01342,0.0*
1,1,.006,.03969,-.01342*
%
%ADD28MACRO28*%
%AMMACRO24*
1,1,.006,0.0,.035*
20,1,.006,0.0,.035,.035,-.035,0.0*
1,1,.006,.035,-.035*
20,1,.006,.035,-.035,-.035,-.035,0.0*
1,1,.006,-.035,-.035*
20,1,.006,-.035,-.035,0.0,.035,0.0*
1,1,.006,0.0,.035*
1,1,.006,-.0455,-.02917*
20,1,.006,-.0455,-.02917,-.0455,.00583,0.0*
1,1,.006,-.0455,.00583*
1,1,.006,-.0455,.00058*
20,1,.006,-.0455,.00058,-.04258,.0035,0.0*
1,1,.006,-.04258,.0035*
20,1,.006,-.04258,.0035,-.03967,.00525,0.0*
1,1,.006,-.03967,.00525*
20,1,.006,-.03967,.00525,-.035,.00583,0.0*
1,1,.006,-.035,.00583*
20,1,.006,-.035,.00583,-.03092,.00525,0.0*
1,1,.006,-.03092,.00525*
20,1,.006,-.03092,.00525,-.02683,.00233,0.0*
1,1,.006,-.02683,.00233*
20,1,.006,-.02683,.00233,-.02508,-.00175,0.0*
1,1,.006,-.02508,-.00175*
20,1,.006,-.02508,-.00175,-.0245,-.00583,0.0*
1,1,.006,-.0245,-.00583*
20,1,.006,-.0245,-.00583,-.02508,-.00992,0.0*
1,1,.006,-.02508,-.00992*
20,1,.006,-.02508,-.00992,-.02683,-.014,0.0*
1,1,.006,-.02683,-.014*
20,1,.006,-.02683,-.014,-.03033,-.01633,0.0*
1,1,.006,-.03033,-.01633*
20,1,.006,-.03033,-.01633,-.035,-.0175,0.0*
1,1,.006,-.035,-.0175*
20,1,.006,-.035,-.0175,-.03908,-.01692,0.0*
1,1,.006,-.03908,-.01692*
20,1,.006,-.03908,-.01692,-.04317,-.01517,0.0*
1,1,.006,-.04317,-.01517*
20,1,.006,-.04317,-.01517,-.0455,-.01283,0.0*
1,1,.006,-.0455,-.01283*
1,1,.006,-.01224,-.028*
20,1,.006,-.01224,-.028,-.00874,-.02917,0.0*
1,1,.006,-.00874,-.02917*
20,1,.006,-.00874,-.02917,-.00407,-.028,0.0*
1,1,.006,-.00407,-.028*
20,1,.006,-.00407,-.028,-.00116,-.02567,0.0*
1,1,.006,-.00116,-.02567*
20,1,.006,-.00116,-.02567,.00118,-.02275,0.0*
1,1,.006,.00118,-.02275*
20,1,.006,.00118,-.02275,.00468,-.01342,0.0*
1,1,.006,.00468,-.01342*
20,1,.006,.00468,-.01342,.01226,.00583,0.0*
1,1,.006,.01226,.00583*
1,1,.006,-.00641,.00583*
20,1,.006,-.00641,.00583,.00468,-.01342,0.0*
1,1,.006,.00468,-.01342*
1,1,.006,.03502,.0175*
20,1,.006,.03502,.0175,.03502,-.0175,0.0*
1,1,.006,.03502,-.0175*
1,1,.006,.02685,.00583*
20,1,.006,.02685,.00583,.04319,.00583,0.0*
1,1,.006,.04319,.00583*
%
%ADD24MACRO24*%
%AMMACRO34*
1,1,.006,0.0,.035*
20,1,.006,0.0,.035,.035,-.035,0.0*
1,1,.006,.035,-.035*
20,1,.006,.035,-.035,-.035,-.035,0.0*
1,1,.006,-.035,-.035*
20,1,.006,-.035,-.035,0.0,.035,0.0*
1,1,.006,0.0,.035*
1,1,.006,-.035,.0175*
20,1,.006,-.035,.0175,-.03967,.01633,0.0*
1,1,.006,-.03967,.01633*
20,1,.006,-.03967,.01633,-.04317,.01342,0.0*
1,1,.006,-.04317,.01342*
20,1,.006,-.04317,.01342,-.0455,.00992,0.0*
1,1,.006,-.0455,.00992*
20,1,.006,-.0455,.00992,-.04725,.00525,0.0*
1,1,.006,-.04725,.00525*
20,1,.006,-.04725,.00525,-.04783,0.0,0.0*
1,1,.006,-.04783,0.0*
20,1,.006,-.04783,0.0,-.04725,-.00525,0.0*
1,1,.006,-.04725,-.00525*
20,1,.006,-.04725,-.00525,-.0455,-.00992,0.0*
1,1,.006,-.0455,-.00992*
20,1,.006,-.0455,-.00992,-.04317,-.01342,0.0*
1,1,.006,-.04317,-.01342*
20,1,.006,-.04317,-.01342,-.03967,-.01633,0.0*
1,1,.006,-.03967,-.01633*
20,1,.006,-.03967,-.01633,-.035,-.0175,0.0*
1,1,.006,-.035,-.0175*
20,1,.006,-.035,-.0175,-.03033,-.01633,0.0*
1,1,.006,-.03033,-.01633*
20,1,.006,-.03033,-.01633,-.02683,-.01342,0.0*
1,1,.006,-.02683,-.01342*
20,1,.006,-.02683,-.01342,-.0245,-.00992,0.0*
1,1,.006,-.0245,-.00992*
20,1,.006,-.0245,-.00992,-.02275,-.00525,0.0*
1,1,.006,-.02275,-.00525*
20,1,.006,-.02275,-.00525,-.02217,0.0,0.0*
1,1,.006,-.02217,0.0*
20,1,.006,-.02217,0.0,-.02275,.00525,0.0*
1,1,.006,-.02275,.00525*
20,1,.006,-.02275,.00525,-.0245,.00992,0.0*
1,1,.006,-.0245,.00992*
20,1,.006,-.0245,.00992,-.02683,.01342,0.0*
1,1,.006,-.02683,.01342*
20,1,.006,-.02683,.01342,-.03033,.01633,0.0*
1,1,.006,-.03033,.01633*
20,1,.006,-.03033,.01633,-.035,.0175,0.0*
1,1,.006,-.035,.0175*
1,1,.006,.00701,-.0175*
20,1,.006,.00701,-.0175,.00701,.0175,0.0*
1,1,.006,.00701,.0175*
20,1,.006,.00701,.0175,-.01457,-.00758,0.0*
1,1,.006,-.01457,-.00758*
20,1,.006,-.01457,-.00758,.01459,-.00758,0.0*
1,1,.006,.01459,-.00758*
1,1,.006,.03502,-.0175*
20,1,.006,.03502,-.0175,.03502,.0175,0.0*
1,1,.006,.03502,.0175*
20,1,.006,.03502,.0175,.02802,.0105,0.0*
1,1,.006,.02802,.0105*
1,1,.006,.02802,-.0175*
20,1,.006,.02802,-.0175,.04202,-.0175,0.0*
1,1,.006,.04202,-.0175*
%
%ADD34MACRO34*%
%AMMACRO32*
1,1,.006,0.0,.035*
20,1,.006,0.0,.035,.035,-.035,0.0*
1,1,.006,.035,-.035*
20,1,.006,.035,-.035,-.035,-.035,0.0*
1,1,.006,-.035,-.035*
20,1,.006,-.035,-.035,0.0,.035,0.0*
1,1,.006,0.0,.035*
1,1,.006,-.035,.0175*
20,1,.006,-.035,.0175,-.03967,.01633,0.0*
1,1,.006,-.03967,.01633*
20,1,.006,-.03967,.01633,-.04317,.01342,0.0*
1,1,.006,-.04317,.01342*
20,1,.006,-.04317,.01342,-.0455,.00992,0.0*
1,1,.006,-.0455,.00992*
20,1,.006,-.0455,.00992,-.04725,.00525,0.0*
1,1,.006,-.04725,.00525*
20,1,.006,-.04725,.00525,-.04783,0.0,0.0*
1,1,.006,-.04783,0.0*
20,1,.006,-.04783,0.0,-.04725,-.00525,0.0*
1,1,.006,-.04725,-.00525*
20,1,.006,-.04725,-.00525,-.0455,-.00992,0.0*
1,1,.006,-.0455,-.00992*
20,1,.006,-.0455,-.00992,-.04317,-.01342,0.0*
1,1,.006,-.04317,-.01342*
20,1,.006,-.04317,-.01342,-.03967,-.01633,0.0*
1,1,.006,-.03967,-.01633*
20,1,.006,-.03967,-.01633,-.035,-.0175,0.0*
1,1,.006,-.035,-.0175*
20,1,.006,-.035,-.0175,-.03033,-.01633,0.0*
1,1,.006,-.03033,-.01633*
20,1,.006,-.03033,-.01633,-.02683,-.01342,0.0*
1,1,.006,-.02683,-.01342*
20,1,.006,-.02683,-.01342,-.0245,-.00992,0.0*
1,1,.006,-.0245,-.00992*
20,1,.006,-.0245,-.00992,-.02275,-.00525,0.0*
1,1,.006,-.02275,-.00525*
20,1,.006,-.02275,-.00525,-.02217,0.0,0.0*
1,1,.006,-.02217,0.0*
20,1,.006,-.02217,0.0,-.02275,.00525,0.0*
1,1,.006,-.02275,.00525*
20,1,.006,-.02275,.00525,-.0245,.00992,0.0*
1,1,.006,-.0245,.00992*
20,1,.006,-.0245,.00992,-.02683,.01342,0.0*
1,1,.006,-.02683,.01342*
20,1,.006,-.02683,.01342,-.03033,.01633,0.0*
1,1,.006,-.03033,.01633*
20,1,.006,-.03033,.01633,-.035,.0175,0.0*
1,1,.006,-.035,.0175*
1,1,.006,.00701,-.0175*
20,1,.006,.00701,-.0175,.00701,.0175,0.0*
1,1,.006,.00701,.0175*
20,1,.006,.00701,.0175,-.01457,-.00758,0.0*
1,1,.006,-.01457,-.00758*
20,1,.006,-.01457,-.00758,.01459,-.00758,0.0*
1,1,.006,.01459,-.00758*
1,1,.006,.04202,-.0175*
20,1,.006,.04202,-.0175,.04202,.0175,0.0*
1,1,.006,.04202,.0175*
20,1,.006,.04202,.0175,.02044,-.00758,0.0*
1,1,.006,.02044,-.00758*
20,1,.006,.02044,-.00758,.0496,-.00758,0.0*
1,1,.006,.0496,-.00758*
%
%ADD32MACRO32*%
%AMMACRO33*
1,1,.006,0.0,.035*
20,1,.006,0.0,.035,.035,-.035,0.0*
1,1,.006,.035,-.035*
20,1,.006,.035,-.035,-.035,-.035,0.0*
1,1,.006,-.035,-.035*
20,1,.006,-.035,-.035,0.0,.035,0.0*
1,1,.006,0.0,.035*
1,1,.006,-.035,.0175*
20,1,.006,-.035,.0175,-.03967,.01633,0.0*
1,1,.006,-.03967,.01633*
20,1,.006,-.03967,.01633,-.04317,.01342,0.0*
1,1,.006,-.04317,.01342*
20,1,.006,-.04317,.01342,-.0455,.00992,0.0*
1,1,.006,-.0455,.00992*
20,1,.006,-.0455,.00992,-.04725,.00525,0.0*
1,1,.006,-.04725,.00525*
20,1,.006,-.04725,.00525,-.04783,0.0,0.0*
1,1,.006,-.04783,0.0*
20,1,.006,-.04783,0.0,-.04725,-.00525,0.0*
1,1,.006,-.04725,-.00525*
20,1,.006,-.04725,-.00525,-.0455,-.00992,0.0*
1,1,.006,-.0455,-.00992*
20,1,.006,-.0455,-.00992,-.04317,-.01342,0.0*
1,1,.006,-.04317,-.01342*
20,1,.006,-.04317,-.01342,-.03967,-.01633,0.0*
1,1,.006,-.03967,-.01633*
20,1,.006,-.03967,-.01633,-.035,-.0175,0.0*
1,1,.006,-.035,-.0175*
20,1,.006,-.035,-.0175,-.03033,-.01633,0.0*
1,1,.006,-.03033,-.01633*
20,1,.006,-.03033,-.01633,-.02683,-.01342,0.0*
1,1,.006,-.02683,-.01342*
20,1,.006,-.02683,-.01342,-.0245,-.00992,0.0*
1,1,.006,-.0245,-.00992*
20,1,.006,-.0245,-.00992,-.02275,-.00525,0.0*
1,1,.006,-.02275,-.00525*
20,1,.006,-.02275,-.00525,-.02217,0.0,0.0*
1,1,.006,-.02217,0.0*
20,1,.006,-.02217,0.0,-.02275,.00525,0.0*
1,1,.006,-.02275,.00525*
20,1,.006,-.02275,.00525,-.0245,.00992,0.0*
1,1,.006,-.0245,.00992*
20,1,.006,-.0245,.00992,-.02683,.01342,0.0*
1,1,.006,-.02683,.01342*
20,1,.006,-.02683,.01342,-.03033,.01633,0.0*
1,1,.006,-.03033,.01633*
20,1,.006,-.03033,.01633,-.035,.0175,0.0*
1,1,.006,-.035,.0175*
1,1,.006,.00701,-.0175*
20,1,.006,.00701,-.0175,.00701,.0175,0.0*
1,1,.006,.00701,.0175*
20,1,.006,.00701,.0175,-.01457,-.00758,0.0*
1,1,.006,-.01457,-.00758*
20,1,.006,-.01457,-.00758,.01459,-.00758,0.0*
1,1,.006,.01459,-.00758*
1,1,.006,.02394,-.00292*
20,1,.006,.02394,-.00292,.02802,.00117,0.0*
1,1,.006,.02802,.00117*
20,1,.006,.02802,.00117,.03152,.0035,0.0*
1,1,.006,.03152,.0035*
20,1,.006,.03152,.0035,.03619,.00467,0.0*
1,1,.006,.03619,.00467*
20,1,.006,.03619,.00467,.04027,.0035,0.0*
1,1,.006,.04027,.0035*
20,1,.006,.04027,.0035,.04319,.00117,0.0*
1,1,.006,.04319,.00117*
20,1,.006,.04319,.00117,.04552,-.00233,0.0*
1,1,.006,.04552,-.00233*
20,1,.006,.04552,-.00233,.0461,-.00642,0.0*
1,1,.006,.0461,-.00642*
20,1,.006,.0461,-.00642,.04552,-.00992,0.0*
1,1,.006,.04552,-.00992*
20,1,.006,.04552,-.00992,.04319,-.01342,0.0*
1,1,.006,.04319,-.01342*
20,1,.006,.04319,-.01342,.03969,-.01633,0.0*
1,1,.006,.03969,-.01633*
20,1,.006,.03969,-.01633,.0356,-.0175,0.0*
1,1,.006,.0356,-.0175*
20,1,.006,.0356,-.0175,.03094,-.01633,0.0*
1,1,.006,.03094,-.01633*
20,1,.006,.03094,-.01633,.02685,-.01283,0.0*
1,1,.006,.02685,-.01283*
20,1,.006,.02685,-.01283,.02452,-.00758,0.0*
1,1,.006,.02452,-.00758*
20,1,.006,.02452,-.00758,.02394,-.00175,0.0*
1,1,.006,.02394,-.00175*
20,1,.006,.02394,-.00175,.0251,.00583,0.0*
1,1,.006,.0251,.00583*
20,1,.006,.0251,.00583,.02685,.00992,0.0*
1,1,.006,.02685,.00992*
20,1,.006,.02685,.00992,.02977,.014,0.0*
1,1,.006,.02977,.014*
20,1,.006,.02977,.014,.03385,.01692,0.0*
1,1,.006,.03385,.01692*
20,1,.006,.03385,.01692,.03794,.0175,0.0*
1,1,.006,.03794,.0175*
20,1,.006,.03794,.0175,.04202,.01633,0.0*
1,1,.006,.04202,.01633*
20,1,.006,.04202,.01633,.04494,.01342,0.0*
1,1,.006,.04494,.01342*
%
%ADD33MACRO33*%
%AMMACRO36*
1,1,.006,0.0,.035*
20,1,.006,0.0,.035,.035,-.035,0.0*
1,1,.006,.035,-.035*
20,1,.006,.035,-.035,-.035,-.035,0.0*
1,1,.006,-.035,-.035*
20,1,.006,-.035,-.035,0.0,.035,0.0*
1,1,.006,0.0,.035*
1,1,.006,-.035,.0175*
20,1,.006,-.035,.0175,-.03967,.01633,0.0*
1,1,.006,-.03967,.01633*
20,1,.006,-.03967,.01633,-.04317,.01342,0.0*
1,1,.006,-.04317,.01342*
20,1,.006,-.04317,.01342,-.0455,.00992,0.0*
1,1,.006,-.0455,.00992*
20,1,.006,-.0455,.00992,-.04725,.00525,0.0*
1,1,.006,-.04725,.00525*
20,1,.006,-.04725,.00525,-.04783,0.0,0.0*
1,1,.006,-.04783,0.0*
20,1,.006,-.04783,0.0,-.04725,-.00525,0.0*
1,1,.006,-.04725,-.00525*
20,1,.006,-.04725,-.00525,-.0455,-.00992,0.0*
1,1,.006,-.0455,-.00992*
20,1,.006,-.0455,-.00992,-.04317,-.01342,0.0*
1,1,.006,-.04317,-.01342*
20,1,.006,-.04317,-.01342,-.03967,-.01633,0.0*
1,1,.006,-.03967,-.01633*
20,1,.006,-.03967,-.01633,-.035,-.0175,0.0*
1,1,.006,-.035,-.0175*
20,1,.006,-.035,-.0175,-.03033,-.01633,0.0*
1,1,.006,-.03033,-.01633*
20,1,.006,-.03033,-.01633,-.02683,-.01342,0.0*
1,1,.006,-.02683,-.01342*
20,1,.006,-.02683,-.01342,-.0245,-.00992,0.0*
1,1,.006,-.0245,-.00992*
20,1,.006,-.0245,-.00992,-.02275,-.00525,0.0*
1,1,.006,-.02275,-.00525*
20,1,.006,-.02275,-.00525,-.02217,0.0,0.0*
1,1,.006,-.02217,0.0*
20,1,.006,-.02217,0.0,-.02275,.00525,0.0*
1,1,.006,-.02275,.00525*
20,1,.006,-.02275,.00525,-.0245,.00992,0.0*
1,1,.006,-.0245,.00992*
20,1,.006,-.0245,.00992,-.02683,.01342,0.0*
1,1,.006,-.02683,.01342*
20,1,.006,-.02683,.01342,-.03033,.01633,0.0*
1,1,.006,-.03033,.01633*
20,1,.006,-.03033,.01633,-.035,.0175,0.0*
1,1,.006,-.035,.0175*
1,1,.006,-.01282,-.01225*
20,1,.006,-.01282,-.01225,-.00932,-.01517,0.0*
1,1,.006,-.00932,-.01517*
20,1,.006,-.00932,-.01517,-.00524,-.01692,0.0*
1,1,.006,-.00524,-.01692*
20,1,.006,-.00524,-.01692,.00001,-.0175,0.0*
1,1,.006,.00001,-.0175*
20,1,.006,.00001,-.0175,.00526,-.01633,0.0*
1,1,.006,.00526,-.01633*
20,1,.006,.00526,-.01633,.00934,-.014,0.0*
1,1,.006,.00934,-.014*
20,1,.006,.00934,-.014,.01226,-.00992,0.0*
1,1,.006,.01226,-.00992*
20,1,.006,.01226,-.00992,.01284,-.00525,0.0*
1,1,.006,.01284,-.00525*
20,1,.006,.01284,-.00525,.01168,-.00058,0.0*
1,1,.006,.01168,-.00058*
20,1,.006,.01168,-.00058,.00876,.00233,0.0*
1,1,.006,.00876,.00233*
20,1,.006,.00876,.00233,.00468,.00467,0.0*
1,1,.006,.00468,.00467*
20,1,.006,.00468,.00467,.00059,.00525,0.0*
1,1,.006,.00059,.00525*
20,1,.006,.00059,.00525,-.00349,.00467,0.0*
1,1,.006,-.00349,.00467*
20,1,.006,-.00349,.00467,-.00874,.00233,0.0*
1,1,.006,-.00874,.00233*
20,1,.006,-.00874,.00233,-.00699,.0175,0.0*
1,1,.006,-.00699,.0175*
20,1,.006,-.00699,.0175,.00876,.0175,0.0*
1,1,.006,.00876,.0175*
1,1,.006,.02394,-.00292*
20,1,.006,.02394,-.00292,.02802,.00117,0.0*
1,1,.006,.02802,.00117*
20,1,.006,.02802,.00117,.03152,.0035,0.0*
1,1,.006,.03152,.0035*
20,1,.006,.03152,.0035,.03619,.00467,0.0*
1,1,.006,.03619,.00467*
20,1,.006,.03619,.00467,.04027,.0035,0.0*
1,1,.006,.04027,.0035*
20,1,.006,.04027,.0035,.04319,.00117,0.0*
1,1,.006,.04319,.00117*
20,1,.006,.04319,.00117,.04552,-.00233,0.0*
1,1,.006,.04552,-.00233*
20,1,.006,.04552,-.00233,.0461,-.00642,0.0*
1,1,.006,.0461,-.00642*
20,1,.006,.0461,-.00642,.04552,-.00992,0.0*
1,1,.006,.04552,-.00992*
20,1,.006,.04552,-.00992,.04319,-.01342,0.0*
1,1,.006,.04319,-.01342*
20,1,.006,.04319,-.01342,.03969,-.01633,0.0*
1,1,.006,.03969,-.01633*
20,1,.006,.03969,-.01633,.0356,-.0175,0.0*
1,1,.006,.0356,-.0175*
20,1,.006,.0356,-.0175,.03094,-.01633,0.0*
1,1,.006,.03094,-.01633*
20,1,.006,.03094,-.01633,.02685,-.01283,0.0*
1,1,.006,.02685,-.01283*
20,1,.006,.02685,-.01283,.02452,-.00758,0.0*
1,1,.006,.02452,-.00758*
20,1,.006,.02452,-.00758,.02394,-.00175,0.0*
1,1,.006,.02394,-.00175*
20,1,.006,.02394,-.00175,.0251,.00583,0.0*
1,1,.006,.0251,.00583*
20,1,.006,.0251,.00583,.02685,.00992,0.0*
1,1,.006,.02685,.00992*
20,1,.006,.02685,.00992,.02977,.014,0.0*
1,1,.006,.02977,.014*
20,1,.006,.02977,.014,.03385,.01692,0.0*
1,1,.006,.03385,.01692*
20,1,.006,.03385,.01692,.03794,.0175,0.0*
1,1,.006,.03794,.0175*
20,1,.006,.03794,.0175,.04202,.01633,0.0*
1,1,.006,.04202,.01633*
20,1,.006,.04202,.01633,.04494,.01342,0.0*
1,1,.006,.04494,.01342*
%
%ADD36MACRO36*%
%AMMACRO21*
1,1,.006,0.0,.035*
20,1,.006,0.0,.035,.035,-.035,0.0*
1,1,.006,.035,-.035*
20,1,.006,.035,-.035,-.035,-.035,0.0*
1,1,.006,-.035,-.035*
20,1,.006,-.035,-.035,0.0,.035,0.0*
1,1,.006,0.0,.035*
1,1,.006,-.035,.0175*
20,1,.006,-.035,.0175,-.03967,.01633,0.0*
1,1,.006,-.03967,.01633*
20,1,.006,-.03967,.01633,-.04317,.01342,0.0*
1,1,.006,-.04317,.01342*
20,1,.006,-.04317,.01342,-.0455,.00992,0.0*
1,1,.006,-.0455,.00992*
20,1,.006,-.0455,.00992,-.04725,.00525,0.0*
1,1,.006,-.04725,.00525*
20,1,.006,-.04725,.00525,-.04783,0.0,0.0*
1,1,.006,-.04783,0.0*
20,1,.006,-.04783,0.0,-.04725,-.00525,0.0*
1,1,.006,-.04725,-.00525*
20,1,.006,-.04725,-.00525,-.0455,-.00992,0.0*
1,1,.006,-.0455,-.00992*
20,1,.006,-.0455,-.00992,-.04317,-.01342,0.0*
1,1,.006,-.04317,-.01342*
20,1,.006,-.04317,-.01342,-.03967,-.01633,0.0*
1,1,.006,-.03967,-.01633*
20,1,.006,-.03967,-.01633,-.035,-.0175,0.0*
1,1,.006,-.035,-.0175*
20,1,.006,-.035,-.0175,-.03033,-.01633,0.0*
1,1,.006,-.03033,-.01633*
20,1,.006,-.03033,-.01633,-.02683,-.01342,0.0*
1,1,.006,-.02683,-.01342*
20,1,.006,-.02683,-.01342,-.0245,-.00992,0.0*
1,1,.006,-.0245,-.00992*
20,1,.006,-.0245,-.00992,-.02275,-.00525,0.0*
1,1,.006,-.02275,-.00525*
20,1,.006,-.02275,-.00525,-.02217,0.0,0.0*
1,1,.006,-.02217,0.0*
20,1,.006,-.02217,0.0,-.02275,.00525,0.0*
1,1,.006,-.02275,.00525*
20,1,.006,-.02275,.00525,-.0245,.00992,0.0*
1,1,.006,-.0245,.00992*
20,1,.006,-.0245,.00992,-.02683,.01342,0.0*
1,1,.006,-.02683,.01342*
20,1,.006,-.02683,.01342,-.03033,.01633,0.0*
1,1,.006,-.03033,.01633*
20,1,.006,-.03033,.01633,-.035,.0175,0.0*
1,1,.006,-.035,.0175*
1,1,.006,.00701,-.0175*
20,1,.006,.00701,-.0175,.00701,.0175,0.0*
1,1,.006,.00701,.0175*
20,1,.006,.00701,.0175,-.01457,-.00758,0.0*
1,1,.006,-.01457,-.00758*
20,1,.006,-.01457,-.00758,.01459,-.00758,0.0*
1,1,.006,.01459,-.00758*
1,1,.006,.03502,-.0175*
20,1,.006,.03502,-.0175,.0391,-.01692,0.0*
1,1,.006,.0391,-.01692*
20,1,.006,.0391,-.01692,.04377,-.01517,0.0*
1,1,.006,.04377,-.01517*
20,1,.006,.04377,-.01517,.04669,-.01225,0.0*
1,1,.006,.04669,-.01225*
20,1,.006,.04669,-.01225,.04785,-.00817,0.0*
1,1,.006,.04785,-.00817*
20,1,.006,.04785,-.00817,.04669,-.00408,0.0*
1,1,.006,.04669,-.00408*
20,1,.006,.04669,-.00408,.04319,-.00058,0.0*
1,1,.006,.04319,-.00058*
20,1,.006,.04319,-.00058,.03794,.00117,0.0*
1,1,.006,.03794,.00117*
20,1,.006,.03794,.00117,.0321,.00117,0.0*
1,1,.006,.0321,.00117*
20,1,.006,.0321,.00117,.0286,.00233,0.0*
1,1,.006,.0286,.00233*
20,1,.006,.0286,.00233,.02569,.00525,0.0*
1,1,.006,.02569,.00525*
20,1,.006,.02569,.00525,.02452,.00933,0.0*
1,1,.006,.02452,.00933*
20,1,.006,.02452,.00933,.02627,.01342,0.0*
1,1,.006,.02627,.01342*
20,1,.006,.02627,.01342,.03035,.01633,0.0*
1,1,.006,.03035,.01633*
20,1,.006,.03035,.01633,.03502,.0175,0.0*
1,1,.006,.03502,.0175*
20,1,.006,.03502,.0175,.03969,.01633,0.0*
1,1,.006,.03969,.01633*
20,1,.006,.03969,.01633,.04377,.01342,0.0*
1,1,.006,.04377,.01342*
20,1,.006,.04377,.01342,.04552,.00933,0.0*
1,1,.006,.04552,.00933*
20,1,.006,.04552,.00933,.04435,.00525,0.0*
1,1,.006,.04435,.00525*
20,1,.006,.04435,.00525,.04144,.00233,0.0*
1,1,.006,.04144,.00233*
20,1,.006,.04144,.00233,.03794,.00117,0.0*
1,1,.006,.03794,.00117*
20,1,.006,.03794,.00117,.0321,.00117,0.0*
1,1,.006,.0321,.00117*
20,1,.006,.0321,.00117,.02685,-.00058,0.0*
1,1,.006,.02685,-.00058*
20,1,.006,.02685,-.00058,.02335,-.00408,0.0*
1,1,.006,.02335,-.00408*
20,1,.006,.02335,-.00408,.02219,-.00817,0.0*
1,1,.006,.02219,-.00817*
20,1,.006,.02219,-.00817,.02335,-.01225,0.0*
1,1,.006,.02335,-.01225*
20,1,.006,.02335,-.01225,.02627,-.01517,0.0*
1,1,.006,.02627,-.01517*
20,1,.006,.02627,-.01517,.03094,-.01692,0.0*
1,1,.006,.03094,-.01692*
20,1,.006,.03094,-.01692,.03502,-.0175,0.0*
1,1,.006,.03502,-.0175*
%
%ADD21MACRO21*%
%AMMACRO16*
1,1,.006,0.0,.035*
20,1,.006,0.0,.035,.035,-.035,0.0*
1,1,.006,.035,-.035*
20,1,.006,.035,-.035,-.035,-.035,0.0*
1,1,.006,-.035,-.035*
20,1,.006,-.035,-.035,0.0,.035,0.0*
1,1,.006,0.0,.035*
1,1,.006,-.035,.0175*
20,1,.006,-.035,.0175,-.03967,.01633,0.0*
1,1,.006,-.03967,.01633*
20,1,.006,-.03967,.01633,-.04317,.01342,0.0*
1,1,.006,-.04317,.01342*
20,1,.006,-.04317,.01342,-.0455,.00992,0.0*
1,1,.006,-.0455,.00992*
20,1,.006,-.0455,.00992,-.04725,.00525,0.0*
1,1,.006,-.04725,.00525*
20,1,.006,-.04725,.00525,-.04783,0.0,0.0*
1,1,.006,-.04783,0.0*
20,1,.006,-.04783,0.0,-.04725,-.00525,0.0*
1,1,.006,-.04725,-.00525*
20,1,.006,-.04725,-.00525,-.0455,-.00992,0.0*
1,1,.006,-.0455,-.00992*
20,1,.006,-.0455,-.00992,-.04317,-.01342,0.0*
1,1,.006,-.04317,-.01342*
20,1,.006,-.04317,-.01342,-.03967,-.01633,0.0*
1,1,.006,-.03967,-.01633*
20,1,.006,-.03967,-.01633,-.035,-.0175,0.0*
1,1,.006,-.035,-.0175*
20,1,.006,-.035,-.0175,-.03033,-.01633,0.0*
1,1,.006,-.03033,-.01633*
20,1,.006,-.03033,-.01633,-.02683,-.01342,0.0*
1,1,.006,-.02683,-.01342*
20,1,.006,-.02683,-.01342,-.0245,-.00992,0.0*
1,1,.006,-.0245,-.00992*
20,1,.006,-.0245,-.00992,-.02275,-.00525,0.0*
1,1,.006,-.02275,-.00525*
20,1,.006,-.02275,-.00525,-.02217,0.0,0.0*
1,1,.006,-.02217,0.0*
20,1,.006,-.02217,0.0,-.02275,.00525,0.0*
1,1,.006,-.02275,.00525*
20,1,.006,-.02275,.00525,-.0245,.00992,0.0*
1,1,.006,-.0245,.00992*
20,1,.006,-.0245,.00992,-.02683,.01342,0.0*
1,1,.006,-.02683,.01342*
20,1,.006,-.02683,.01342,-.03033,.01633,0.0*
1,1,.006,-.03033,.01633*
20,1,.006,-.03033,.01633,-.035,.0175,0.0*
1,1,.006,-.035,.0175*
1,1,.006,-.01282,-.01225*
20,1,.006,-.01282,-.01225,-.00932,-.01517,0.0*
1,1,.006,-.00932,-.01517*
20,1,.006,-.00932,-.01517,-.00524,-.01692,0.0*
1,1,.006,-.00524,-.01692*
20,1,.006,-.00524,-.01692,.00001,-.0175,0.0*
1,1,.006,.00001,-.0175*
20,1,.006,.00001,-.0175,.00526,-.01633,0.0*
1,1,.006,.00526,-.01633*
20,1,.006,.00526,-.01633,.00934,-.014,0.0*
1,1,.006,.00934,-.014*
20,1,.006,.00934,-.014,.01226,-.00992,0.0*
1,1,.006,.01226,-.00992*
20,1,.006,.01226,-.00992,.01284,-.00525,0.0*
1,1,.006,.01284,-.00525*
20,1,.006,.01284,-.00525,.01168,-.00058,0.0*
1,1,.006,.01168,-.00058*
20,1,.006,.01168,-.00058,.00876,.00233,0.0*
1,1,.006,.00876,.00233*
20,1,.006,.00876,.00233,.00468,.00467,0.0*
1,1,.006,.00468,.00467*
20,1,.006,.00468,.00467,.00059,.00525,0.0*
1,1,.006,.00059,.00525*
20,1,.006,.00059,.00525,-.00349,.00467,0.0*
1,1,.006,-.00349,.00467*
20,1,.006,-.00349,.00467,-.00874,.00233,0.0*
1,1,.006,-.00874,.00233*
20,1,.006,-.00874,.00233,-.00699,.0175,0.0*
1,1,.006,-.00699,.0175*
20,1,.006,-.00699,.0175,.00876,.0175,0.0*
1,1,.006,.00876,.0175*
1,1,.006,.03385,-.0175*
20,1,.006,.03385,-.0175,.03502,-.00992,0.0*
1,1,.006,.03502,-.00992*
20,1,.006,.03502,-.00992,.03677,-.0035,0.0*
1,1,.006,.03677,-.0035*
20,1,.006,.03677,-.0035,.0391,.00233,0.0*
1,1,.006,.0391,.00233*
20,1,.006,.0391,.00233,.04202,.00875,0.0*
1,1,.006,.04202,.00875*
20,1,.006,.04202,.00875,.04669,.0175,0.0*
1,1,.006,.04669,.0175*
20,1,.006,.04669,.0175,.02335,.0175,0.0*
1,1,.006,.02335,.0175*
%
%ADD16MACRO16*%
%AMMACRO17*
1,1,.006,.035,0.0*
20,1,.006,.035,0.0,.034468,-.006078,0.0*
1,1,.006,.034468,-.006078*
20,1,.006,.034468,-.006078,.032889,-.011971,0.0*
1,1,.006,.032889,-.011971*
20,1,.006,.032889,-.011971,.030311,-.0175,0.0*
1,1,.006,.030311,-.0175*
20,1,.006,.030311,-.0175,.026812,-.022498,0.0*
1,1,.006,.026812,-.022498*
20,1,.006,.026812,-.022498,.022498,-.026812,0.0*
1,1,.006,.022498,-.026812*
20,1,.006,.022498,-.026812,.0175,-.030311,0.0*
1,1,.006,.0175,-.030311*
20,1,.006,.0175,-.030311,.011971,-.032889,0.0*
1,1,.006,.011971,-.032889*
20,1,.006,.011971,-.032889,.006078,-.034468,0.0*
1,1,.006,.006078,-.034468*
20,1,.006,.006078,-.034468,0.0,-.035,0.0*
1,1,.006,0.0,-.035*
20,1,.006,0.0,-.035,-.006078,-.034468,0.0*
1,1,.006,-.006078,-.034468*
20,1,.006,-.006078,-.034468,-.011971,-.032889,0.0*
1,1,.006,-.011971,-.032889*
20,1,.006,-.011971,-.032889,-.0175,-.030311,0.0*
1,1,.006,-.0175,-.030311*
20,1,.006,-.0175,-.030311,-.022498,-.026812,0.0*
1,1,.006,-.022498,-.026812*
20,1,.006,-.022498,-.026812,-.026812,-.022498,0.0*
1,1,.006,-.026812,-.022498*
20,1,.006,-.026812,-.022498,-.030311,-.0175,0.0*
1,1,.006,-.030311,-.0175*
20,1,.006,-.030311,-.0175,-.032889,-.011971,0.0*
1,1,.006,-.032889,-.011971*
20,1,.006,-.032889,-.011971,-.034468,-.006078,0.0*
1,1,.006,-.034468,-.006078*
20,1,.006,-.034468,-.006078,-.035,0.0,0.0*
1,1,.006,-.035,0.0*
20,1,.006,-.035,0.0,-.034468,.006078,0.0*
1,1,.006,-.034468,.006078*
20,1,.006,-.034468,.006078,-.032889,.011971,0.0*
1,1,.006,-.032889,.011971*
20,1,.006,-.032889,.011971,-.030311,.0175,0.0*
1,1,.006,-.030311,.0175*
20,1,.006,-.030311,.0175,-.026812,.022498,0.0*
1,1,.006,-.026812,.022498*
20,1,.006,-.026812,.022498,-.022498,.026812,0.0*
1,1,.006,-.022498,.026812*
20,1,.006,-.022498,.026812,-.0175,.030311,0.0*
1,1,.006,-.0175,.030311*
20,1,.006,-.0175,.030311,-.011971,.032889,0.0*
1,1,.006,-.011971,.032889*
20,1,.006,-.011971,.032889,-.006078,.034468,0.0*
1,1,.006,-.006078,.034468*
20,1,.006,-.006078,.034468,0.0,.035,0.0*
1,1,.006,0.0,.035*
20,1,.006,0.0,.035,.006078,.034468,0.0*
1,1,.006,.006078,.034468*
20,1,.006,.006078,.034468,.011971,.032889,0.0*
1,1,.006,.011971,.032889*
20,1,.006,.011971,.032889,.0175,.030311,0.0*
1,1,.006,.0175,.030311*
20,1,.006,.0175,.030311,.022498,.026812,0.0*
1,1,.006,.022498,.026812*
20,1,.006,.022498,.026812,.026812,.022498,0.0*
1,1,.006,.026812,.022498*
20,1,.006,.026812,.022498,.030311,.0175,0.0*
1,1,.006,.030311,.0175*
20,1,.006,.030311,.0175,.032889,.011971,0.0*
1,1,.006,.032889,.011971*
20,1,.006,.032889,.011971,.034468,.006078,0.0*
1,1,.006,.034468,.006078*
20,1,.006,.034468,.006078,.035,0.0,0.0*
1,1,.006,.035,0.0*
1,1,.006,-.0455,.00583*
20,1,.006,-.0455,.00583,-.035,-.0175,0.0*
1,1,.006,-.035,-.0175*
20,1,.006,-.035,-.0175,-.0245,.00583,0.0*
1,1,.006,-.0245,.00583*
1,1,.006,.00001,.00583*
20,1,.006,.00001,.00583,.00001,-.0175,0.0*
1,1,.006,.00001,-.0175*
1,1,.006,.00001,.01517*
20,1,.006,.00001,.01517,-.00116,.01575,0.0*
1,1,.006,-.00116,.01575*
20,1,.006,-.00116,.01575,-.00116,.01692,0.0*
1,1,.006,-.00116,.01692*
20,1,.006,-.00116,.01692,.00001,.0175,0.0*
1,1,.006,.00001,.0175*
20,1,.006,.00001,.0175,.00118,.01692,0.0*
1,1,.006,.00118,.01692*
20,1,.006,.00118,.01692,.00118,.01575,0.0*
1,1,.006,.00118,.01575*
20,1,.006,.00118,.01575,.00001,.01517,0.0*
1,1,.006,.00001,.01517*
1,1,.006,.04552,-.0175*
20,1,.006,.04552,-.0175,.04552,.00583,0.0*
1,1,.006,.04552,.00583*
1,1,.006,.04552,.00175*
20,1,.006,.04552,.00175,.04319,.00408,0.0*
1,1,.006,.04319,.00408*
20,1,.006,.04319,.00408,.03969,.00525,0.0*
1,1,.006,.03969,.00525*
20,1,.006,.03969,.00525,.0356,.00583,0.0*
1,1,.006,.0356,.00583*
20,1,.006,.0356,.00583,.03152,.00467,0.0*
1,1,.006,.03152,.00467*
20,1,.006,.03152,.00467,.02802,.00233,0.0*
1,1,.006,.02802,.00233*
20,1,.006,.02802,.00233,.02569,-.00117,0.0*
1,1,.006,.02569,-.00117*
20,1,.006,.02569,-.00117,.02452,-.00583,0.0*
1,1,.006,.02452,-.00583*
20,1,.006,.02452,-.00583,.02569,-.0105,0.0*
1,1,.006,.02569,-.0105*
20,1,.006,.02569,-.0105,.02802,-.014,0.0*
1,1,.006,.02802,-.014*
20,1,.006,.02802,-.014,.03152,-.01633,0.0*
1,1,.006,.03152,-.01633*
20,1,.006,.03152,-.01633,.0356,-.0175,0.0*
1,1,.006,.0356,-.0175*
20,1,.006,.0356,-.0175,.03969,-.01692,0.0*
1,1,.006,.03969,-.01692*
20,1,.006,.03969,-.01692,.04319,-.01517,0.0*
1,1,.006,.04319,-.01517*
20,1,.006,.04319,-.01517,.04552,-.01283,0.0*
1,1,.006,.04552,-.01283*
%
%ADD17MACRO17*%
%ADD40C,.006*%
G75*
%LPD*%
G75*
G36*
G01X1531427Y535293D02*
Y375293D01*
X1536427Y355293D01*
X1546427D01*
X1551427Y375293D01*
Y534793D01*
X1546427Y525293D01*
X1531427Y535293D01*
G37*
G54D10*
X-294532Y1044846D03*
X-281332D03*
X-287932D03*
X-267012Y1044916D03*
X322986Y467109D03*
X330115Y490303D03*
X369507Y464391D03*
X371080Y481589D03*
X1088471Y953095D03*
G54D11*
X-44872Y125213D03*
Y141213D03*
Y232533D03*
D03*
Y248533D03*
D03*
Y738493D03*
Y754493D03*
X-26872Y125213D03*
Y141213D03*
Y232533D03*
D03*
Y248533D03*
D03*
Y738493D03*
Y754493D03*
X1088471Y282145D03*
G54D20*
X43898Y168544D03*
Y231457D03*
X1088471Y250195D03*
G54D21*
X76880Y143269D03*
X86880D03*
X739968Y29361D03*
X749968D03*
X1088471Y537745D03*
G54D30*
X434102Y232640D03*
Y311875D03*
X583913Y69167D03*
X608571D03*
X1088471Y314095D03*
G54D12*
X-39858Y731383D03*
X-35858D03*
X-31858D03*
X4390Y533777D03*
X13170Y372673D03*
X18340Y366452D03*
X13120Y375871D03*
X16010Y369168D03*
X21530Y368991D03*
X14140Y391826D03*
X18210Y386530D03*
X13950Y388616D03*
X13390Y397543D03*
X14240Y394866D03*
X19450Y550297D03*
X18960Y572061D03*
X17876Y578422D03*
X21881Y595792D03*
X17020Y592934D03*
X13510Y591939D03*
X15850Y610980D03*
X14500Y601957D03*
X9240Y638699D03*
X17071Y658951D03*
X11680Y656335D03*
X9260Y658321D03*
X14000Y658369D03*
X14170Y653991D03*
X9360Y653943D03*
X23987Y12977D03*
X28104Y30414D03*
X24411Y16186D03*
X36848Y25198D03*
X28408Y26414D03*
X34149Y44149D03*
X30282Y34564D03*
X30274Y37714D03*
X36567Y73145D03*
X39126Y84631D03*
X36567Y107988D03*
X38280Y362184D03*
X35750Y364593D03*
X33420Y367309D03*
X23860Y366275D03*
X28250Y438740D03*
X37990Y453022D03*
X28250Y472076D03*
X37990Y520218D03*
X38807Y543539D03*
X34140Y540345D03*
X34240Y536966D03*
X38349Y555730D03*
X36930Y611082D03*
X28270Y602194D03*
X33140Y602232D03*
X35862Y617052D03*
X29964Y658951D03*
X45410Y21563D03*
X54860Y16952D03*
X43480Y34592D03*
X45578Y50478D03*
X50981Y58681D03*
X46981Y58690D03*
X49559Y50577D03*
X41685Y73110D03*
X54703Y122796D03*
X46811Y122928D03*
X54062Y257049D03*
X49244Y360352D03*
X40690Y359555D03*
X53340Y393132D03*
X49750Y387305D03*
X51720Y384808D03*
X50840Y395761D03*
X47820Y398827D03*
X49730Y412473D03*
X45530D03*
X52150Y414896D03*
X47900Y414660D03*
X44360Y414915D03*
X49640Y430237D03*
X45410Y430444D03*
X51350Y433695D03*
X44360Y433729D03*
X51670Y462885D03*
X47590Y463876D03*
X49830Y465496D03*
X47200Y467262D03*
X49590Y469432D03*
X49625Y478472D03*
Y480972D03*
X49185Y472713D03*
X50330Y497940D03*
X53330D03*
X49645Y491804D03*
Y489304D03*
X47380Y494638D03*
X53622Y509276D03*
X53330Y506417D03*
Y503817D03*
X50330D03*
X54117Y529098D03*
X46140Y541712D03*
X41957Y543321D03*
X53988Y568748D03*
X43850Y602797D03*
X39360Y604593D03*
X50270Y627793D03*
X51051Y619407D03*
X48060Y621229D03*
X50170Y636895D03*
X51038Y643928D03*
X49720Y668412D03*
X59524Y25922D03*
X66981Y59390D03*
X62981Y59440D03*
X57040Y73421D03*
X60318Y65593D03*
X64309Y141882D03*
X68756Y167695D03*
X59640Y161376D03*
X55963Y199565D03*
X68930Y197193D03*
X57749Y204326D03*
X56383Y218543D03*
X63720Y228683D03*
X56936Y223944D03*
X57624Y366105D03*
X58000Y412641D03*
X64568Y451029D03*
X67568D03*
X70568D03*
X66747Y466363D03*
X64050Y465689D03*
X61183Y465314D03*
X61357Y483392D03*
Y480892D03*
X61188Y487117D03*
X56330Y497940D03*
X58830D03*
X61676Y502656D03*
Y500156D03*
X61188Y489617D03*
Y492117D03*
X55982Y494543D03*
X65438Y510666D03*
X61033Y510705D03*
X61003Y515110D03*
X65478D03*
X56148Y530809D03*
X66181Y562149D03*
X63930Y560181D03*
X66036Y574901D03*
X63670Y576040D03*
X63300Y621755D03*
X63490Y630693D03*
X62160Y644091D03*
X59390Y642906D03*
X59530Y631704D03*
X66880Y761625D03*
X59260Y779815D03*
X58840Y783097D03*
X62290Y779629D03*
X67660Y779452D03*
X62730Y782694D03*
X66860Y782716D03*
X60370Y776861D03*
X64790Y776777D03*
X56500Y789667D03*
X79360Y46044D03*
X82065Y73224D03*
X80845Y106859D03*
X76880Y126528D03*
X72890Y154349D03*
X81030Y172605D03*
X78850Y157866D03*
X85010Y171679D03*
X71510Y164548D03*
X74470Y175666D03*
X75236Y188946D03*
X75359Y201109D03*
X85876Y218939D03*
X78190Y214642D03*
X86172Y213852D03*
X75560Y218513D03*
X72150Y225148D03*
X78614Y229920D03*
X79217Y232861D03*
X83390Y235665D03*
X79142Y237920D03*
X86479Y249259D03*
X81210Y261337D03*
X79544Y267579D03*
X78220Y281745D03*
X78207Y279092D03*
X82368Y297135D03*
X72368Y287906D03*
X82560Y288099D03*
X82600Y285426D03*
X73917Y385722D03*
X74058Y389621D03*
X74031Y393857D03*
X73868Y397913D03*
X80490Y420690D03*
Y423690D03*
X86050Y428718D03*
X80490Y426690D03*
X79900Y439193D03*
X86050Y425112D03*
Y437470D03*
Y434470D03*
X79900Y445193D03*
Y442193D03*
X85617Y451275D03*
X82617D03*
X86050Y443432D03*
Y446432D03*
X83455Y489485D03*
Y491985D03*
X85955Y489485D03*
Y491985D03*
X83455Y494485D03*
X85955D03*
X81635Y513104D03*
X81174Y503587D03*
X81635Y521104D03*
X82031Y523928D03*
X72216Y540493D03*
X81585Y536382D03*
X80318Y541026D03*
X84990Y563286D03*
X82140Y560758D03*
X81980Y556851D03*
X81516Y577905D03*
X83030Y582656D03*
X85140Y585213D03*
X73130Y601599D03*
X73180Y611184D03*
X80630Y689682D03*
X82847Y716068D03*
X82736Y791695D03*
Y788695D03*
X70925D03*
Y791695D03*
X97830Y66508D03*
X98531Y121340D03*
X102257Y167955D03*
X90878Y177967D03*
X90905Y199733D03*
X86560Y205852D03*
X96168Y231618D03*
X98700Y234650D03*
X96990Y223043D03*
X88399Y244041D03*
X93200Y300734D03*
X99968Y367705D03*
X95968Y367814D03*
X98410Y421908D03*
X90031Y421693D03*
X90238Y418623D03*
X101650Y428745D03*
Y425552D03*
Y433296D03*
Y436075D03*
X101590Y446203D03*
X101650Y443038D03*
X88617Y451275D03*
X86726Y501997D03*
X88563Y491984D03*
Y489484D03*
Y494484D03*
X86695Y498180D03*
X87721Y505817D03*
X95660Y531362D03*
X97366Y542897D03*
X88200Y568111D03*
X98370Y619252D03*
X94070Y618986D03*
Y613841D03*
X97790Y613797D03*
X95350Y644088D03*
X98480Y646217D03*
X98410Y648878D03*
Y680541D03*
X100223Y733207D03*
X89810Y765905D03*
X97390Y766435D03*
X98590Y782494D03*
X94547Y788695D03*
Y791695D03*
X112386Y71874D03*
X115628Y104405D03*
X106517Y210796D03*
X104550Y262359D03*
X104270Y265662D03*
X110230Y360735D03*
X103151Y373340D03*
X110230Y363235D03*
X117030Y389978D03*
X110490Y397362D03*
X103750Y402740D03*
X103810Y405876D03*
X103870Y399604D03*
X108235Y401017D03*
X111120Y401084D03*
X115727Y405844D03*
X113412Y404826D03*
X113504Y407673D03*
X114207Y417910D03*
Y414910D03*
X105670Y411262D03*
X117980Y451981D03*
X118020Y455079D03*
X114072Y480964D03*
X115516Y485696D03*
X110400Y502223D03*
X110436Y499681D03*
X110472Y496888D03*
X113337Y502080D03*
X113372Y496888D03*
X113301Y499574D03*
X117026Y488316D03*
X108026Y492500D03*
X114372Y518898D03*
X112575Y532934D03*
X109972Y519508D03*
X113912Y541144D03*
X114005Y544358D03*
X112627Y536697D03*
X109640Y611890D03*
X109410Y621425D03*
X109500Y616724D03*
X109260Y644687D03*
Y648989D03*
X117790Y667235D03*
X115748Y716275D03*
X106358Y785790D03*
X102421Y782191D03*
X110295Y785734D03*
Y782191D03*
X116370Y785941D03*
X104300Y773100D03*
X114232Y791695D03*
Y788695D03*
X129860Y14571D03*
X130195Y19162D03*
X131474Y43439D03*
X126220Y80364D03*
Y83291D03*
X125480Y91163D03*
X132400Y88153D03*
X129580Y86837D03*
X129780Y92580D03*
X124150Y94643D03*
X128330Y98360D03*
X130350Y130400D03*
Y134167D03*
X126460Y250160D03*
X126570Y256194D03*
X129660Y279890D03*
X130310Y269174D03*
X130324Y272096D03*
Y277096D03*
X123160Y287060D03*
X129610Y287115D03*
X123960Y283696D03*
X128960D03*
X125050Y384546D03*
X122120Y386736D03*
X126300Y390369D03*
X122729Y398001D03*
X127729D03*
X125229D03*
X128226Y413925D03*
X125726D03*
X123226D03*
X129028Y425593D03*
X121080Y460060D03*
X124040Y459746D03*
X127060Y460040D03*
X126377Y466738D03*
X126260Y470267D03*
X121360Y472028D03*
X118720Y471989D03*
X126072Y480864D03*
X130794Y493910D03*
X133731D03*
X127705Y489431D03*
X125105D03*
X119326Y489706D03*
X121968Y488481D03*
X122018Y516353D03*
X133138Y510114D03*
X121644Y509398D03*
X130596Y510042D03*
X124652Y509398D03*
X130703Y512549D03*
X130844Y515128D03*
X128087Y513874D03*
X132960Y550005D03*
X125340Y558090D03*
X133590Y588438D03*
X130790Y595613D03*
X128240Y666583D03*
X120909Y674490D03*
X132190Y662616D03*
X129607Y686735D03*
X126220Y720949D03*
X120357Y738889D03*
X132334Y732982D03*
X120322Y742187D03*
X123518Y742030D03*
X130850Y782456D03*
X118169Y783857D03*
X130660Y785601D03*
X127290Y781982D03*
X122720Y785051D03*
X137500Y25494D03*
X147427Y30367D03*
X146380Y20345D03*
X147461Y38078D03*
X147497Y42983D03*
X145210Y60154D03*
X149157Y60010D03*
X137540Y58255D03*
X146558Y74863D03*
X140350Y81347D03*
X135640Y134167D03*
X135590Y130449D03*
X147570Y249033D03*
X147160Y242219D03*
X144400Y244061D03*
Y247561D03*
X141682Y269829D03*
X143150Y281123D03*
X137925Y290987D03*
X137990Y296735D03*
X139950Y293835D03*
X136130Y305640D03*
X137091Y301799D03*
X149020Y303498D03*
X135730Y314543D03*
X134768Y319043D03*
X144058Y376025D03*
X137889Y403348D03*
X141800Y404481D03*
X141847Y401820D03*
X135088Y405060D03*
X135181Y402121D03*
X145295Y404388D03*
X135507Y421367D03*
X139395Y425090D03*
X138437Y435930D03*
Y438430D03*
X147820Y441929D03*
X147576Y445279D03*
Y447779D03*
Y450279D03*
X138437Y440930D03*
X139310Y478102D03*
X136470Y481994D03*
X139365Y516636D03*
X139402Y513707D03*
X149477Y532733D03*
X144120Y547577D03*
X146920Y547677D03*
X145020Y576001D03*
X143252Y573105D03*
X145550Y588088D03*
X141260Y588175D03*
X141190Y597685D03*
X145880Y584125D03*
X144710Y598135D03*
X136420Y599352D03*
X147753Y627557D03*
X145750Y630254D03*
X148140Y660112D03*
X148487Y676041D03*
X147750Y687539D03*
X143823Y682907D03*
X134450Y682978D03*
X134777Y738726D03*
Y734726D03*
X134753Y726161D03*
X137070Y728012D03*
X134720Y742382D03*
X147290Y744113D03*
X145040Y740741D03*
X139600Y781281D03*
X135610Y784521D03*
X139680Y784596D03*
X149450Y780429D03*
X146150Y783820D03*
X141791Y788695D03*
Y791695D03*
X150787Y9246D03*
X158181Y11978D03*
X153863Y15176D03*
X164139Y13027D03*
X154592Y21173D03*
X150592Y20974D03*
X152412Y38112D03*
X152366Y42983D03*
X156255Y45743D03*
X160731Y41038D03*
X162350Y42984D03*
X152789Y53124D03*
X157659Y47891D03*
X161221Y89447D03*
X160040Y108844D03*
X162130Y129344D03*
X163518Y243987D03*
X162317Y249877D03*
X161918Y254287D03*
X160449Y259605D03*
X162484Y276599D03*
X158583Y285548D03*
X161918Y293869D03*
X161767Y287242D03*
X162181Y303075D03*
X161687Y310355D03*
X162063Y327940D03*
X162017Y324389D03*
X159564Y328013D03*
X161513Y317143D03*
X159285Y336220D03*
X164418Y348187D03*
X152058Y376016D03*
X160058Y375818D03*
X150524Y382808D03*
X165290Y385948D03*
X151820Y385554D03*
X150902Y379714D03*
X160886Y380294D03*
X160710Y384044D03*
X161640Y403286D03*
X162940Y406188D03*
X161577Y436834D03*
X151145Y469456D03*
X163377Y484538D03*
X152554Y494027D03*
X158406Y500016D03*
X154307Y507507D03*
X154517Y513931D03*
X154038Y511386D03*
X153967Y517186D03*
X159185Y531356D03*
X153731Y520734D03*
X162335Y521906D03*
X155400Y533436D03*
X154246Y527468D03*
X162335Y528206D03*
X159186Y534504D03*
X159185Y543953D03*
X155060Y545526D03*
X154945Y542383D03*
Y536083D03*
Y539233D03*
X159185Y547103D03*
X154900Y548682D03*
X162315Y553391D03*
X155109Y561153D03*
X154900Y551832D03*
X159186Y553402D03*
X157611Y557468D03*
X154410Y557990D03*
X154140Y577815D03*
X158430Y568437D03*
X162786Y568599D03*
X151900Y590454D03*
X153527Y597138D03*
X160699Y587904D03*
X153712Y610917D03*
X153330Y599935D03*
X153422Y603043D03*
X153955Y620760D03*
X157963Y643289D03*
X162668Y631897D03*
X162530Y643235D03*
Y636435D03*
X151915Y675068D03*
X155957Y674813D03*
X160112Y674990D03*
X165012Y675887D03*
X164812Y662579D03*
X151567Y687579D03*
X155650Y681515D03*
X161994Y678445D03*
X159590Y683050D03*
X157287Y678138D03*
X165167Y681311D03*
X152222Y678394D03*
X160101Y687962D03*
X163018Y684381D03*
X164092Y688014D03*
X150840Y682436D03*
X149860Y726626D03*
X154970Y736966D03*
X158881Y730784D03*
X162640Y743927D03*
X158970D03*
X154400Y744337D03*
X155230Y740259D03*
X160480Y777583D03*
X164630Y781222D03*
X153320Y783499D03*
X149810Y783858D03*
X179235Y7369D03*
X171310Y12450D03*
X171666Y7449D03*
X175280Y12401D03*
X174166Y7449D03*
X166639Y13027D03*
X165959Y27133D03*
X173110Y26877D03*
X180907Y27544D03*
X176090Y26906D03*
X177224Y49101D03*
X174724D03*
X177224Y51601D03*
X174724D03*
X172224Y49101D03*
Y54101D03*
X177224D03*
X174724D03*
X172224Y51601D03*
X169149Y50968D03*
X168040Y61462D03*
X177757Y88271D03*
X168308Y88412D03*
X177733Y91967D03*
X180990Y108770D03*
X177210Y97657D03*
X165690Y98835D03*
X171950Y105105D03*
X173900Y97662D03*
X177680Y101764D03*
X167127Y120603D03*
X174213Y120569D03*
X180510Y233307D03*
X174138Y243873D03*
X171320Y243601D03*
X167467Y243242D03*
X171668Y256287D03*
X173263Y262589D03*
X176301Y262624D03*
X167322Y255855D03*
X167698Y260617D03*
X178929Y262244D03*
X175110Y260412D03*
X175118Y274287D03*
X170617Y267326D03*
X175318Y278687D03*
X170510Y275522D03*
X174078Y271435D03*
X170829Y271452D03*
X178818Y274540D03*
X178941Y270160D03*
X177470Y294933D03*
X180254Y295023D03*
X175162Y293934D03*
X175659Y286984D03*
X176037Y309845D03*
X180254Y310663D03*
X175921Y301920D03*
X178921D03*
X178812Y324259D03*
X180342Y316469D03*
X175330Y318552D03*
X166189Y335285D03*
X167383Y341306D03*
X177359Y332553D03*
X174876Y336549D03*
X177604Y355155D03*
X177720Y352522D03*
X177029Y347811D03*
X177672Y358103D03*
X176058Y376568D03*
X168058Y376035D03*
X167951Y380551D03*
X175290Y389582D03*
X174500Y383383D03*
X178660Y388418D03*
X171934Y386364D03*
X175155Y380727D03*
X175663Y386424D03*
X176371Y404721D03*
X172760Y406540D03*
X170506Y424127D03*
X175993Y414924D03*
X173381Y424005D03*
X178232Y430642D03*
X178217Y435317D03*
X173151Y427552D03*
X172944Y448387D03*
X170444D03*
X177525Y451946D03*
X180125D03*
X178961Y448138D03*
X176220Y448247D03*
X171616Y467804D03*
X179857Y477790D03*
X168370D03*
X178085Y518755D03*
X168617Y525756D03*
X172371Y519783D03*
X174720Y531356D03*
X171606Y527511D03*
X178117Y528187D03*
X178082Y537654D03*
X178099Y550267D03*
X174105Y542290D03*
X167027Y539526D03*
Y536376D03*
X173217Y536556D03*
X169293Y562358D03*
X171053Y569411D03*
X175386Y569589D03*
X179740Y568951D03*
X166605Y587860D03*
X178416Y587849D03*
X179532Y600437D03*
X173432D03*
X165832Y600337D03*
Y606037D03*
Y613137D03*
X172532Y619537D03*
X178632Y619437D03*
X165832D03*
X167530Y631935D03*
X174479Y631986D03*
X177038Y647135D03*
X166388Y647435D03*
X171180Y652009D03*
X171270Y655650D03*
X179180Y675205D03*
X174761Y663816D03*
X168645Y688064D03*
X165628Y691289D03*
X167315Y684943D03*
X178982Y688631D03*
X178278Y705976D03*
Y701976D03*
Y697976D03*
X169268Y705304D03*
X169396Y701006D03*
X169268Y697399D03*
X169619Y693335D03*
X178278Y709976D03*
X171154Y715673D03*
X169531Y710542D03*
X171689Y728920D03*
X165599Y730476D03*
X177920Y739302D03*
X169350Y785470D03*
X172600Y780150D03*
X167350Y778074D03*
X173287Y791695D03*
Y788695D03*
X189235Y7369D03*
X191735D03*
X181735D03*
X194825Y10196D03*
X194861Y12952D03*
X183407Y27544D03*
X188634Y27860D03*
X184843Y88467D03*
X191930Y88507D03*
X196000Y95568D03*
X195473Y108767D03*
X184170Y95213D03*
X186060Y100103D03*
X183013Y98813D03*
X190100Y99701D03*
X196010Y125188D03*
X186730Y121202D03*
X188821Y232784D03*
X183550Y235060D03*
X193677Y243855D03*
X189192Y243061D03*
X184318Y247612D03*
X188899Y240208D03*
X195126Y249955D03*
X188899Y236808D03*
X194056Y256697D03*
X193735Y265857D03*
X188442Y252643D03*
X184829Y259139D03*
X188658Y256870D03*
X184117Y264852D03*
X181602Y262656D03*
X186873Y263697D03*
X185798Y256760D03*
X186873Y260697D03*
X194693Y259197D03*
Y262197D03*
X190918Y277687D03*
X185991Y279041D03*
X186118Y270787D03*
X188418Y278887D03*
X181818Y274540D03*
X194205Y271034D03*
X191860Y270148D03*
X183698Y285693D03*
X193557Y294428D03*
X187812Y286352D03*
X184812Y292979D03*
X186254Y295023D03*
X191054Y294424D03*
X183254Y295023D03*
X194771Y302176D03*
X193812Y308619D03*
X195254Y310663D03*
X184754Y302843D03*
X181921Y301920D03*
X191949Y301987D03*
X188810Y301998D03*
X187907Y308784D03*
X186254Y310663D03*
X193313Y325492D03*
X186296Y326366D03*
X186350Y317116D03*
X196476Y317042D03*
X193957Y317064D03*
X187404Y343998D03*
X192293Y340792D03*
X185195Y332852D03*
X184367Y337792D03*
X192230Y337322D03*
X186925Y355812D03*
X192519Y352761D03*
X186908Y352760D03*
X184058Y376479D03*
X194231Y390267D03*
X184927Y383876D03*
X185074Y380726D03*
X194330Y396425D03*
X192676Y402961D03*
X182771Y424013D03*
X185271D03*
X182771Y421513D03*
X185271D03*
X182132Y418327D03*
X182877Y430662D03*
X182879Y435312D03*
X192069Y444852D03*
X184523Y441915D03*
X181923Y445044D03*
Y442544D03*
X185747Y487664D03*
X193500Y489796D03*
X186417Y518526D03*
X186467Y514036D03*
X184920Y508626D03*
X181231Y512455D03*
X181232Y515607D03*
X187417Y508756D03*
X189007Y514846D03*
X181232Y528205D03*
X188640Y530667D03*
X187875Y534128D03*
X181232Y543953D03*
X184384Y537656D03*
X181232Y537654D03*
X184384Y543955D03*
X188927Y537836D03*
X190434Y546870D03*
X188383Y556895D03*
X184386Y553406D03*
X181232Y553402D03*
X188654Y573395D03*
X191500Y571956D03*
X181330Y587535D03*
X185032Y606737D03*
X184932Y600537D03*
X185032Y612937D03*
X184932Y619437D03*
X182353Y631612D03*
X196410Y650155D03*
X187410Y649715D03*
Y659705D03*
X191910Y650055D03*
X188200Y672526D03*
X196463Y685036D03*
X182163Y684555D03*
X194508Y704476D03*
X187798Y704513D03*
X181744Y694829D03*
X190375Y695624D03*
X185440Y712499D03*
X196144Y712602D03*
X187744Y708356D03*
X191930Y712624D03*
X196079Y723943D03*
X194440Y735623D03*
X189940Y735681D03*
X185440D03*
X182674Y730521D03*
X191150Y724108D03*
X186164Y724134D03*
X204785Y13762D03*
X201849Y15292D03*
X198577Y15374D03*
X199016Y88434D03*
X206103Y88207D03*
X202560Y107797D03*
X210203Y108457D03*
X206273Y98364D03*
X200480Y97687D03*
X212423Y104957D03*
X199993Y103637D03*
X207070Y179744D03*
X207041Y184502D03*
X212020Y234359D03*
X198296Y232699D03*
X211935Y244085D03*
X198685Y240785D03*
X211935Y237385D03*
Y240785D03*
X205566Y243497D03*
X211028Y255696D03*
X210333Y265197D03*
X208129Y257519D03*
X206144Y252477D03*
X208289Y263639D03*
X210305Y262289D03*
X201994Y261248D03*
X202402Y263713D03*
X200469Y259139D03*
X201518Y265990D03*
X208226Y269697D03*
X201667Y274542D03*
X199509Y278094D03*
X209449Y281098D03*
X210303Y268227D03*
X206299Y281098D03*
X210303Y271227D03*
X203149Y281098D03*
X201518Y268887D03*
X209449Y287398D03*
Y290548D03*
X203149Y287398D03*
X206299D03*
X196867Y294342D03*
X206299Y290548D03*
X206319Y296863D03*
X203149Y290548D03*
X206299Y293698D03*
Y312598D03*
X198880Y310245D03*
X196812Y308619D03*
X206299Y306298D03*
Y303148D03*
X209449Y312598D03*
X203166Y312577D03*
X202525Y299358D03*
X209300Y322800D03*
X207310Y330149D03*
X206299Y315748D03*
X203058Y315593D03*
X200211Y321446D03*
X200572Y323920D03*
X208700Y328000D03*
X200590Y327615D03*
X208485Y332356D03*
X200905Y333776D03*
X201489Y336207D03*
Y339107D03*
X197243Y344518D03*
X206817Y358874D03*
X207274Y353124D03*
X198987Y353137D03*
X206657Y356116D03*
X202823Y376922D03*
X197938Y376839D03*
X200439Y390168D03*
X203880Y385272D03*
X205790Y387003D03*
X200488Y396425D03*
X210880Y402359D03*
X206380Y402201D03*
X200039Y448750D03*
Y451350D03*
X197809Y469953D03*
X200434Y478345D03*
X200459Y487253D03*
X208710Y500856D03*
X211379Y501904D03*
X208050Y528883D03*
X209886Y539962D03*
X201509Y539853D03*
X207309Y539953D03*
X199709Y551653D03*
X208109Y551053D03*
X202486Y551130D03*
X210040Y576893D03*
X209590Y580893D03*
X197230Y595335D03*
X198890Y584105D03*
X207178Y591595D03*
X211760Y610915D03*
X207476Y608936D03*
X207010Y602472D03*
X196907Y605012D03*
X197030Y598535D03*
X211862Y617709D03*
X197230Y615435D03*
X197130Y626135D03*
X200910Y659735D03*
Y650155D03*
X205410Y650035D03*
X209238Y674373D03*
X202450Y663633D03*
X199510Y663158D03*
X202518Y673273D03*
X197889Y671226D03*
X210824Y692266D03*
X197582Y703474D03*
X200692Y704081D03*
X211236Y695586D03*
X197243Y697899D03*
X210023Y712842D03*
X201663Y712694D03*
X198940Y712499D03*
X205440Y712510D03*
X211897Y723870D03*
X201411Y708231D03*
X212440Y735829D03*
X198940Y735681D03*
X207940D03*
X203440D03*
X205883Y724373D03*
X200817Y724180D03*
X200846Y788695D03*
Y791695D03*
X225990Y21219D03*
X221990D03*
X222290Y45504D03*
X226290D03*
X221310Y51103D03*
X225310D03*
X221600Y66317D03*
X225600D03*
X213190Y88414D03*
X220276Y88440D03*
X214573Y93771D03*
X222983Y91587D03*
X219095Y108675D03*
X217040Y103121D03*
X226713Y122007D03*
X217135Y244085D03*
X226010Y240342D03*
X217135Y237385D03*
X227517Y244187D03*
X219772Y252659D03*
X215761Y252833D03*
X224794Y256754D03*
X218153Y260697D03*
Y263697D03*
X223929Y263639D03*
X225973Y262197D03*
X216109Y265139D03*
Y262139D03*
X218508Y256664D03*
X225973Y265197D03*
Y259197D03*
X225199Y281098D03*
X216109Y274139D03*
X212599Y281098D03*
X218899D03*
X224357Y273228D03*
X216184Y268587D03*
X216109Y271139D03*
X215749Y281098D03*
X213138Y274187D03*
X212599Y290548D03*
X225199Y287398D03*
X212599Y293698D03*
X222049Y290548D03*
X225160Y293676D03*
X225199Y290548D03*
Y284248D03*
X222049Y287398D03*
X212599D03*
X215749Y290548D03*
Y293698D03*
Y287398D03*
X225199Y309448D03*
Y299998D03*
Y303148D03*
X222049Y309448D03*
X212599Y299998D03*
Y303148D03*
X222049Y312598D03*
X218899Y309448D03*
X222049Y303148D03*
X225199Y306298D03*
Y312598D03*
X222049Y306298D03*
X218899D03*
X222049Y299998D03*
X212610Y306305D03*
X218899Y299998D03*
Y303148D03*
X218947Y312617D03*
X215100Y322700D03*
X217129Y327207D03*
X215085Y325649D03*
X212600Y319100D03*
X217129Y324207D03*
X224949Y328707D03*
X225199Y315748D03*
X224585Y322992D03*
X224711Y325922D03*
X217129Y336207D03*
X217067Y339542D03*
X217129Y333207D03*
X223010Y344242D03*
X223166Y338842D03*
X222911Y333155D03*
X224996Y334617D03*
X223095Y336241D03*
X221280Y340579D03*
X228057Y352837D03*
X222777Y353066D03*
X214888Y352909D03*
X222974Y356134D03*
X223561Y385108D03*
X214008Y385165D03*
X221438Y390655D03*
X224108Y388029D03*
X216633Y384989D03*
X213710Y402237D03*
X224730Y418003D03*
X221406Y436560D03*
X227816Y442675D03*
X218483Y442550D03*
X221858Y442300D03*
X225024Y442467D03*
X226276Y460704D03*
X213994Y466054D03*
X228242Y463681D03*
X223953Y463550D03*
X212809Y479053D03*
X215409Y479253D03*
X223786Y476638D03*
X216209Y488853D03*
X213209D03*
X224209Y494928D03*
X219309Y489353D03*
X222209D03*
X214626Y516492D03*
X227326Y505741D03*
X227329Y508894D03*
X223709Y505353D03*
X216564Y528902D03*
X214118Y528583D03*
X218751Y543835D03*
X221591Y563371D03*
X223561Y561475D03*
X223453Y578087D03*
X216590Y570850D03*
X220428Y580271D03*
X218859Y593093D03*
X225100Y597453D03*
X219296Y604811D03*
X215604Y621977D03*
X215985Y633977D03*
X215948Y629977D03*
X221129Y642363D03*
X218308Y635939D03*
X225179Y642614D03*
X215768Y671993D03*
X225237Y671772D03*
X212635Y665604D03*
X224289Y680081D03*
X224360Y684366D03*
X213365Y692151D03*
X224060Y690317D03*
X224336Y687758D03*
X223707Y695436D03*
X220580Y692876D03*
X223741Y700554D03*
X221340Y697995D03*
X226610Y713482D03*
X227650Y720791D03*
X224410Y719970D03*
X216940Y736063D03*
X221440Y735934D03*
X225940Y724061D03*
Y733671D03*
Y736437D03*
X220532Y788695D03*
Y791695D03*
X212658D03*
Y788695D03*
X241990Y21219D03*
X229990D03*
X242290Y45504D03*
X230290D03*
X229310Y51103D03*
X233290Y51045D03*
X237310Y50983D03*
X241310D03*
X237600Y66317D03*
X241600D03*
X229600D03*
X233600D03*
X236360Y93931D03*
X236812Y88698D03*
X229725Y88719D03*
X235113Y91307D03*
X231013Y91547D03*
X243730Y103057D03*
X240355Y108757D03*
X239500Y100925D03*
X231910Y105731D03*
X235190Y96905D03*
X230643Y108497D03*
X234243Y100156D03*
X237773Y103607D03*
X233268Y121742D03*
X230749Y160807D03*
X230650Y164566D03*
X230890Y169424D03*
X231000Y173381D03*
X230100Y187389D03*
X230140Y197240D03*
X231710Y243642D03*
X231749Y265139D03*
X239569Y257639D03*
X241613Y262197D03*
X239569Y266639D03*
X241613Y259197D03*
X237594Y252754D03*
X241613Y265197D03*
X233793Y266697D03*
Y257697D03*
X233904Y252772D03*
X239569Y263639D03*
X233793Y263697D03*
X231749Y262139D03*
X233793Y260697D03*
X239569Y260639D03*
X231749Y259139D03*
X240910Y274742D03*
X233793Y269697D03*
X234649Y281098D03*
X237865Y281131D03*
X239569Y269639D03*
X232118Y271587D03*
X241613Y271197D03*
Y268197D03*
X228821Y274197D03*
X231648Y274243D03*
X237799Y290548D03*
Y284248D03*
X231499Y287398D03*
X231450Y290583D03*
X237760Y293692D03*
X237799Y287398D03*
X240949Y290548D03*
Y287398D03*
X231499Y284248D03*
Y296848D03*
Y293698D03*
X240949Y296848D03*
X237800Y299998D03*
X231499Y309448D03*
Y299998D03*
X237799Y312598D03*
X231499D03*
X240949Y309448D03*
X237799Y303148D03*
X234649D03*
X237799Y306298D03*
X240949Y299998D03*
Y303148D03*
X241258Y319123D03*
X231567Y321742D03*
X232782Y327096D03*
X230725Y325649D03*
X238545Y327149D03*
X240374Y328960D03*
X240511Y325517D03*
X240692Y344204D03*
X233055Y339936D03*
X230725Y331649D03*
X238548Y333149D03*
X230725Y334547D03*
X240598Y334642D03*
X240218Y338010D03*
X231144Y338225D03*
X238560Y336136D03*
X232769Y333207D03*
X232804Y336181D03*
X239290Y340428D03*
X233697Y353961D03*
X238084Y355992D03*
X243940Y390885D03*
X236687Y385234D03*
X232172Y388814D03*
X228729Y385227D03*
X241451Y392147D03*
X236412Y387722D03*
X231223Y391424D03*
X239546Y390528D03*
X239228Y393291D03*
X232647Y396011D03*
X228906Y424560D03*
X228713Y416525D03*
Y419525D03*
X240599Y440053D03*
X231870Y439511D03*
X228906Y433560D03*
Y427560D03*
Y436560D03*
X231885Y442252D03*
X235319Y464362D03*
X233309Y472553D03*
X237609Y472453D03*
X241909Y472553D03*
X233626Y502591D03*
X230476D03*
X243075D03*
X230476Y505741D03*
X236776Y508891D03*
Y518339D03*
X233626Y508891D03*
Y515190D03*
X230476D03*
X233626Y518339D03*
X236776Y512040D03*
X243075Y508891D03*
X230476D03*
X236776Y515190D03*
X230476Y518339D03*
Y512040D03*
X233626D03*
X239925Y518339D03*
X233626Y521489D03*
X236776Y534087D03*
X233626Y527788D03*
X230476Y534087D03*
X236776Y521489D03*
Y527788D03*
X233626Y524639D03*
X236776D03*
X230476D03*
X233626Y534087D03*
X239925Y527788D03*
Y524639D03*
X230476Y527788D03*
Y521489D03*
X239925Y534087D03*
Y521489D03*
X233626Y543536D03*
X239925Y540386D03*
Y543536D03*
X236776Y540386D03*
Y537236D03*
X230476D03*
Y543536D03*
Y540386D03*
X233626D03*
X236776Y543536D03*
X233626Y537236D03*
X239925D03*
X243075Y559284D03*
Y552984D03*
X231209Y566282D03*
X242915Y576539D03*
X243209Y574018D03*
X239269Y597128D03*
X229809Y583627D03*
X234500Y637685D03*
X243743Y636514D03*
X241670Y652558D03*
X233584Y652519D03*
X239168Y671672D03*
X240493Y692678D03*
X239084Y696252D03*
X233954Y697395D03*
X236120Y704173D03*
X238348Y712469D03*
X239210Y720040D03*
X243900Y724662D03*
X239440Y736140D03*
X230440Y736412D03*
X234940Y724325D03*
Y733355D03*
X243940Y736412D03*
X239500Y733523D03*
X230440Y724242D03*
X234940Y736392D03*
X240217Y788695D03*
Y791695D03*
X232343D03*
Y788695D03*
X249990Y21219D03*
X245990D03*
X257270Y29334D03*
X250290Y45504D03*
X246290D03*
X258103Y53688D03*
X257500Y56117D03*
X245310Y50867D03*
X249300Y50862D03*
X253490Y53736D03*
X253810Y63244D03*
X245600Y66317D03*
X249600D03*
X246073Y92197D03*
X256573Y94097D03*
X247870Y105821D03*
X259030Y123727D03*
X259443Y120773D03*
X255287Y226709D03*
X254181Y234521D03*
X257950Y236924D03*
X255209Y260639D03*
X255359Y266557D03*
X247389Y259139D03*
X256553Y256881D03*
X249433Y263697D03*
Y260697D03*
X256916Y262609D03*
X247389Y262139D03*
X257253Y259197D03*
X259518Y252358D03*
X249433Y257697D03*
X246467Y255442D03*
X257046Y279607D03*
X255205Y272755D03*
X244109Y277996D03*
X244099Y281098D03*
X254234Y281622D03*
X250399Y281098D03*
X247389Y268139D03*
X257253Y271197D03*
Y268197D03*
X250399Y296848D03*
X253611Y293765D03*
X250399Y290548D03*
X244099Y284248D03*
X250399D03*
X244099Y293698D03*
X244110Y290505D03*
X257447Y287117D03*
X244099Y287398D03*
X250399D03*
X253549Y290548D03*
X247249Y296848D03*
X244099D03*
X258380Y295984D03*
X254334Y298728D03*
X247249Y303148D03*
X244118Y309387D03*
X254007Y306819D03*
X244118Y303187D03*
X257057Y309636D03*
X244099Y299998D03*
X247249Y306298D03*
X257418Y303533D03*
X258590Y311560D03*
X247281Y315727D03*
X247290Y327694D03*
X254631Y324716D03*
X254998Y329779D03*
X256276Y322652D03*
X247789Y322910D03*
X254905Y327213D03*
X250401Y315713D03*
X253710Y315669D03*
X248509Y339207D03*
X254819Y332435D03*
X250466Y344381D03*
X245691Y341215D03*
X247218Y333049D03*
X255009Y338318D03*
X246685Y337357D03*
X255124Y335244D03*
X247025Y330512D03*
X251334Y352857D03*
X259444Y354291D03*
X246265Y355855D03*
X256588Y359005D03*
X250661Y384780D03*
X256532Y384895D03*
X247065Y385398D03*
X244546Y385315D03*
X253762Y385255D03*
X247797Y406029D03*
X250297D03*
X252797D03*
X245297D03*
X244196Y419610D03*
Y417010D03*
X258798Y417594D03*
X254798Y417728D03*
X244196Y427610D03*
Y425010D03*
Y433010D03*
Y435610D03*
X252670Y443592D03*
X255509Y472253D03*
X246109Y472465D03*
X251309Y472553D03*
X252524Y502591D03*
X255673D03*
X249374D03*
X246224D03*
X245609Y517182D03*
X255673Y512040D03*
X252524D03*
X255673Y508891D03*
Y505741D03*
X249374D03*
Y508891D03*
X252524Y505741D03*
Y508891D03*
X249374Y512040D03*
X246224D03*
X252524Y527789D03*
Y524639D03*
X255673Y534088D03*
X252524D03*
X249374D03*
X255673Y524639D03*
Y527789D03*
X249374D03*
Y524639D03*
X255673Y537237D03*
X249374D03*
X252524D03*
X255673Y540387D03*
X249374D03*
X252524D03*
Y549835D03*
X255673D03*
X249374D03*
X255673Y565580D03*
Y552984D03*
Y556133D03*
Y559282D03*
Y562431D03*
X249344Y552984D03*
Y556134D03*
X246224Y559284D03*
Y556134D03*
Y562434D03*
X252554Y559314D03*
X252036Y582131D03*
X245860Y575049D03*
X249909Y568653D03*
X249541Y587156D03*
X253709Y586128D03*
X249541Y583156D03*
X253187Y596382D03*
X246639Y608378D03*
Y605778D03*
X249640Y602519D03*
X246639Y624378D03*
Y621778D03*
Y616378D03*
Y613778D03*
X249013Y628514D03*
X251803Y636704D03*
X254773Y644424D03*
X254303Y636744D03*
X256463Y639364D03*
X252173Y644344D03*
X249083Y636664D03*
X256513Y642494D03*
X246553Y636684D03*
X252486Y671772D03*
X253398Y692357D03*
X250795Y703150D03*
X251451Y697465D03*
X254940Y712381D03*
X255310Y715915D03*
X248530Y721829D03*
X250630Y719457D03*
X253340Y724726D03*
X248440Y736163D03*
X257440Y736041D03*
X252940Y736318D03*
X248770Y724631D03*
X252940Y733567D03*
X252028Y791695D03*
X273660Y23037D03*
X268579Y19365D03*
X265934Y16522D03*
X273645Y27712D03*
X268372Y40782D03*
X265872D03*
X272010Y40553D03*
X274510D03*
X273873Y63167D03*
X269793D03*
X261750Y75886D03*
X274580Y74281D03*
X269920Y74318D03*
X272440Y76177D03*
X268080Y76416D03*
X267703Y89397D03*
X271133Y92787D03*
X265830Y102566D03*
X264210Y96914D03*
X273973Y97645D03*
X263683Y99902D03*
X268702Y107928D03*
X269010Y121648D03*
X269620Y243240D03*
X269192Y248209D03*
X272242Y244842D03*
X272620Y238653D03*
X271458Y241347D03*
X266187Y249852D03*
X267020Y257079D03*
X263029Y259139D03*
X265073Y266697D03*
X263029Y265139D03*
X271811Y256687D03*
X271898Y263173D03*
X260068Y262187D03*
X263268Y262370D03*
X269263Y252800D03*
X271944Y278363D03*
X264386Y280407D03*
X265944Y278363D03*
X274886Y272587D03*
X273386Y280407D03*
X270444Y270543D03*
X271886Y272587D03*
X265886Y271718D03*
X268886Y272587D03*
X268944Y278363D03*
X263029Y271139D03*
Y268139D03*
X273444Y270543D03*
X274944Y278363D03*
X270386Y280407D03*
X267386D03*
X262886Y288227D03*
X264386Y296047D03*
X267386D03*
X265825Y293987D03*
X268867Y293942D03*
X262904Y293850D03*
X268943Y291086D03*
X265768Y287546D03*
X273444Y286183D03*
X273618Y295387D03*
X271811Y303313D03*
X271944Y309643D03*
X262944D03*
X261386Y311687D03*
X260045Y309615D03*
X268944Y309643D03*
X265944Y309640D03*
X269380Y302736D03*
X264501Y303109D03*
X266939Y303281D03*
X274303Y303413D03*
X259820Y303800D03*
X267268Y311642D03*
X264287Y311687D03*
X270518Y311637D03*
X274832Y309687D03*
X262035Y322679D03*
X267883Y325837D03*
X265318Y326487D03*
X270525Y325754D03*
X262201Y328491D03*
X272967Y325842D03*
X275517D03*
X267030Y330147D03*
X268502Y344181D03*
X263576Y340898D03*
X274701Y333804D03*
X270326Y335795D03*
X270485Y339030D03*
X264015Y336151D03*
X267943Y339617D03*
X270293Y330540D03*
X272964Y330669D03*
X262379Y338103D03*
X262247Y334502D03*
X270071Y333021D03*
X272263Y334222D03*
X272352Y340900D03*
X269456Y355353D03*
X269117Y352876D03*
X273477Y385100D03*
X261663Y385193D03*
X267993Y390695D03*
X266882Y388165D03*
X261539Y387755D03*
X264421Y384812D03*
X275497Y390758D03*
X262798Y417886D03*
X271720Y422587D03*
X265532Y422648D03*
X269630Y424884D03*
X275256Y445753D03*
X271035Y443051D03*
X273735Y443034D03*
X273509Y471649D03*
X260609Y472453D03*
X264909Y472553D03*
X269109Y472353D03*
X275452Y483219D03*
X265122Y502591D03*
X267741Y491608D03*
X274582Y502591D03*
X271402Y499441D03*
X271429Y496295D03*
X261972Y502591D03*
X268272Y505741D03*
Y508891D03*
Y512040D03*
X271422D03*
X265121Y508891D03*
X261972D03*
Y505741D03*
X265122Y512040D03*
X261972D03*
X265122Y505741D03*
X261972Y521489D03*
X268272Y534088D03*
X265122D03*
X261972D03*
X268272Y524639D03*
Y527789D03*
X265122D03*
Y524639D03*
X261972D03*
Y527789D03*
X268272Y521489D03*
X265122D03*
X268272Y540387D03*
X265122D03*
X261972D03*
X265122Y537237D03*
X268272D03*
X261972D03*
X268272Y549836D03*
X271421D03*
X265122D03*
X261972D03*
X274571Y552985D03*
X265122D03*
X268272Y559291D03*
X271422Y562434D03*
X271421Y556135D03*
X271422Y559291D03*
X261973Y552985D03*
X262009Y556153D03*
X261972Y562431D03*
X271422Y565583D03*
X271421Y552985D03*
X274572Y556142D03*
X269609Y588653D03*
X268717Y606015D03*
X261967Y608638D03*
Y605638D03*
X260064Y602993D03*
X261967Y614638D03*
X263467Y626638D03*
X261967Y617638D03*
X263467Y623638D03*
X273938Y633084D03*
X273674Y640095D03*
X273548Y636471D03*
X270040Y651241D03*
X269640Y655290D03*
X270430Y665576D03*
X269709Y672575D03*
X265913Y671772D03*
X270140Y691038D03*
X272460Y687889D03*
X265300Y702131D03*
X272650Y693742D03*
X269410Y706003D03*
X270940Y722080D03*
X275440Y735626D03*
X261940Y735878D03*
X266440Y736030D03*
X270940Y735642D03*
X271713Y788695D03*
Y791695D03*
X259902D03*
X280699Y13908D03*
X278199D03*
X282180Y10253D03*
X285703Y9813D03*
X278660Y10073D03*
X278305Y23057D03*
X280699Y16408D03*
X278199D03*
X278307Y27707D03*
X287476Y37125D03*
X277472Y34959D03*
Y37459D03*
X280072Y34330D03*
X275766Y52772D03*
X275800Y50212D03*
X290823Y63167D03*
X282023D03*
X277853D03*
X287270Y75018D03*
X283870Y74724D03*
X279100Y74447D03*
X289738Y76173D03*
X285543Y76867D03*
X281400Y75938D03*
X276969Y76247D03*
X277000Y88323D03*
X286263Y88677D03*
X287595Y106109D03*
X279010Y104889D03*
X286710Y95717D03*
X281200Y98369D03*
X289720Y96094D03*
X278760Y101061D03*
X287599Y108831D03*
X278880Y108482D03*
X278354Y244281D03*
X290154Y244007D03*
X285934Y243931D03*
X282178Y244005D03*
X289254Y255688D03*
X286492Y258364D03*
X283660Y251542D03*
X281954Y255588D03*
X288954Y260788D03*
X276328Y264687D03*
X281945Y260231D03*
X279336Y264795D03*
X277886Y272587D03*
X280886D03*
X286010Y276042D03*
X282867Y281142D03*
X276444Y270543D03*
X282309Y270435D03*
X279444Y270543D03*
X277944Y278363D03*
X279386Y280407D03*
X276386D03*
X276507Y295816D03*
X286132Y285953D03*
X278918Y286887D03*
X276444Y286183D03*
X279386Y311687D03*
X285890Y311357D03*
X277020Y302298D03*
X282337Y308217D03*
X281859Y310862D03*
X277816Y309678D03*
X279754Y303269D03*
X276386Y311687D03*
X281461Y321744D03*
X280776Y326412D03*
X286071Y329184D03*
X278067Y325842D03*
X282167Y324242D03*
X288466Y325343D03*
X285704Y321809D03*
X275660Y338857D03*
X281212Y338079D03*
X277288Y334282D03*
X282234Y333792D03*
X285794Y339063D03*
X279718Y333694D03*
X275602Y343811D03*
X290190Y352480D03*
X278943Y346914D03*
X277718Y352687D03*
X282818D03*
X286711Y352668D03*
X283140Y346082D03*
X286020Y356454D03*
X279863Y367513D03*
X276687Y385100D03*
X288687Y385290D03*
X281864Y386178D03*
X284687Y386769D03*
X288220Y389630D03*
X283820Y396266D03*
X281142Y402379D03*
X280730Y393856D03*
X276400Y422341D03*
X280010Y422279D03*
X281190Y424966D03*
X278080Y424760D03*
X286210Y444926D03*
X289630Y444828D03*
X283212Y442286D03*
X286100Y442298D03*
X288742Y442090D03*
X287970Y446705D03*
X282000Y444966D03*
X279112Y444954D03*
X279990Y442071D03*
X276809Y471853D03*
X280210Y460762D03*
X287567Y470649D03*
Y467649D03*
X280380Y467284D03*
X278990Y464793D03*
X284332Y472834D03*
X282298Y483803D03*
X277470Y481197D03*
X280970D03*
X284024Y499445D03*
X287173D03*
X288009Y495653D03*
X277712Y502595D03*
X290323Y534092D03*
X280874D03*
X287174D03*
X284024D03*
X277725D03*
Y527792D03*
Y521493D03*
X280874Y537241D03*
Y543541D03*
X284024D03*
X287174Y540391D03*
Y543541D03*
X290323Y540391D03*
Y543541D03*
X277725Y540391D03*
Y543541D03*
Y537241D03*
X290322Y549841D03*
X280872D03*
X287174Y559289D03*
X290323Y565589D03*
X284024Y565588D03*
X287174D03*
X290323Y559289D03*
Y562439D03*
Y556140D03*
X287174Y562438D03*
X280874D03*
X284024D03*
Y559289D03*
X277725Y552989D03*
X280874Y559289D03*
X277725Y556135D03*
Y559289D03*
X287174Y556139D03*
X280874Y552989D03*
X284024Y556139D03*
X287174Y552989D03*
X284024D03*
X280874Y556139D03*
X291066Y590488D03*
Y593088D03*
X278109Y589238D03*
X289171Y661908D03*
X279090Y668504D03*
X279785Y663876D03*
X289365Y665845D03*
X288880Y689467D03*
X278350Y687309D03*
X275560Y697804D03*
X279060Y693306D03*
X284760Y707022D03*
X278341Y717269D03*
X289060Y722193D03*
X281830Y722184D03*
X289150Y718548D03*
X279940Y724126D03*
X289240Y724687D03*
X283990Y734977D03*
X284020Y724956D03*
X279587Y791695D03*
X295307Y41260D03*
X295390Y44017D03*
X295610Y50299D03*
X295560Y52907D03*
X294903Y63167D03*
X306693D03*
X303053D03*
X298883D03*
X292313Y76345D03*
X305880Y76361D03*
X299220Y76196D03*
X302953Y76167D03*
X295867Y76567D03*
X296093Y88477D03*
X302853Y89057D03*
X294800Y100593D03*
X295490Y97209D03*
X302370Y95215D03*
X293505Y94965D03*
X303220Y98397D03*
X299590Y121289D03*
X299850Y124708D03*
X293873Y130357D03*
X300118Y250987D03*
X296176Y249585D03*
X295910Y266706D03*
X295110Y262961D03*
X300477Y265010D03*
X300310Y253842D03*
Y257242D03*
X295307Y275439D03*
X294510Y280709D03*
X301473Y282650D03*
X301723Y279150D03*
X297782Y291966D03*
X295010Y286767D03*
X301182Y291966D03*
X305132Y286867D03*
X298332D03*
X301732D03*
X297668Y300709D03*
X294888Y304456D03*
X294781Y309788D03*
X301795Y310398D03*
X296639Y308057D03*
X305250Y310342D03*
X300201Y300874D03*
X303197Y304297D03*
X295200Y321473D03*
X294596Y328129D03*
X297073Y329159D03*
X294218Y343587D03*
X294888Y335326D03*
X298452Y340487D03*
X306820Y342146D03*
X303759Y331478D03*
X294618Y348287D03*
X293467Y352442D03*
X305446Y359450D03*
X298202Y374572D03*
X303171Y374224D03*
X291686Y375177D03*
X295388Y375644D03*
X303722Y385367D03*
X291382Y385457D03*
X291860Y442927D03*
X292170Y445986D03*
X301240Y470885D03*
X291327Y466811D03*
X306220Y477125D03*
X303631Y475607D03*
Y472607D03*
X301209Y488853D03*
X303709Y489353D03*
X300209Y495853D03*
X296913Y514460D03*
X301457Y513837D03*
X293473Y534092D03*
Y540391D03*
Y565589D03*
Y562439D03*
Y559290D03*
X295047Y554565D03*
X291357Y586128D03*
X299121Y597542D03*
X306229Y600263D03*
X305602Y620685D03*
Y618185D03*
X299629Y623877D03*
X299090Y634421D03*
X302870Y633981D03*
X297162Y642065D03*
X303110Y639381D03*
X305200Y652883D03*
X301070Y655920D03*
X292850Y656359D03*
X304870Y655747D03*
X306294Y659156D03*
X301360Y652183D03*
X306294Y667156D03*
Y663156D03*
Y675156D03*
Y671156D03*
X294120Y668391D03*
X297770Y674720D03*
X305979Y691156D03*
X306145Y683156D03*
X305979Y687156D03*
X306294Y679156D03*
X292970Y682450D03*
X301696Y701851D03*
Y699351D03*
X293286Y703504D03*
X305990Y697189D03*
X303681Y714421D03*
X305213Y720393D03*
X296885Y718059D03*
X297223Y715523D03*
X291318Y713875D03*
X291790Y735976D03*
X306540Y724266D03*
X297940Y724377D03*
X302660Y736359D03*
X298160Y736489D03*
X302810Y733807D03*
X295700Y733133D03*
X291398Y792234D03*
X299272Y791695D03*
X317334Y10955D03*
X322640Y9774D03*
X317334Y28955D03*
X314640Y63167D03*
X310483D03*
X318543D03*
X322713D03*
X318910Y74595D03*
X314310Y74540D03*
X307740Y74263D03*
X309730Y76232D03*
X321283Y76327D03*
X316623Y76047D03*
X312402Y76587D03*
X314830Y92851D03*
X312183Y88837D03*
X321463Y88517D03*
X315083Y90207D03*
X312223Y96407D03*
X317970Y95961D03*
X313583Y122387D03*
X311420Y250230D03*
X315410Y258656D03*
X312680Y258353D03*
X307204Y304212D03*
X310623Y313589D03*
X313123D03*
X320623D03*
X318123D03*
X315623D03*
X321643Y321928D03*
X309143D03*
X311643D03*
X314143D03*
X316643D03*
X319143D03*
X322765Y327721D03*
X322210Y336696D03*
X319323Y338320D03*
X309510Y344127D03*
X313980Y335813D03*
X321130Y342418D03*
X309190Y336959D03*
X319666Y354376D03*
X319807Y346376D03*
X321150Y357730D03*
X309131Y374573D03*
X314860Y367656D03*
X322255Y371935D03*
X319363Y372149D03*
X315383Y387863D03*
X307116Y385979D03*
X315533Y384749D03*
X321144Y399643D03*
X318644D03*
X316190Y413299D03*
X311610Y432528D03*
X313530Y436460D03*
X315940Y438104D03*
X319478Y429389D03*
X308220Y432552D03*
X322599Y432505D03*
X309440Y426404D03*
X318950Y432473D03*
X316963Y467655D03*
X321357Y456709D03*
X307800Y467859D03*
X310380Y473942D03*
X316956Y478833D03*
X321246Y472669D03*
X315980Y472128D03*
X307670Y473605D03*
X318968Y536052D03*
X318678Y540966D03*
X321828Y541682D03*
X313888Y566003D03*
X313141Y550821D03*
X313075Y553755D03*
X313108Y556556D03*
X313275Y559590D03*
X316788Y572903D03*
X316688Y569603D03*
X313347Y570695D03*
X319135Y591407D03*
X313419Y594040D03*
X313227Y590232D03*
X310919Y594040D03*
X310627Y590232D03*
X315957Y594127D03*
X312641Y611556D03*
X307996Y611536D03*
X312656Y606881D03*
X307994Y606886D03*
X308102Y620685D03*
Y618185D03*
X320367Y618071D03*
X314910Y627222D03*
X317722Y614646D03*
X317492Y618193D03*
X307574Y633762D03*
X314940Y642067D03*
X310453Y642451D03*
X320360Y642275D03*
X311382Y635432D03*
X314790Y652049D03*
X317130Y653628D03*
X314614Y690767D03*
X322440Y700130D03*
X320110Y703093D03*
X313230Y702465D03*
X317580Y719996D03*
X307113Y713003D03*
X321820Y712680D03*
X311990Y717601D03*
X309531Y714298D03*
X312972Y712693D03*
X318090Y712846D03*
X307940Y736445D03*
X311440Y735831D03*
X315940Y735924D03*
X320440Y736031D03*
X307280Y733705D03*
X311083Y791871D03*
X318957Y791695D03*
X323334Y12377D03*
X323871Y25812D03*
Y16812D03*
Y19812D03*
Y28812D03*
X336316Y31815D03*
X327117Y31840D03*
X326353Y63167D03*
X323640Y74393D03*
X326140Y76196D03*
X336024Y88176D03*
X329643Y89887D03*
X324070Y88861D03*
X336340Y99265D03*
X327950Y101057D03*
X323000Y94337D03*
X327430Y108208D03*
X332453Y122297D03*
X323032Y122237D03*
X336495Y290569D03*
X331376Y299883D03*
X328526Y308696D03*
X334478Y299604D03*
X323123Y313589D03*
X333540Y315590D03*
X332700Y333089D03*
X333726Y353801D03*
X333440Y349221D03*
X323040Y354485D03*
X334816Y367787D03*
X337316Y367758D03*
X337330Y372679D03*
X334816Y372609D03*
X326282Y399743D03*
X323644Y399643D03*
X325749Y418701D03*
X328290Y424304D03*
X324940Y413899D03*
X336218Y424850D03*
X325180Y432577D03*
X334420Y428660D03*
X336088Y454511D03*
X326190Y448621D03*
X329120Y449203D03*
X327780Y445819D03*
X331360Y447306D03*
X325040Y480129D03*
X336010Y531598D03*
X324927Y546013D03*
X328592Y541146D03*
X328352Y545412D03*
X325588Y541447D03*
X323154Y556367D03*
Y558867D03*
Y553867D03*
X337550Y558618D03*
Y556118D03*
Y553618D03*
X323088Y561503D03*
X323188Y564503D03*
X330388Y565803D03*
X332388Y567703D03*
X328088Y567503D03*
X329260Y603381D03*
X328930Y611691D03*
X329110Y623514D03*
X330440Y639504D03*
X328032Y642674D03*
X332710Y642694D03*
X328760Y657144D03*
X327540Y653432D03*
X335610Y658177D03*
X332747Y655636D03*
X332190Y659883D03*
X329912Y662383D03*
X335915Y675011D03*
X335390Y667895D03*
X326890Y676159D03*
X327257Y672408D03*
X333180Y665611D03*
X335130Y670744D03*
X334313Y663113D03*
X327500Y667244D03*
X324970Y665128D03*
X337030Y677894D03*
X337798Y686721D03*
X336110Y693934D03*
X331520Y701642D03*
X332720Y698170D03*
X325841Y719731D03*
X330410Y712895D03*
X336990Y735701D03*
X324940Y736067D03*
X329440Y735814D03*
X333940Y735895D03*
X329590Y724283D03*
X334640Y725035D03*
X338270Y733387D03*
X339162Y9304D03*
Y11904D03*
X350411Y21277D03*
X339239Y24232D03*
X339471Y19373D03*
Y16773D03*
X339239Y26832D03*
X346600Y38561D03*
X346150Y36030D03*
X353060Y61504D03*
X350198Y88277D03*
X343111Y88429D03*
X340543Y88647D03*
X345463Y90837D03*
X344770Y101718D03*
X351793Y105404D03*
X343070Y99372D03*
X344073Y124397D03*
X351533Y124697D03*
X351373Y134367D03*
X351503Y130972D03*
X345297Y284849D03*
X342955Y291523D03*
X354170Y308924D03*
X351500Y301795D03*
X353903Y314077D03*
X353841Y306194D03*
X339370Y329176D03*
X341910Y325739D03*
X344720D03*
X339600Y332076D03*
X343880Y356989D03*
X349110Y375767D03*
X352420Y375672D03*
X346020Y374075D03*
X343430Y385937D03*
X343770Y382166D03*
X346862Y424850D03*
X346750Y466532D03*
X352890Y479656D03*
X348000Y479150D03*
X352260Y483029D03*
X338762Y479636D03*
X352160Y502138D03*
X351250Y499752D03*
X353400Y507260D03*
X353460Y504536D03*
X348190Y511550D03*
X353120Y510003D03*
X350690Y516376D03*
X352940Y518025D03*
X340182Y531787D03*
X351110Y531835D03*
X340330Y541931D03*
X341011Y537828D03*
X342190Y565848D03*
X342759Y599193D03*
X339616Y603438D03*
Y605938D03*
X339384Y611544D03*
X339600Y621293D03*
Y618693D03*
X339384Y614144D03*
X353298Y633903D03*
X340340Y638054D03*
X340669Y644827D03*
X345580Y638109D03*
X347670Y642285D03*
X351728Y653860D03*
X351722Y659319D03*
X340630Y655093D03*
X339930Y661219D03*
X353902Y667128D03*
X340530Y675658D03*
X338970Y670776D03*
X340870Y665042D03*
X340525Y686600D03*
X353260Y688757D03*
X351810Y706800D03*
X339750Y695271D03*
X339010Y700406D03*
X338926Y697752D03*
X344780Y713349D03*
X352400Y722132D03*
X341190Y712379D03*
X352010Y713968D03*
X342230Y709384D03*
X343730Y724581D03*
X350180Y735880D03*
X350580Y724427D03*
X345610Y733982D03*
X354060Y734790D03*
X350720Y745722D03*
X346516Y790294D03*
X358285Y21325D03*
X356550Y74767D03*
X365670Y64458D03*
X366733Y88477D03*
X359646Y88174D03*
X362133Y90877D03*
X360827Y108541D03*
X362300Y98674D03*
X369670Y99845D03*
X354943Y104191D03*
X354448Y108092D03*
X367560Y120823D03*
X365283Y128125D03*
X354580Y298101D03*
X364220Y296795D03*
X357400Y307608D03*
X365970Y299194D03*
X369280Y300916D03*
X362660Y316986D03*
X357110Y329210D03*
X359410Y317080D03*
X369040Y316735D03*
X359120Y331164D03*
X357040Y332970D03*
X365026Y332478D03*
X362540Y361443D03*
X354690Y377000D03*
X364645Y377065D03*
X360960Y389080D03*
X364880Y384455D03*
X366140Y407639D03*
X360350Y395873D03*
X369280Y415600D03*
X355250Y420679D03*
X368660Y449478D03*
X369500Y445873D03*
X355150Y486758D03*
X368787Y472998D03*
X368943Y506356D03*
X366426Y527722D03*
Y530222D03*
Y532722D03*
X368238Y522673D03*
X358182Y531231D03*
X357820Y534561D03*
X365329Y546121D03*
X368694Y546159D03*
X369918Y592253D03*
X369848Y588903D03*
X360647Y602636D03*
X354973Y605588D03*
Y602588D03*
Y611588D03*
Y614588D03*
Y620588D03*
Y623588D03*
X361562Y645175D03*
X363530Y629727D03*
X367858Y657573D03*
X365070Y658065D03*
X361650Y658537D03*
X361580Y652755D03*
X362173Y665128D03*
X368200Y672132D03*
X368100Y668133D03*
X361810Y675011D03*
X361660Y671306D03*
X365160Y672922D03*
X361760Y668716D03*
X367399Y684652D03*
X367866Y677326D03*
X361646Y689228D03*
X367066Y681094D03*
X364320Y680434D03*
X367496Y690248D03*
X361510Y680886D03*
X362040Y684875D03*
X364649Y684022D03*
X364844Y698332D03*
X361786Y699128D03*
X361717Y695128D03*
X367480Y705169D03*
X367614Y693053D03*
X361580Y703860D03*
X363590Y702324D03*
X366510Y723622D03*
X361350Y720720D03*
X361490Y712505D03*
X367350Y713661D03*
X363162Y739537D03*
X366430Y731459D03*
X357096Y732976D03*
X360246Y730819D03*
X354520Y728701D03*
X363460Y735388D03*
X363359Y743537D03*
X354420Y749198D03*
X366860Y739956D03*
X366201Y787976D03*
X354390Y790294D03*
X366201Y790976D03*
X379940Y17789D03*
X382990Y17519D03*
X371180Y17789D03*
X370960Y20577D03*
X383247Y64141D03*
X373560Y63973D03*
X380906Y88134D03*
X373820Y88400D03*
X384450Y108830D03*
X372620Y98355D03*
X384090Y98743D03*
X379160Y102923D03*
X374030Y95000D03*
X382087Y103647D03*
X376100Y108780D03*
X376723Y94178D03*
X377363Y121108D03*
X374040Y304980D03*
X373640Y301078D03*
X370460Y305908D03*
X371090Y303487D03*
X384248Y319157D03*
X379560Y374955D03*
X379720Y372257D03*
X378830Y386352D03*
X382620Y391882D03*
X379300Y380862D03*
X379286Y378015D03*
X379750Y383965D03*
X376600Y408045D03*
X382680Y408202D03*
X374560Y412421D03*
X376150Y430405D03*
X383750Y437058D03*
X372320Y439514D03*
X378910Y430874D03*
X371080Y448276D03*
X372710Y445705D03*
X374203Y482079D03*
X377284Y473374D03*
X374207Y479329D03*
X373850Y496585D03*
X381760Y496004D03*
X374203Y491029D03*
X379177Y509798D03*
X383924Y514797D03*
X385040Y521754D03*
X384588Y526069D03*
X382632Y530322D03*
Y527822D03*
Y532822D03*
X373538Y520213D03*
X377150Y543151D03*
X376490Y540574D03*
X382596Y537379D03*
X384485Y552365D03*
X382595Y554166D03*
X385410Y566122D03*
X383344Y590662D03*
Y593262D03*
X373448Y589053D03*
X373518Y592403D03*
X371407Y641507D03*
X383034Y640267D03*
X380101Y660239D03*
X379093Y657739D03*
X376650Y654157D03*
X377211Y673197D03*
X379791Y679454D03*
X376946Y689985D03*
X377100Y697218D03*
X371170Y711574D03*
X382960Y711431D03*
X372110Y720308D03*
X376190Y711259D03*
X375575Y739459D03*
X375548Y731459D03*
X375834Y727459D03*
X377840Y724388D03*
X370430Y749138D03*
X376960Y788580D03*
Y791580D03*
X399002Y17519D03*
X392600Y20548D03*
X389240D03*
X392250Y59899D03*
X389690Y60665D03*
X401310Y61439D03*
X393371Y72919D03*
X397790Y69610D03*
X401220Y65155D03*
X399804Y88778D03*
X397442Y90667D03*
X389400Y89232D03*
X399653Y108357D03*
X391536Y108990D03*
X398820Y95823D03*
X391190Y104173D03*
X388860Y98010D03*
X399613Y104657D03*
X391233Y96093D03*
X399150Y131773D03*
X391880Y131692D03*
X399858Y249711D03*
X399298Y257231D03*
X391998Y258251D03*
X392668Y272511D03*
X399608Y275211D03*
X400928Y293151D03*
X396098Y283931D03*
X399880Y319568D03*
X389740Y404725D03*
X393370Y411618D03*
X399060Y454322D03*
X399050Y450968D03*
X398800Y462248D03*
Y458058D03*
X387080Y486400D03*
X385940Y482478D03*
X388890Y480439D03*
X386410Y477576D03*
X389670Y477262D03*
X389107Y492097D03*
X395690Y512774D03*
X396350Y532016D03*
X396048Y540127D03*
X395922Y536127D03*
X390000Y567345D03*
X396520Y567444D03*
X391630Y597900D03*
X401091Y587054D03*
X398386Y587126D03*
X401422Y597270D03*
X400589Y611672D03*
X400587Y607022D03*
X401422Y599770D03*
X398822Y600399D03*
X398195Y620821D03*
X400695Y618321D03*
X398195D03*
X400695Y620821D03*
X392063Y624109D03*
X401353Y624007D03*
X395701Y637430D03*
X399440Y637340D03*
X396940Y658078D03*
X396366Y653229D03*
X399363Y653588D03*
X396478Y661529D03*
X399911Y661325D03*
X386173Y665065D03*
X391938Y672320D03*
X392097Y676231D03*
X399873Y666411D03*
X400267Y684029D03*
X390000Y689724D03*
X389961Y682218D03*
X396550Y680266D03*
X399829Y690191D03*
X400968Y686699D03*
X400408Y681193D03*
X390660Y686923D03*
X391910Y696742D03*
X392080Y692796D03*
X391740Y705957D03*
X398620Y701411D03*
X390950Y701922D03*
X389350Y711288D03*
X396150Y708926D03*
X394840Y711437D03*
X414949Y75291D03*
X403739Y72783D03*
X404310Y65213D03*
X401670Y93807D03*
X404528Y88702D03*
X409060Y92095D03*
X404813Y93887D03*
X407303Y95117D03*
X408072Y109146D03*
X405688Y253581D03*
X402948Y253251D03*
X405970Y256489D03*
X405038Y267521D03*
X401728Y277251D03*
X401618Y267351D03*
X405248Y272731D03*
X405878Y294071D03*
X408790Y317049D03*
X411240Y316482D03*
X403130Y418091D03*
X406200Y417755D03*
X405980Y414630D03*
X405930Y411386D03*
X406140Y424766D03*
X406150Y433203D03*
X406530Y440667D03*
X406000Y444755D03*
X402900Y444842D03*
X414870Y455166D03*
Y450976D03*
X409054Y483084D03*
X412260Y482881D03*
X413607Y485620D03*
X413733Y490781D03*
X410733D03*
X407733D03*
Y493781D03*
Y496781D03*
Y499781D03*
X410733Y493781D03*
X413733D03*
X410733Y496781D03*
X413733D03*
X410733Y499781D03*
X413733D03*
X409985Y508431D03*
X413222Y508054D03*
X411439Y516956D03*
X405348Y506316D03*
X402458Y505903D03*
X401556Y508937D03*
X409251Y521763D03*
X416515Y547602D03*
X402499Y554143D03*
X404578Y551838D03*
X410522Y593947D03*
X413022D03*
X406884Y594176D03*
X406881Y591322D03*
X405234Y611692D03*
X405249Y607017D03*
X412960Y618207D03*
X405426Y626809D03*
X410315Y614782D03*
X410085Y618329D03*
X413930Y639810D03*
X409520Y637387D03*
X414760Y636225D03*
X410989Y652957D03*
X410918Y649363D03*
X413966Y675624D03*
X411862Y688027D03*
X412250Y683196D03*
X411149Y678387D03*
X415834Y693272D03*
X412878Y693183D03*
X414550Y707464D03*
X414810Y696968D03*
X409581Y711643D03*
X402540Y710649D03*
X412080Y719034D03*
X415730Y710897D03*
X406720Y723395D03*
X413940Y735665D03*
X421473Y160556D03*
Y157556D03*
X421640Y228403D03*
X422698Y244301D03*
X422288Y250661D03*
X419038Y242611D03*
X427768Y253569D03*
X422178Y266891D03*
X428208Y262109D03*
X418575Y263691D03*
X418597Y273538D03*
X418698Y279631D03*
X426948Y281051D03*
X418998Y289871D03*
X422918Y289501D03*
X418718Y301181D03*
X421710Y424527D03*
X430340Y416573D03*
X432450Y418766D03*
X422120Y418288D03*
X432960Y414886D03*
X422080Y414644D03*
Y410454D03*
X421770Y433187D03*
X422860Y441790D03*
X422760Y445581D03*
X425870Y449509D03*
X422460Y449467D03*
X429670Y449552D03*
X419420Y453168D03*
Y457358D03*
X419071Y509283D03*
X431280Y514223D03*
X431356Y516836D03*
X425999Y516211D03*
X424873Y513921D03*
X423278Y525160D03*
X428874Y525193D03*
X417520Y525128D03*
X428874Y530627D03*
X417520Y531177D03*
X428745Y536999D03*
X423332Y536763D03*
X417617Y536773D03*
X426068Y546048D03*
X417979Y545352D03*
X428039Y556539D03*
X423861Y556535D03*
X424904Y586283D03*
X422210Y605343D03*
X419221Y612253D03*
X425151Y608429D03*
X422221Y619873D03*
X420245Y636004D03*
X417422Y637592D03*
X422470Y647852D03*
X422007Y652732D03*
X423623Y645396D03*
X422026Y656883D03*
X429820Y656709D03*
X425146Y672426D03*
X430140Y665660D03*
X417974Y663446D03*
X422222Y675226D03*
X426100Y667884D03*
X422510Y677836D03*
X430873Y684536D03*
X425173Y688588D03*
X427900Y679709D03*
X430861Y679156D03*
X422981Y690351D03*
X430862Y691156D03*
X430813Y687156D03*
X427210Y691934D03*
X423317Y705344D03*
X423055Y696713D03*
X430618Y699156D03*
X430667Y703156D03*
X430731Y707156D03*
X430813Y695156D03*
X426391Y701173D03*
X423242Y707949D03*
X425590Y695895D03*
X421350Y694003D03*
X422940Y723802D03*
X430738Y711156D03*
X427130Y717871D03*
X421730Y717398D03*
X424410Y718429D03*
X417330Y717420D03*
X431440Y723955D03*
X420160Y724309D03*
X430940Y735895D03*
X426430Y735126D03*
X418440Y735930D03*
X420290Y733741D03*
X423900Y736055D03*
X424200Y733399D03*
X426440Y724240D03*
X421321Y791476D03*
X417384D03*
X446268Y69074D03*
X442380Y75513D03*
X439670Y70044D03*
X446088Y90159D03*
Y85159D03*
Y87659D03*
X434158Y122272D03*
X443448Y124552D03*
X441518Y122242D03*
X434158Y125092D03*
X444828Y122132D03*
X446522Y146932D03*
X433253Y160737D03*
X433363Y157607D03*
X442520Y223623D03*
X442580Y236459D03*
X447900Y265292D03*
X441498Y266731D03*
X442148Y279361D03*
X442165Y271284D03*
X441076Y294906D03*
X445540Y288853D03*
X441361Y300812D03*
X438340Y403375D03*
X439150Y400930D03*
X446830Y400551D03*
X445900Y403460D03*
X436370Y410543D03*
X444020Y410374D03*
X439830D03*
X446660Y413325D03*
X446950Y417162D03*
X440900Y446260D03*
X436710D03*
X444850Y446337D03*
X438390Y456129D03*
X438520Y452324D03*
X433720Y449467D03*
X447770Y485290D03*
X445366Y490657D03*
X447781Y523888D03*
X442763Y549595D03*
X435998Y539726D03*
X434203Y542897D03*
X438722Y538842D03*
X448329Y534995D03*
X441326Y556050D03*
X434187Y556444D03*
X437516Y587579D03*
X441230Y587341D03*
X447830Y588739D03*
X446378Y582681D03*
X440040Y608537D03*
X440135Y615808D03*
X445604Y629045D03*
X433872Y645119D03*
X446980Y638774D03*
X437100Y643793D03*
X446500Y645075D03*
X443850Y634754D03*
X439250Y630973D03*
X434681Y642639D03*
X435420Y647117D03*
X446799Y657526D03*
X435972Y655595D03*
X445270Y660832D03*
X444403Y665963D03*
X436000Y675706D03*
X435539Y671628D03*
X436445Y667628D03*
X446900Y714648D03*
X442650Y719485D03*
X446260Y722014D03*
X444530Y723917D03*
X439200Y722093D03*
X447240Y724780D03*
X439940Y735507D03*
X443940Y735681D03*
X435440Y735928D03*
X436440Y724710D03*
X442120Y724781D03*
X447680Y733564D03*
X441006Y791476D03*
X437069D03*
X450618Y69004D03*
X457583Y66384D03*
X454263Y77675D03*
X458598Y77967D03*
X462294Y87759D03*
Y85259D03*
Y90259D03*
X461516Y78275D03*
X450917Y97566D03*
X453168Y105144D03*
X460412Y105704D03*
X457912D03*
X462912D03*
X453298Y122254D03*
X450798D03*
X452158Y124582D03*
X458818Y122065D03*
Y125422D03*
X455292Y162797D03*
X455470Y166963D03*
X452669Y157140D03*
X455913Y178698D03*
X454763Y183503D03*
X453340Y185670D03*
X457482Y183523D03*
X452115Y195057D03*
X459000Y200500D03*
X454150Y249053D03*
X459990Y245930D03*
X457165Y262368D03*
X456800Y259233D03*
X459108Y253181D03*
X449860Y267121D03*
X456530Y256034D03*
X449290Y276227D03*
X449860Y272121D03*
X452900Y281647D03*
X453780Y292411D03*
X453810Y289325D03*
X461130Y408318D03*
X448970Y403846D03*
X451950Y402434D03*
X461080Y411451D03*
X463690Y451813D03*
X461590Y446700D03*
X461540Y449833D03*
X457702Y475480D03*
X460702D03*
X454702D03*
X463702D03*
X450899Y483452D03*
X463540Y495717D03*
X457537Y495546D03*
X454770Y495587D03*
X450813Y492993D03*
X463565Y515723D03*
X452895Y510061D03*
X449402Y515514D03*
X451325Y525981D03*
X454022Y541052D03*
X460236Y581679D03*
X455890Y592792D03*
X450778Y583106D03*
X458600Y599200D03*
X453775Y600614D03*
X453935Y624739D03*
X459690Y626423D03*
X456342Y649436D03*
X461997Y654507D03*
X458650Y666543D03*
X463020Y661023D03*
X464330Y663251D03*
X458820Y674137D03*
X463120Y681992D03*
X460530Y681874D03*
X459650Y685993D03*
X457730Y682010D03*
X456960Y685581D03*
X461960Y684394D03*
X459950Y722720D03*
X453960Y723142D03*
X457060Y722427D03*
X460822Y712620D03*
X451820Y712210D03*
X454070Y714226D03*
X453530Y736212D03*
X458050Y725053D03*
X462440Y735687D03*
X455410Y734113D03*
X450410Y733682D03*
X451320Y725044D03*
X460691Y791476D03*
X456754D03*
X475310Y59746D03*
X464767Y78145D03*
X479450Y63721D03*
X466647Y91224D03*
X466682Y102410D03*
X474381Y125310D03*
X478088Y125219D03*
X471500Y138000D03*
X473200Y140300D03*
X468400Y135800D03*
X475760Y168747D03*
X472670Y166398D03*
X473580Y177859D03*
X474630Y174843D03*
X480220Y185766D03*
X468452Y197934D03*
X476400Y203100D03*
X478000Y212500D03*
X471795Y267941D03*
X470090Y332824D03*
X475190Y339013D03*
X474140Y408318D03*
X469590D03*
X465330D03*
X468210Y401505D03*
X465913Y402659D03*
X465883Y399834D03*
X474080Y411451D03*
X469530D03*
X465270D03*
X480050Y419556D03*
X471540Y437214D03*
X473140Y439971D03*
X469500Y447730D03*
X467920Y451667D03*
X472210Y450267D03*
X465730Y449833D03*
X465790Y446700D03*
X479575Y467597D03*
X479754Y462988D03*
X466702Y475480D03*
X466307Y495676D03*
X467677Y510055D03*
X467496Y513179D03*
X466587Y515764D03*
X467586Y506807D03*
X474130Y553659D03*
X474290Y563565D03*
X471190Y593964D03*
X473294Y613207D03*
X473153Y622451D03*
X465580Y641417D03*
X478905Y659426D03*
X470190Y648693D03*
X474946Y659376D03*
X468540Y655799D03*
X479353Y668666D03*
X466049Y675327D03*
X469977Y676496D03*
X468260Y664366D03*
X469467Y679915D03*
X479409Y682305D03*
X477710Y722299D03*
X466620Y714137D03*
X473940Y714184D03*
X471450Y736368D03*
X466440Y735987D03*
X471310Y733811D03*
X466440Y724465D03*
X470550Y724034D03*
X473560Y724951D03*
X465850Y733428D03*
X476980Y736594D03*
X476160Y734205D03*
X474940Y747192D03*
X476439Y791476D03*
X483240Y60546D03*
X487030Y68075D03*
X488438Y100123D03*
X484068Y99980D03*
X492955Y99440D03*
X491875Y125222D03*
X487140Y123397D03*
X487020Y119754D03*
X494910Y133316D03*
X490760Y154771D03*
X488570Y147486D03*
X487740Y161235D03*
X488220Y157515D03*
X482500Y184169D03*
X487080Y180918D03*
X494210Y175035D03*
X495300Y201600D03*
X487464Y198566D03*
X491046Y207506D03*
X486738Y210434D03*
X487168Y214568D03*
X491320Y231809D03*
X488816Y242877D03*
X484780Y314090D03*
X494850Y315733D03*
X480830Y333921D03*
X495140Y385762D03*
X486670Y426196D03*
X495500Y447465D03*
X483685Y473522D03*
X483641Y479628D03*
X492260Y482826D03*
X494980Y482979D03*
X486640Y543687D03*
X485510Y536673D03*
X489938Y563425D03*
X486720Y563730D03*
X481380Y553210D03*
X490658Y579025D03*
X487398Y576665D03*
X490693Y570770D03*
X490538Y567825D03*
X481410Y573563D03*
X485890Y590563D03*
X489380Y590839D03*
X485380Y596505D03*
X490040Y622140D03*
X491100Y644351D03*
X491380Y639279D03*
X495900Y641804D03*
X491930Y654203D03*
X495622Y660178D03*
X492310Y650516D03*
X482180Y646278D03*
X493020Y646701D03*
X491157Y675604D03*
X491044Y667604D03*
X491060Y671604D03*
X492770Y665090D03*
X491189Y679656D03*
X494323Y687669D03*
X492294Y682347D03*
X483056Y679628D03*
X491167Y687507D03*
X494340Y691623D03*
X491067Y699656D03*
X491380Y694656D03*
X496000Y736152D03*
X483180Y736506D03*
X487940Y735681D03*
X491890Y735740D03*
X494850Y733252D03*
X480620Y734244D03*
X480376Y791476D03*
X496955Y99958D03*
X508955Y99978D03*
X500955Y100139D03*
X504955Y99830D03*
X508904Y124063D03*
X499456Y128666D03*
X502132Y146686D03*
X500963Y162261D03*
X501040Y177297D03*
X502999Y180541D03*
X499154Y194198D03*
X505580Y192555D03*
X498875Y217172D03*
X499075Y235575D03*
X496123Y233500D03*
X504941Y227859D03*
X499405Y242877D03*
X507000Y239000D03*
X511070Y310719D03*
X509140Y338005D03*
X504897Y390481D03*
X510577Y417741D03*
X502687Y417453D03*
X497818Y440265D03*
X509464Y450265D03*
X505442Y458719D03*
X505843Y465018D03*
X511070Y493380D03*
X511520Y496255D03*
X505740Y495880D03*
X511560Y513792D03*
X504613Y522050D03*
X498920Y523803D03*
X503958Y529405D03*
X501331Y528932D03*
X500138Y543225D03*
X503448Y540235D03*
X505718Y542865D03*
X500038Y555925D03*
Y550725D03*
X500138Y563025D03*
Y558625D03*
X500338Y566425D03*
X510338Y571325D03*
X500438Y574925D03*
X500419Y578644D03*
X500538Y572025D03*
X500338Y569425D03*
X499868Y585725D03*
X505738Y590525D03*
Y600425D03*
X496140Y608883D03*
X504268Y608625D03*
X500098Y608885D03*
X509238Y608515D03*
X508024Y613598D03*
X504980Y616425D03*
X498350Y627580D03*
X505780Y642543D03*
X501120Y633249D03*
X510700Y634300D03*
X496690Y633589D03*
X501940Y644073D03*
X498666Y653012D03*
X504836Y657097D03*
X503680Y659666D03*
X498040Y675306D03*
X498870Y668324D03*
X506376Y687436D03*
X506470Y683512D03*
X500710Y706582D03*
X510608Y717448D03*
X499842Y710582D03*
X499452Y714582D03*
X502890Y736349D03*
X506105Y724132D03*
X498080Y733252D03*
X509855Y724107D03*
X500260Y729094D03*
X500061Y791476D03*
X496124D03*
X512955Y100428D03*
X524955Y99359D03*
X516955Y100333D03*
X520955Y100444D03*
X525570Y124623D03*
X518248Y137692D03*
X518477Y141401D03*
X527349Y152246D03*
X526875Y161838D03*
X518725Y170525D03*
X512600Y178900D03*
X512200Y204200D03*
X526443Y194116D03*
X514500Y194300D03*
X525293Y191705D03*
X511997Y207730D03*
X512160Y217073D03*
X526657Y207363D03*
X524405Y212531D03*
X514766Y208222D03*
X519183Y224173D03*
X519300Y220500D03*
X516625Y230075D03*
X515675Y234555D03*
X524675Y234766D03*
X517189Y226229D03*
X518590Y310129D03*
X526250Y310940D03*
X519650Y320384D03*
X522420Y315475D03*
X517260Y315978D03*
X523930Y321642D03*
X514400Y340829D03*
X520510Y337299D03*
X526440Y432077D03*
X515780Y434039D03*
X523667Y438452D03*
X522379Y431974D03*
X513140Y452621D03*
X519440Y452321D03*
X526340D03*
X516353Y443517D03*
X523838Y442723D03*
X513140Y459721D03*
Y466021D03*
X525640Y473021D03*
X519640D03*
X513140D03*
X516353Y480708D03*
X525603Y480187D03*
X519490Y496645D03*
X525698Y496724D03*
X519938Y493125D03*
X524938D03*
X522250Y513692D03*
X514430Y511801D03*
X519430D03*
X527138Y529525D03*
X523938Y528725D03*
X515110Y528785D03*
X519438Y543025D03*
X513480Y541499D03*
X518938Y540425D03*
X521938Y540325D03*
X516380Y540364D03*
X525338Y540125D03*
X513838Y556925D03*
X516738Y562425D03*
X513738D03*
X512354Y590825D03*
X515413Y590950D03*
X524638Y590225D03*
X520228Y590335D03*
X519638Y600425D03*
X523538Y600325D03*
X527438D03*
X525570Y602466D03*
X523800Y611145D03*
X520370Y625158D03*
X519830Y634663D03*
X511910Y638722D03*
X515371Y658880D03*
X515438Y649996D03*
X517806Y670102D03*
X526610Y672286D03*
X515425Y685783D03*
X518382Y678247D03*
X518947Y685122D03*
X518500Y723073D03*
X514620Y713193D03*
X517443Y717011D03*
X517775Y711203D03*
X522865Y711178D03*
X514498Y716473D03*
X519440Y735681D03*
X512140Y736554D03*
X514901Y724120D03*
X523370Y724131D03*
X516940Y735683D03*
X521800Y732667D03*
X514420Y733131D03*
X524576Y733227D03*
X519746Y791476D03*
X515809D03*
X542180Y93534D03*
X542248Y106333D03*
X532955Y108669D03*
X528955Y99781D03*
X532955Y100604D03*
X542700Y112881D03*
X527898Y147146D03*
X538655Y151415D03*
X538294Y159415D03*
X533483Y177449D03*
X533797Y180764D03*
X529272Y178311D03*
X542002Y180100D03*
X538525Y213425D03*
X532500Y206500D03*
X536676Y234993D03*
X536576Y246993D03*
X539438Y250323D03*
X536972Y242993D03*
X536476Y238993D03*
X529527Y265584D03*
X532794Y282068D03*
X528680Y317349D03*
X541380Y340358D03*
X543110Y333848D03*
X536180Y341432D03*
X536170Y336603D03*
X531795Y340409D03*
X531430Y337074D03*
X527603Y337208D03*
X529910Y419478D03*
X540700Y418852D03*
X536440Y421973D03*
X530940Y422207D03*
X541440Y431787D03*
X536440Y431923D03*
X531440Y432178D03*
X542738Y455823D03*
X530038Y444323D03*
X533040Y453221D03*
X534738Y445523D03*
X541838Y450723D03*
X533740Y458021D03*
Y465021D03*
X542738Y463123D03*
X533740Y473021D03*
X540938Y473623D03*
X535729Y476632D03*
X539419Y491107D03*
X532934Y491384D03*
X538038Y488323D03*
X533038D03*
X543280Y491040D03*
X530438Y529525D03*
X541538Y529625D03*
X534401Y529562D03*
X530638Y539525D03*
X534638Y539825D03*
X541238Y539625D03*
X528138Y539925D03*
X533038Y590325D03*
X540701Y590162D03*
X527638Y590325D03*
X535776Y590487D03*
X530338Y590325D03*
X536438Y600425D03*
X542438Y613723D03*
X540540Y601008D03*
X538828Y602945D03*
X538400Y613804D03*
X541980Y620227D03*
X527828Y615387D03*
X540048Y629641D03*
X539471Y632476D03*
X530779Y637354D03*
X532479Y633588D03*
X535230Y648711D03*
X541440Y647594D03*
X531970Y650491D03*
X539120Y670129D03*
X539830Y667332D03*
X531599Y689838D03*
X533270Y679351D03*
X531597Y697509D03*
X535485Y715182D03*
X535272Y711217D03*
X535062Y708679D03*
X530012Y708618D03*
X543193Y710787D03*
X537503Y710088D03*
X528388Y722903D03*
X537702Y735662D03*
X541940Y735681D03*
X528440D03*
X531845Y724095D03*
X532940Y734810D03*
X531029Y733142D03*
X539431Y791476D03*
X535494D03*
X547248Y106582D03*
X555938Y97292D03*
X551454Y97154D03*
X547480Y96632D03*
X546306Y110193D03*
X548367Y135415D03*
X548007Y139415D03*
X547543Y143415D03*
X558845Y158697D03*
X555510Y173872D03*
X555836Y179259D03*
X546000Y180000D03*
X558768Y191223D03*
X553909Y207401D03*
X547927Y212190D03*
X558416Y210682D03*
X544700Y216100D03*
X549909Y207060D03*
X555750Y212029D03*
X544500Y207000D03*
X545424Y226722D03*
X546690Y233066D03*
X544990Y231086D03*
X549488Y233003D03*
X549358Y230153D03*
X552120Y232388D03*
X552050Y229124D03*
X550040Y243929D03*
X550090Y247079D03*
X557207Y274828D03*
X551341Y274262D03*
X557222Y285109D03*
X553690Y340829D03*
X547340Y339103D03*
X555707Y389146D03*
X548470Y378127D03*
X549760Y407251D03*
X553750Y410420D03*
X544500Y422583D03*
X557017Y438968D03*
X543381Y448428D03*
X556771Y456156D03*
X556959Y443009D03*
X551140Y445789D03*
X555140Y445940D03*
X556971Y460656D03*
X543338Y459323D03*
X547340Y484025D03*
X548000Y509493D03*
X547880Y515743D03*
X544370Y510267D03*
Y515267D03*
X544138Y530125D03*
X545413Y547950D03*
X551161Y547148D03*
X545138Y539725D03*
X551538Y540325D03*
X551338Y544225D03*
X551438Y561225D03*
X551338Y551100D03*
X551438Y563825D03*
X551538Y568525D03*
X551238Y571725D03*
X550938Y587325D03*
X547000Y590163D03*
X551238Y584025D03*
X543850Y590313D03*
X548138Y600425D03*
X544638Y600525D03*
X553619Y601204D03*
X546938Y613828D03*
X552849Y631652D03*
X545377Y647594D03*
X555356Y665156D03*
Y669156D03*
X555308Y673156D03*
X555357Y689156D03*
X555284Y685156D03*
X555235Y681156D03*
X555308Y677156D03*
X547346Y697581D03*
X544984Y699419D03*
X555150Y697156D03*
X555271Y693156D03*
X547542Y711523D03*
X555148Y735583D03*
X550940Y735681D03*
X546440D03*
X553193Y724847D03*
X546566Y724119D03*
X544082Y724460D03*
X549049Y724412D03*
X557426Y724436D03*
X555179Y791476D03*
X566090Y109136D03*
X560938Y97195D03*
X565938Y96820D03*
X563230Y150222D03*
X563274Y162169D03*
X559646Y174476D03*
X572782Y195199D03*
X561909Y207393D03*
X569874Y231795D03*
X572690Y226569D03*
X572020Y222393D03*
X567980Y222353D03*
X568410Y226647D03*
X561258Y230153D03*
X566248Y230283D03*
X563506Y232027D03*
X571576Y246693D03*
X564676D03*
X571476Y260093D03*
X564676D03*
Y253693D03*
X566774Y275195D03*
X566876Y289890D03*
X567320Y415088D03*
X565977Y456156D03*
X566059Y460956D03*
X561610Y503885D03*
X560960Y510151D03*
X571830Y509411D03*
X573840Y512108D03*
X564370Y504117D03*
Y509117D03*
X568068Y525306D03*
X567493Y532225D03*
X561065Y543998D03*
X560838Y540325D03*
X574738Y587425D03*
X574645Y583525D03*
X566053Y627509D03*
X571650Y625998D03*
X563850Y659575D03*
X563840Y653515D03*
X563586Y682137D03*
X563577Y692284D03*
X563441Y676872D03*
X563393Y686908D03*
X568215Y702343D03*
X568288Y715547D03*
X568908Y735883D03*
X573440Y735681D03*
X564438Y735853D03*
X560350Y735807D03*
X573440Y724053D03*
X568940Y724090D03*
X562395Y724557D03*
X571232Y732545D03*
X559116Y791476D03*
X588943Y98963D03*
X589308Y103990D03*
X583829Y117732D03*
X583661Y121836D03*
X583547Y128232D03*
X583970Y144589D03*
X580180Y148894D03*
X579540Y143304D03*
X584438Y160933D03*
X582920Y194220D03*
X579707Y220662D03*
X583707Y220762D03*
X587707Y220728D03*
X576105Y231626D03*
X578076Y246693D03*
Y253393D03*
Y260093D03*
X575874Y282395D03*
X581474Y274795D03*
X575874Y289895D03*
Y285995D03*
X575880Y293016D03*
X575908Y295606D03*
X583853Y313783D03*
X585584Y308881D03*
X579168Y313641D03*
X583737Y321204D03*
X579788Y354743D03*
X575550Y463784D03*
X575650Y469996D03*
X588153Y459599D03*
X579600Y508878D03*
X578840Y512108D03*
X575438Y545425D03*
X589036Y548825D03*
X583890Y537093D03*
X575238Y552025D03*
X588540Y557418D03*
X584413Y563198D03*
X583538Y552225D03*
X575038Y554725D03*
X575138Y559825D03*
X575038Y567725D03*
X575538Y571725D03*
X574876Y575625D03*
X578110Y582149D03*
X582023Y571242D03*
X586369Y585801D03*
X578399Y585696D03*
X579500Y625963D03*
X577000Y620029D03*
X585500Y620926D03*
X587440Y656958D03*
X576700Y655594D03*
X588950Y650070D03*
X579020Y658250D03*
X580740Y653286D03*
X584903Y663828D03*
X576846Y675985D03*
X579076Y669603D03*
X576520Y667750D03*
X586060Y682582D03*
X587040Y688218D03*
X589050Y680160D03*
X579980Y683140D03*
X576644Y679562D03*
X578030Y690236D03*
X577010Y682718D03*
X576519Y687665D03*
X589500Y690546D03*
X586995Y694080D03*
X579151Y707857D03*
X588151D03*
X584101Y707893D03*
X576442Y705492D03*
X585400Y697289D03*
X579220Y720776D03*
X585693Y722428D03*
X583440Y735856D03*
X587940Y735681D03*
X587963Y724108D03*
X577940Y724127D03*
X580510Y724421D03*
X578802Y791476D03*
X574864D03*
X603158Y91535D03*
X601374Y94048D03*
X604543Y94886D03*
X598123Y102023D03*
X595318Y98854D03*
X593850Y103755D03*
X592392Y100623D03*
X594920Y123370D03*
X595345Y120216D03*
X595438Y138130D03*
X593537Y161023D03*
X592917Y171906D03*
X592491Y175906D03*
X593277Y179955D03*
X595707Y220995D03*
X591707Y221095D03*
X597074Y239995D03*
X600874Y239795D03*
X604774Y249795D03*
X596774D03*
X600874D03*
X604674Y239995D03*
X592874Y250995D03*
X605674Y236295D03*
X592858Y247079D03*
X593459Y240780D03*
X594067Y265168D03*
X594174Y256695D03*
X593874Y262395D03*
X596574Y268695D03*
X600674Y268795D03*
X604574D03*
X604926Y278476D03*
X604774Y271893D03*
X590874Y275195D03*
X592201Y308988D03*
X591977Y319360D03*
X598551Y329541D03*
X601450Y326509D03*
X600770Y358702D03*
X605746Y387837D03*
X605573Y393920D03*
X594860Y395088D03*
X600680Y412780D03*
X598670Y508170D03*
X596560Y536108D03*
X606300Y551844D03*
X604437Y557956D03*
X596050Y557563D03*
X596530Y574903D03*
X596495Y578903D03*
X596484Y582903D03*
X596209Y586903D03*
X590898Y597158D03*
X605290Y594166D03*
X596401Y589852D03*
X605521Y601097D03*
X590842Y608112D03*
X591023Y600384D03*
X605362Y609413D03*
X590646Y618751D03*
X605010Y641435D03*
X600980Y641533D03*
X594733Y653385D03*
X591840Y659568D03*
X596470Y655231D03*
X601588Y664798D03*
X602332Y671156D03*
X593142Y663828D03*
X602020Y679156D03*
X600650Y707835D03*
X592440Y723768D03*
X596860Y723422D03*
X606146Y713145D03*
X601813Y715579D03*
X598880Y719232D03*
X601440Y735681D03*
X605938Y735665D03*
X596940Y735681D03*
X593004Y735662D03*
X598487Y791476D03*
X594550D03*
X618623Y108918D03*
X608274Y249795D03*
X608774Y239995D03*
X608274Y268795D03*
X612974Y269095D03*
X609150Y328514D03*
X616490Y327534D03*
X619190Y336986D03*
X608306Y359971D03*
X617592Y362539D03*
X608869Y396959D03*
X608821Y403445D03*
X619014Y408353D03*
X621399Y420400D03*
X611130Y417928D03*
X609370Y452974D03*
X609300Y531638D03*
X613541Y546764D03*
X616320Y537066D03*
X609168Y554851D03*
X621937Y558276D03*
X621840Y555040D03*
X609060Y552101D03*
X607077Y566915D03*
X612270Y586543D03*
X612493Y607666D03*
X612370Y614143D03*
X614579Y645072D03*
X608310Y641603D03*
X620510Y639427D03*
X616471Y636215D03*
X607620Y647169D03*
X615700Y657757D03*
X610651Y675156D03*
X614909Y671938D03*
X617235Y689036D03*
X610693Y679333D03*
X610570Y691156D03*
X610550Y686640D03*
X610810Y683933D03*
X621410Y696941D03*
X607020Y704644D03*
X608975Y708094D03*
X612914Y707630D03*
X610540Y697964D03*
X618020Y700000D03*
X610570Y695156D03*
X611244Y709830D03*
X621254Y713788D03*
X617093Y709167D03*
X616070Y720838D03*
X620830Y717516D03*
X609840Y713617D03*
X619590Y735383D03*
X614732Y735517D03*
X608791Y735775D03*
X618172Y791476D03*
X614235D03*
X610298D03*
X626380Y85117D03*
X624020Y83243D03*
X623750Y87130D03*
X626380Y88518D03*
X623725Y90422D03*
X626180Y91919D03*
X623820Y93654D03*
X626320Y96084D03*
X623610Y97125D03*
X626180Y99276D03*
X624358Y176090D03*
X632483Y192781D03*
X624950Y189801D03*
X632485Y202077D03*
X622470Y261628D03*
X635000Y265400D03*
X624101Y296525D03*
X632376Y305257D03*
X631702Y307880D03*
X632122Y312898D03*
X635652Y313118D03*
X636962Y310928D03*
X623820Y321062D03*
X633470Y326710D03*
X628140Y317610D03*
X631860Y321455D03*
X627000Y327926D03*
X622890Y325227D03*
X633652Y315198D03*
X630190Y336986D03*
X625190D03*
X624889Y357778D03*
X637738Y392034D03*
X636990Y386464D03*
X627022Y383713D03*
X633633Y403717D03*
X637614Y397259D03*
X636938Y402885D03*
X633663Y411009D03*
X633455Y427209D03*
X634578Y424964D03*
X626250Y450248D03*
X631280Y446007D03*
X635120Y456136D03*
X630570Y451450D03*
X635545Y465888D03*
X622100Y465822D03*
X625900Y461769D03*
X632680Y466669D03*
X636010Y469995D03*
X622798Y546764D03*
X632362Y565543D03*
X627047Y581066D03*
X636868Y593141D03*
X630768Y593241D03*
X624468D03*
Y612141D03*
X624368Y605941D03*
Y599741D03*
X629868Y612241D03*
X635968D03*
X627986Y625895D03*
X630984Y624829D03*
X623290Y641222D03*
X634137Y639352D03*
X630137Y639312D03*
X631930Y655254D03*
X634251Y683493D03*
X623940Y723503D03*
X622290Y708516D03*
X623960Y735141D03*
X628380Y735476D03*
X631690Y733744D03*
X635460Y735130D03*
X630040Y745114D03*
X636390Y775395D03*
X632030Y779137D03*
X632000Y775400D03*
X629983Y791476D03*
X633920D03*
X643957Y53688D03*
X639957Y53849D03*
X638970Y132241D03*
X640448Y294422D03*
X643170Y294282D03*
X641227Y297070D03*
X644113Y297071D03*
X653352Y291388D03*
X642932Y284768D03*
X640112Y285042D03*
X640171Y311965D03*
X644105D03*
X652362Y306598D03*
X651352Y323938D03*
X653162Y318398D03*
X650162D03*
X648450Y338711D03*
X646013Y358110D03*
X648838Y349785D03*
X642863Y358010D03*
X646171Y364676D03*
X647440Y386383D03*
X647340Y393283D03*
X647440Y408383D03*
X647340Y400083D03*
X651138Y417385D03*
X648493Y417221D03*
X641480Y430289D03*
X650079D03*
X648208Y427819D03*
X643208D03*
X653070Y427500D03*
X641690Y443656D03*
X653360Y446280D03*
X651840Y460012D03*
X648920Y457851D03*
X646381Y478679D03*
X651395Y487265D03*
X650150Y494337D03*
X638350Y507893D03*
X641842Y516730D03*
X640470Y523266D03*
X645150Y535704D03*
X638166Y560972D03*
X638286Y557415D03*
X643012Y565243D03*
X651437Y569676D03*
X646732Y580781D03*
X641870Y580743D03*
X646870Y569443D03*
Y576243D03*
X643568Y593241D03*
Y612341D03*
Y606641D03*
Y599541D03*
X642795Y624818D03*
X648701Y624774D03*
X638470Y639290D03*
X650928D03*
X646737Y639413D03*
X642737D03*
X651226Y666288D03*
X639940Y687841D03*
X640330Y684439D03*
X642999Y685781D03*
X648077Y713569D03*
X644950Y719110D03*
X653500Y732583D03*
X639928Y738905D03*
X638890Y734879D03*
X639920Y753526D03*
X650400Y770522D03*
X649640Y757527D03*
X646370Y759252D03*
X652212Y786700D03*
X659947Y53722D03*
X658769Y143630D03*
X658767Y151013D03*
X658959Y165625D03*
X658972Y158337D03*
X667300Y188112D03*
X660700Y203282D03*
X669250Y203317D03*
X665320Y203247D03*
X664560Y195018D03*
Y191443D03*
X660770Y214951D03*
X665390Y214916D03*
X661160Y235485D03*
X658582Y222614D03*
X658601Y229770D03*
X661190Y246085D03*
X656270Y299379D03*
X654060Y302459D03*
X659350Y298810D03*
X654352Y323938D03*
X655122Y315070D03*
X656730Y338633D03*
X666270Y359134D03*
X660138Y365885D03*
X659543Y377086D03*
X662390Y377039D03*
X653938Y364885D03*
X654340Y386283D03*
X661140D03*
X654840Y408483D03*
X661940Y408383D03*
X666312Y417742D03*
X658295Y417662D03*
X653649Y417582D03*
X668779Y417135D03*
X663674Y417999D03*
X656021Y427864D03*
X665766Y427868D03*
X663339Y425601D03*
X658339D03*
X658680Y446610D03*
X667428Y463432D03*
X666928Y468132D03*
X662630Y500823D03*
X664024Y513414D03*
X668823Y532470D03*
X668627Y527718D03*
X665170Y595943D03*
X661396Y588900D03*
X655445Y591918D03*
X664603Y601976D03*
X655978Y609635D03*
X656070Y612743D03*
X655688Y601761D03*
X664870Y614543D03*
X654645Y627064D03*
X667610Y617197D03*
X659600Y623785D03*
X655873Y615540D03*
X655170Y639432D03*
X656971Y660492D03*
X668000Y676595D03*
X656254Y683277D03*
X663040Y688057D03*
X665050Y680648D03*
X655610Y706309D03*
X656505Y701191D03*
X654514Y720674D03*
X657320Y723584D03*
X654050Y718086D03*
X656650Y713057D03*
X659200Y721454D03*
X654000Y736400D03*
X656660Y736218D03*
X655574Y728674D03*
X657570Y730414D03*
X658860Y727383D03*
X656000Y732400D03*
X664460Y785890D03*
X657010Y786039D03*
X661479Y791476D03*
X665416D03*
X679927Y53881D03*
X675927Y53779D03*
X670980Y77061D03*
X671810Y106472D03*
X670280Y188112D03*
X676590Y188198D03*
X680100Y188182D03*
X680220Y200725D03*
X678650Y203480D03*
X681770Y203514D03*
X682140Y191214D03*
Y194615D03*
X680310Y217357D03*
X678750Y214908D03*
X681870Y214942D03*
X669320Y214986D03*
X671129Y305579D03*
X671166Y302550D03*
X679430Y350013D03*
X672752Y366160D03*
X679552Y372873D03*
X669540Y386283D03*
X678099Y389915D03*
X674235Y379364D03*
X677946Y387211D03*
X678986Y392661D03*
X669440Y395183D03*
Y408483D03*
X669540Y402783D03*
X678338Y405185D03*
X679138Y397985D03*
X680017Y403143D03*
X678838Y407785D03*
X683128Y451332D03*
X680228Y451432D03*
X672660Y441007D03*
X670428Y463532D03*
X669728Y468032D03*
X672628D03*
X679175Y464038D03*
X672190Y457216D03*
X674353Y463842D03*
X683112Y464038D03*
Y483723D03*
X683113Y471941D03*
X683112Y479786D03*
X684876Y497385D03*
X683112Y487660D03*
X678450Y508438D03*
X680790Y504521D03*
X678315Y540752D03*
X684620Y535923D03*
X678217Y536752D03*
X678360Y557426D03*
X673950Y557314D03*
X677850Y562515D03*
X673700D03*
X677730Y567706D03*
X673590Y567696D03*
X670940Y612070D03*
X683720Y631732D03*
X681310Y666671D03*
X671400Y666151D03*
X669390Y695406D03*
X672630Y720752D03*
X675100Y749300D03*
X672710Y746235D03*
X672500Y749179D03*
X684500Y786665D03*
X676390Y778439D03*
X677490Y782114D03*
X673290Y782855D03*
X677227Y786454D03*
X669320Y783845D03*
X683520Y789080D03*
Y792080D03*
X688160Y64459D03*
X689500Y120441D03*
X691148Y140140D03*
X698150Y136791D03*
X691280Y149571D03*
X691314Y145071D03*
X699990Y149631D03*
X700060Y144981D03*
X687571Y172292D03*
X693520Y186376D03*
X697850Y186441D03*
X689820Y200159D03*
Y203491D03*
X689480Y191144D03*
X691970Y216820D03*
X691690Y212100D03*
X693540Y205721D03*
X697800Y205879D03*
X692010Y221158D03*
X687584Y233034D03*
Y251770D03*
X689864Y392130D03*
X686686Y392522D03*
X687121Y407004D03*
X689864Y398141D03*
X686686Y397522D03*
X689527Y407843D03*
X686731Y413349D03*
X689527Y412843D03*
X687049Y467975D03*
X698860D03*
X687130Y464132D03*
X691070Y464058D03*
X690986Y467975D03*
X698860Y471912D03*
X690986D03*
Y479786D03*
X687049Y483723D03*
X698860Y479786D03*
Y483723D03*
X687049Y479786D03*
X690986Y483723D03*
X687049Y471912D03*
X698683Y487517D03*
X690986Y487660D03*
X687049D03*
X692955Y502112D03*
X691161Y518684D03*
X692520Y506898D03*
X696494Y513677D03*
X700719Y516954D03*
X686661Y519199D03*
X698438Y524890D03*
X694150Y536155D03*
X690040Y535797D03*
X687183Y539585D03*
X691532Y559789D03*
Y567789D03*
Y571789D03*
Y579789D03*
Y587789D03*
X695600Y590788D03*
X685410Y621250D03*
X688340Y621294D03*
X687660Y631799D03*
X692720Y670540D03*
X698830Y670652D03*
X689100Y680291D03*
X688510Y735294D03*
X707176Y50574D03*
X706380Y75482D03*
X708130Y106389D03*
X701687Y212132D03*
X700947Y216868D03*
X700994Y221368D03*
X701770Y331938D03*
X707942Y448676D03*
X714639Y454872D03*
X702730Y455483D03*
X715528Y459332D03*
X702797Y464038D03*
Y467975D03*
X706734Y471913D03*
X710768Y475972D03*
X715328Y481122D03*
X706734Y483723D03*
X710671Y479786D03*
X706734Y475850D03*
X710671Y471913D03*
X702585Y483749D03*
X702797Y471912D03*
Y479786D03*
X706734D03*
X707736Y510140D03*
X712281Y525785D03*
X712820Y519647D03*
X710585Y539103D03*
X701170Y538508D03*
X708258Y549815D03*
X701023Y553658D03*
X710873Y563230D03*
X713300Y578995D03*
X713190Y583032D03*
X715282Y620282D03*
X711612Y620383D03*
X712732Y631749D03*
X716064D03*
X703570Y673036D03*
X707660Y673204D03*
X713910Y681330D03*
X708450Y695489D03*
X705870Y721832D03*
X709500Y736800D03*
X706575Y740425D03*
X716245Y765576D03*
X704786Y791274D03*
X708723Y791092D03*
X709040Y787507D03*
X719800Y24920D03*
X726160Y109316D03*
X726190Y105325D03*
X726160Y112508D03*
X726500Y123466D03*
X726400Y130303D03*
X726470Y126659D03*
X726430Y465371D03*
X731340Y476723D03*
X718431Y483368D03*
X721290Y484381D03*
X719370Y472436D03*
X725730Y486788D03*
X729640Y486848D03*
X727602Y500100D03*
X720150Y491632D03*
X729942Y515757D03*
X719332D03*
X728661Y558934D03*
X731251Y558975D03*
X726154Y559002D03*
X720445Y558990D03*
X723370Y558906D03*
X720052Y620480D03*
X719092Y631682D03*
X717372Y634474D03*
X718510Y681526D03*
X721100Y689400D03*
X731200Y716200D03*
X729500Y737400D03*
X730800Y728400D03*
X729500Y746300D03*
X718150Y763015D03*
X721100Y762903D03*
X721245Y765576D03*
X727570Y775278D03*
X730990Y775334D03*
X726925Y778490D03*
X731925D03*
X721790Y791408D03*
X722590Y787885D03*
X738620Y109351D03*
X738650Y105360D03*
X744760Y103711D03*
X744790Y106938D03*
X747710Y100293D03*
X738620Y112543D03*
X738370Y123395D03*
X745070Y110183D03*
X738270Y130232D03*
X738340Y126588D03*
X747080Y129815D03*
X747600Y323527D03*
X745220Y327250D03*
X741401Y454832D03*
X737350Y459823D03*
X742779Y487639D03*
X743364Y478975D03*
X743150Y483502D03*
X738130Y502748D03*
X732817Y489435D03*
X744090Y575066D03*
X747470Y585542D03*
X747460Y582318D03*
X734460Y788654D03*
Y791654D03*
X762590Y106529D03*
X762630Y103302D03*
X751080Y100293D03*
X754580Y124020D03*
X748070Y110209D03*
X751180D03*
X754610Y127247D03*
X750930Y129815D03*
X750430Y314330D03*
X750350Y311343D03*
X750700Y323771D03*
X753230Y328262D03*
X759400Y334839D03*
X754850Y335055D03*
X755500Y337791D03*
X757823Y451032D03*
X758494Y455532D03*
X758500Y469500D03*
X757500Y474000D03*
X748300Y496800D03*
X751730Y583047D03*
X749520Y658372D03*
X765250Y357789D03*
X765610Y361194D03*
X766840Y561290D03*
X766920Y564080D03*
X766950Y558318D03*
X766820Y569897D03*
X766900Y567233D03*
Y572869D03*
X770850Y575760D03*
X770710Y584054D03*
X1088471Y889195D03*
G54D40*
G01X-3000Y0D02*
X-95158D01*
G01X-80798Y159685D02*
Y169685D01*
X-78298D01*
X-77298Y169185D01*
X-76548Y168518D01*
X-75923Y167518D01*
X-75423Y166351D01*
X-75298Y164685D01*
X-75423Y163018D01*
X-75923Y161852D01*
X-76548Y160851D01*
X-77298Y160185D01*
X-78298Y159685D01*
X-80798D01*
G01X-65548D02*
X-70548D01*
Y169685D01*
X-65548D01*
G01X-67548Y164852D02*
X-70548D01*
G01X-58048Y169685D02*
Y159685D01*
G01X-60923Y169685D02*
X-55173D01*
G01X-51173Y159685D02*
X-48048Y169685D01*
X-44923Y159685D01*
G01X-46048Y163185D02*
X-50048D01*
G01X-39548Y169685D02*
X-36548D01*
G01X-38048D02*
Y159685D01*
G01X-39548D02*
X-36548D01*
G01X-30548Y169685D02*
Y159685D01*
X-25548D01*
G01X-11173D02*
X-8048Y169685D01*
X-4923Y159685D01*
G01X-6048Y163185D02*
X-10048D01*
G01X-83670Y258044D02*
Y268044D01*
X-81170D01*
X-80170Y267544D01*
X-79420Y266877D01*
X-78795Y265877D01*
X-78295Y264710D01*
X-78170Y263044D01*
X-78295Y261377D01*
X-78795Y260211D01*
X-79420Y259210D01*
X-80170Y258544D01*
X-81170Y258044D01*
X-83670D01*
G01X-68420D02*
X-73420D01*
Y268044D01*
X-68420D01*
G01X-70420Y263211D02*
X-73420D01*
G01X-60920Y268044D02*
Y258044D01*
G01X-63795Y268044D02*
X-58045D01*
G01X-54045Y258044D02*
X-50920Y268044D01*
X-47795Y258044D01*
G01X-48920Y261544D02*
X-52920D01*
G01X-42420Y268044D02*
X-39420D01*
G01X-40920D02*
Y258044D01*
G01X-42420D02*
X-39420D01*
G01X-33420Y268044D02*
Y258044D01*
X-28420D01*
G01X-14045D02*
X-10920Y268044D01*
X-7795Y258044D01*
G01X-8920Y261544D02*
X-12920D01*
G01X-42372Y125213D02*
G02I-2500J0D01*
G01X-44872Y127713D02*
G03Y122713I0J-2500D01*
G03Y127713I0J2500D01*
G01X-42372Y125213D02*
G03X-47372I-2500J0D01*
G03X-42372I2500J0D01*
G01X-44872Y127713D02*
G03I0J-2500D01*
G01X-42372Y141213D02*
G02I-2500J0D01*
G01X-44872Y143713D02*
G03Y138713I0J-2500D01*
G03Y143713I0J2500D01*
G01X-42372Y141213D02*
G03X-47372I-2500J0D01*
G03X-42372I2500J0D01*
G01X-44872Y143713D02*
G03I0J-2500D01*
G01X-42372Y232533D02*
G02I-2500J0D01*
G01X-44872Y235033D02*
G03Y230033I0J-2500D01*
G03Y235033I0J2500D01*
G01D02*
G03Y230033I0J-2500D01*
G03Y235033I0J2500D01*
G01X-42372Y232533D02*
G03X-47372I-2500J0D01*
G03X-42372I2500J0D01*
G01X-44872Y235033D02*
G03I0J-2500D01*
G01D02*
G02I0J-2500D01*
G01X-42372Y248533D02*
G02I-2500J0D01*
G01X-44872Y251033D02*
G03Y246033I0J-2500D01*
G03Y251033I0J2500D01*
G01D02*
G03Y246033I0J-2500D01*
G03Y251033I0J2500D01*
G01X-42372Y248533D02*
G03X-47372I-2500J0D01*
G03X-42372I2500J0D01*
G01X-44872Y251033D02*
G03I0J-2500D01*
G01D02*
G02I0J-2500D01*
G01X-42372Y738493D02*
G02I-2500J0D01*
G01X-44872Y735993D02*
G03Y740993I0J2500D01*
G03Y735993I0J-2500D01*
G01X-42372Y738493D02*
G03X-47372I-2500J0D01*
G03X-42372I2500J0D01*
G01X-44872Y735993D02*
G03I0J2500D01*
G01X-42372Y754493D02*
G02I-2500J0D01*
G01X-44872Y751993D02*
G03Y756993I0J2500D01*
G03Y751993I0J-2500D01*
G01X-42372Y754493D02*
G03X-47372I-2500J0D01*
G03X-42372I2500J0D01*
G01X-44872Y751993D02*
G03I0J2500D01*
G01X-24372Y125213D02*
G02I-2500J0D01*
G01X-26872Y127713D02*
G03Y122713I0J-2500D01*
G03Y127713I0J2500D01*
G01X-24372Y125213D02*
G03X-29372I-2500J0D01*
G03X-24372I2500J0D01*
G01X-26872Y127713D02*
G03I0J-2500D01*
G01X-24372Y141213D02*
G02I-2500J0D01*
G01X-26872Y143713D02*
G03Y138713I0J-2500D01*
G03Y143713I0J2500D01*
G01X-24372Y141213D02*
G03X-29372I-2500J0D01*
G03X-24372I2500J0D01*
G01X-26872Y143713D02*
G03I0J-2500D01*
G01X-24372Y232533D02*
G02I-2500J0D01*
G01X-26872Y235033D02*
G03Y230033I0J-2500D01*
G03Y235033I0J2500D01*
G01D02*
G03Y230033I0J-2500D01*
G03Y235033I0J2500D01*
G01X-24372Y232533D02*
G03X-29372I-2500J0D01*
G03X-24372I2500J0D01*
G01X-26872Y235033D02*
G03I0J-2500D01*
G01D02*
G02I0J-2500D01*
G01X-24372Y248533D02*
G02I-2500J0D01*
G01X-26872Y251033D02*
G03Y246033I0J-2500D01*
G03Y251033I0J2500D01*
G01D02*
G03Y246033I0J-2500D01*
G03Y251033I0J2500D01*
G01X-24372Y248533D02*
G03X-29372I-2500J0D01*
G03X-24372I2500J0D01*
G01X-26872Y251033D02*
G03I0J-2500D01*
G01D02*
G02I0J-2500D01*
G01X-24372Y738493D02*
G02I-2500J0D01*
G01X-26872Y735993D02*
G03Y740993I0J2500D01*
G03Y735993I0J-2500D01*
G01X-24372Y738493D02*
G03X-29372I-2500J0D01*
G03X-24372I2500J0D01*
G01X-26872Y735993D02*
G03I0J2500D01*
G01X-24372Y754493D02*
G02I-2500J0D01*
G01X-26872Y751993D02*
G03Y756993I0J2500D01*
G03Y751993I0J-2500D01*
G01X-24372Y754493D02*
G03X-29372I-2500J0D01*
G03X-24372I2500J0D01*
G01X-26872Y751993D02*
G03I0J2500D01*
G01X0Y-3000D02*
Y-76052D01*
G01X736866Y821652D02*
X738695Y819832D01*
X738819Y819708D01*
Y679921D01*
G03X746693Y672047I7874J0D01*
G01X779528D01*
G02X787402Y664173I0J-7874D01*
G01Y297835D01*
G02X781496Y291929I-5906J0D01*
G01X780315D01*
G03X774409Y286024I0J-5906D01*
G01Y132480D01*
G03X780315Y126575I5906J1D01*
G01X781496D01*
G02X787402Y120669I0J-5906D01*
G01Y7874D01*
G02X779528Y0I-7874J0D01*
G01X7874D01*
G02X0Y7874I0J7874D01*
G01Y115354D01*
G02X5906Y121260I5906J0D01*
G01X25591D01*
G03X31496Y127165I0J5905D01*
G01Y272835D01*
G03X25591Y278740I-5905J0D01*
G01X5906D01*
G02X0Y284646I0J5906D01*
G01Y664173D01*
G02X7874Y672047I7874J0D01*
G01X40787D01*
G03X48661Y679921I0J7874D01*
G01Y819674D01*
X49201Y820214D01*
X50646Y821652D01*
X327026D01*
X328915Y819773D01*
X328976Y819712D01*
Y792323D01*
G03X336457I3740J0D01*
G01Y819673D01*
X336476Y819692D01*
X338446Y821652D01*
X378606D01*
X380551Y819707D01*
Y741142D01*
G03X406929I13189J0D01*
G01Y819675D01*
X406946Y819692D01*
X408916Y821652D01*
X685296D01*
X686388Y820566D01*
X687244Y819710D01*
Y792323D01*
G03X694724I3740J0D01*
G01Y819670D01*
X694746Y819692D01*
X696716Y821652D01*
X736866D01*
G01X5906Y278740D02*
X25591D01*
G02X31496Y272835I0J-5905D01*
G01Y127165D01*
G02X25591Y121260I-5905J0D01*
G01X5906D01*
G03X0Y115354I0J-5906D01*
G01Y7874D01*
G03X7874Y0I7874J0D01*
G01X779528D01*
G03X787402Y7874I0J7874D01*
G01Y120669D01*
G03X781496Y126575I-5906J0D01*
G01X780315D01*
G02X774409Y132480I0J5906D01*
G01Y286024D01*
G02X780315Y291929I5906J-1D01*
G01X781496D01*
G03X787402Y297835I0J5906D01*
G01Y664173D01*
G03X779528Y672047I-7874J0D01*
G01X746693D01*
G02X738819Y679921I0J7874D01*
G01Y819708D01*
X738695Y819832D01*
X736866Y821652D01*
G01X26918Y154399D02*
X-1136Y164201D01*
G01X28440Y254026D02*
X386Y263828D01*
G01X5906Y278740D02*
G02X0Y284646I0J5906D01*
G01Y664173D01*
G02X7874Y672047I7874J0D01*
G01X40787D01*
G03X48661Y679921I0J7874D01*
G01Y819674D01*
X49201Y820214D01*
X50646Y821652D01*
G01X0Y683704D02*
Y934117D01*
G01X337289Y931117D02*
X0D01*
G01X5000Y932117D02*
X0Y931117D01*
X5000Y930117D01*
Y932117D01*
G01X21868Y155104D02*
X26918Y154399D01*
X22528Y156992D01*
X21868Y155104D01*
G01X21204Y1276290D02*
X11204D01*
X13204Y1274790D01*
G01X21204D02*
Y1277790D01*
G01X11204Y1286290D02*
X11537Y1285290D01*
X12371Y1284540D01*
X13371Y1284040D01*
X14704Y1283665D01*
X16204Y1283540D01*
X17704Y1283665D01*
X19037Y1284040D01*
X20038Y1284540D01*
X20871Y1285290D01*
X21204Y1286290D01*
X20871Y1287290D01*
X20038Y1288040D01*
X19037Y1288540D01*
X17704Y1288915D01*
X16204Y1289040D01*
X14704Y1288915D01*
X13371Y1288540D01*
X12371Y1288040D01*
X11537Y1287290D01*
X11204Y1286290D01*
G01X21204Y1293040D02*
X11204D01*
X19537Y1296290D01*
X11204Y1299540D01*
X21204D01*
G01Y1303040D02*
X11204D01*
X19537Y1306290D01*
X11204Y1309540D01*
X21204D01*
G01X38493Y-241864D02*
Y-246864D01*
G01X37036Y-241864D02*
X39950D01*
G01X44860Y-246864D02*
X42326D01*
Y-241864D01*
X44860D01*
G01X43846Y-244281D02*
X42326D01*
G01X47426Y-241864D02*
Y-246864D01*
X49960D01*
G01X53793Y-247031D02*
X53666Y-246947D01*
Y-246781D01*
X53793Y-246697D01*
X53920Y-246781D01*
Y-246947D01*
X53793Y-247031D01*
G01Y-244781D02*
X53666Y-244697D01*
Y-244531D01*
X53793Y-244447D01*
X53920Y-244531D01*
Y-244697D01*
X53793Y-244781D01*
G01X58576Y-248531D02*
X57943Y-247697D01*
X57626Y-246864D01*
Y-243531D01*
X57943Y-242697D01*
X58576Y-241864D01*
G01X63993D02*
X63486Y-242031D01*
X63106Y-242447D01*
X62853Y-242947D01*
X62663Y-243614D01*
X62600Y-244364D01*
X62663Y-245114D01*
X62853Y-245781D01*
X63106Y-246281D01*
X63486Y-246697D01*
X63993Y-246864D01*
X64500Y-246697D01*
X64880Y-246281D01*
X65133Y-245781D01*
X65323Y-245114D01*
X65386Y-244364D01*
X65323Y-243614D01*
X65133Y-242947D01*
X64880Y-242447D01*
X64500Y-242031D01*
X63993Y-241864D01*
G01X67700Y-245864D02*
X68080Y-246447D01*
X68586Y-246781D01*
X69156Y-246864D01*
X69663Y-246781D01*
X70170Y-246364D01*
X70486Y-245864D01*
X70550Y-245364D01*
X70423Y-244781D01*
X69980Y-244364D01*
X69536Y-244197D01*
X68966D01*
G01X69536D02*
X69916Y-243947D01*
X70233Y-243531D01*
X70360Y-243031D01*
X70233Y-242531D01*
X69916Y-242114D01*
X69346Y-241864D01*
X68776Y-241947D01*
X68206Y-242281D01*
G01X74510Y-248531D02*
X75143Y-247697D01*
X75460Y-246864D01*
Y-243531D01*
X75143Y-242697D01*
X74510Y-241864D01*
G01X77900Y-245864D02*
X78280Y-246447D01*
X78786Y-246781D01*
X79356Y-246864D01*
X79863Y-246781D01*
X80370Y-246364D01*
X80686Y-245864D01*
X80750Y-245364D01*
X80623Y-244781D01*
X80180Y-244364D01*
X79736Y-244197D01*
X79166D01*
G01X79736D02*
X80116Y-243947D01*
X80433Y-243531D01*
X80560Y-243031D01*
X80433Y-242531D01*
X80116Y-242114D01*
X79546Y-241864D01*
X78976Y-241947D01*
X78406Y-242281D01*
G01X83190Y-242697D02*
X83570Y-242197D01*
X84013Y-241947D01*
X84520Y-241864D01*
X85153Y-242031D01*
X85596Y-242447D01*
X85723Y-242947D01*
X85660Y-243447D01*
X85406Y-243864D01*
X84140Y-244697D01*
X83570Y-245281D01*
X83190Y-246114D01*
X83063Y-246864D01*
X85723D01*
G01X89366D02*
X89493Y-245781D01*
X89683Y-244864D01*
X89936Y-244031D01*
X90253Y-243114D01*
X90760Y-241864D01*
X88226D01*
G01X93770Y-245197D02*
X95416D01*
G01X98490Y-242697D02*
X98870Y-242197D01*
X99313Y-241947D01*
X99820Y-241864D01*
X100453Y-242031D01*
X100896Y-242447D01*
X101023Y-242947D01*
X100960Y-243447D01*
X100706Y-243864D01*
X99440Y-244697D01*
X98870Y-245281D01*
X98490Y-246114D01*
X98363Y-246864D01*
X101023D01*
G01X103400Y-245864D02*
X103780Y-246447D01*
X104286Y-246781D01*
X104856Y-246864D01*
X105363Y-246781D01*
X105870Y-246364D01*
X106186Y-245864D01*
X106250Y-245364D01*
X106123Y-244781D01*
X105680Y-244364D01*
X105236Y-244197D01*
X104666D01*
G01X105236D02*
X105616Y-243947D01*
X105933Y-243531D01*
X106060Y-243031D01*
X105933Y-242531D01*
X105616Y-242114D01*
X105046Y-241864D01*
X104476Y-241947D01*
X103906Y-242281D01*
G01X110653Y-246864D02*
Y-241864D01*
X108310Y-245447D01*
X111476D01*
G01X113600Y-246114D02*
X113980Y-246531D01*
X114423Y-246781D01*
X114993Y-246864D01*
X115563Y-246697D01*
X116006Y-246364D01*
X116323Y-245781D01*
X116386Y-245114D01*
X116260Y-244447D01*
X115943Y-244031D01*
X115500Y-243697D01*
X115056Y-243614D01*
X114613Y-243697D01*
X114043Y-244031D01*
X114233Y-241864D01*
X115943D01*
G01X123990Y-246864D02*
Y-241864D01*
X126396D01*
G01X125510Y-244281D02*
X123990D01*
G01X128710Y-246864D02*
X130293Y-241864D01*
X131876Y-246864D01*
G01X131306Y-245114D02*
X129280D01*
G01X134063Y-246864D02*
X136723Y-241864D01*
G01X134063D02*
X136723Y-246864D01*
G01X140493Y-247031D02*
X140366Y-246947D01*
Y-246781D01*
X140493Y-246697D01*
X140620Y-246781D01*
Y-246947D01*
X140493Y-247031D01*
G01Y-244781D02*
X140366Y-244697D01*
Y-244531D01*
X140493Y-244447D01*
X140620Y-244531D01*
Y-244697D01*
X140493Y-244781D01*
G01X145276Y-248531D02*
X144643Y-247697D01*
X144326Y-246864D01*
Y-243531D01*
X144643Y-242697D01*
X145276Y-241864D01*
G01X150693D02*
X150186Y-242031D01*
X149806Y-242447D01*
X149553Y-242947D01*
X149363Y-243614D01*
X149300Y-244364D01*
X149363Y-245114D01*
X149553Y-245781D01*
X149806Y-246281D01*
X150186Y-246697D01*
X150693Y-246864D01*
X151200Y-246697D01*
X151580Y-246281D01*
X151833Y-245781D01*
X152023Y-245114D01*
X152086Y-244364D01*
X152023Y-243614D01*
X151833Y-242947D01*
X151580Y-242447D01*
X151200Y-242031D01*
X150693Y-241864D01*
G01X154400Y-245864D02*
X154780Y-246447D01*
X155286Y-246781D01*
X155856Y-246864D01*
X156363Y-246781D01*
X156870Y-246364D01*
X157186Y-245864D01*
X157250Y-245364D01*
X157123Y-244781D01*
X156680Y-244364D01*
X156236Y-244197D01*
X155666D01*
G01X156236D02*
X156616Y-243947D01*
X156933Y-243531D01*
X157060Y-243031D01*
X156933Y-242531D01*
X156616Y-242114D01*
X156046Y-241864D01*
X155476Y-241947D01*
X154906Y-242281D01*
G01X161210Y-248531D02*
X161843Y-247697D01*
X162160Y-246864D01*
Y-243531D01*
X161843Y-242697D01*
X161210Y-241864D01*
G01X164600Y-245864D02*
X164980Y-246447D01*
X165486Y-246781D01*
X166056Y-246864D01*
X166563Y-246781D01*
X167070Y-246364D01*
X167386Y-245864D01*
X167450Y-245364D01*
X167323Y-244781D01*
X166880Y-244364D01*
X166436Y-244197D01*
X165866D01*
G01X166436D02*
X166816Y-243947D01*
X167133Y-243531D01*
X167260Y-243031D01*
X167133Y-242531D01*
X166816Y-242114D01*
X166246Y-241864D01*
X165676Y-241947D01*
X165106Y-242281D01*
G01X170016Y-246281D02*
X170460Y-246697D01*
X170966Y-246864D01*
X171473Y-246697D01*
X171916Y-246197D01*
X172233Y-245447D01*
X172360Y-244697D01*
Y-243781D01*
X172233Y-243031D01*
X171916Y-242364D01*
X171536Y-242031D01*
X171093Y-241864D01*
X170586Y-242031D01*
X170206Y-242364D01*
X169953Y-242864D01*
X169826Y-243531D01*
X169953Y-244114D01*
X170270Y-244697D01*
X170650Y-245031D01*
X171093Y-245114D01*
X171600Y-244947D01*
X171980Y-244531D01*
X172360Y-243781D01*
G01X176066Y-246864D02*
X176193Y-245781D01*
X176383Y-244864D01*
X176636Y-244031D01*
X176953Y-243114D01*
X177460Y-241864D01*
X174926D01*
G01X180470Y-245197D02*
X182116D01*
G01X185000Y-245864D02*
X185380Y-246447D01*
X185886Y-246781D01*
X186456Y-246864D01*
X186963Y-246781D01*
X187470Y-246364D01*
X187786Y-245864D01*
X187850Y-245364D01*
X187723Y-244781D01*
X187280Y-244364D01*
X186836Y-244197D01*
X186266D01*
G01X186836D02*
X187216Y-243947D01*
X187533Y-243531D01*
X187660Y-243031D01*
X187533Y-242531D01*
X187216Y-242114D01*
X186646Y-241864D01*
X186076Y-241947D01*
X185506Y-242281D01*
G01X190290Y-244781D02*
X190733Y-244197D01*
X191113Y-243864D01*
X191620Y-243697D01*
X192063Y-243864D01*
X192380Y-244197D01*
X192633Y-244697D01*
X192696Y-245281D01*
X192633Y-245781D01*
X192380Y-246281D01*
X192000Y-246697D01*
X191556Y-246864D01*
X191050Y-246697D01*
X190606Y-246197D01*
X190353Y-245447D01*
X190290Y-244614D01*
X190416Y-243531D01*
X190606Y-242947D01*
X190923Y-242364D01*
X191366Y-241947D01*
X191810Y-241864D01*
X192253Y-242031D01*
X192570Y-242447D01*
G01X196593Y-246864D02*
Y-241864D01*
X195833Y-242864D01*
G01Y-246864D02*
X197353D01*
G01X202453D02*
Y-241864D01*
X200110Y-245447D01*
X203276D01*
G01X26493Y-176864D02*
Y-251864D01*
X526493D01*
Y-176864D01*
X26493D01*
G01X48550Y146457D02*
G03I-9633J3549D01*
G01X50072Y246084D02*
G03I-9633J3549D01*
G01X23390Y254731D02*
X28440Y254026D01*
X24050Y256619D01*
X23390Y254731D01*
G01X30062Y1277510D02*
Y1246014D01*
G01D02*
Y1297195D01*
G01X96292Y1277510D02*
X22188D01*
G01X30062Y1348376D02*
Y1297195D01*
G01Y1316880D02*
Y1348376D01*
G01X95438Y1316880D02*
X22188D01*
G01X327026Y821652D02*
X50646D01*
G01X48661Y822648D02*
Y857217D01*
G01X93054Y1336565D02*
X49747D01*
G01X93054Y1352313D02*
X49747D01*
G01X54732Y1366158D02*
X44732D01*
X51899Y1361533D01*
Y1367783D01*
G01X54732Y1371408D02*
X44732D01*
X53065Y1374658D01*
X44732Y1377908D01*
X54732D01*
G01Y1381408D02*
X44732D01*
X53065Y1384658D01*
X44732Y1387908D01*
X54732D01*
G01X57621Y1336565D02*
Y1389715D01*
G01X106999Y96614D02*
G02X89851I-8574J-10787D01*
G03X91339Y99696I-2449J3083D01*
G01Y105512D01*
G02X105512I7086J0D01*
G01Y99696D01*
G03X106999Y96614I3937J0D01*
G01D02*
G02X89851I-8574J-10787D01*
G03X91339Y99696I-2449J3083D01*
G01Y105512D01*
G02X105512I7086J0D01*
G01Y99696D01*
G03X106999Y96614I3937J0D01*
G01D02*
G02X89851I-8574J-10787D01*
G03X91339Y99696I-2449J3083D01*
G01Y105512D01*
G02X105512I7086J0D01*
G01Y99696D01*
G03X106999Y96614I3937J0D01*
G01D02*
G02X89851I-8574J-10787D01*
G03X91339Y99696I-2449J3083D01*
G01Y105512D01*
G02X105512I7086J0D01*
G01Y99696D01*
G03X106999Y96614I3937J0D01*
G01Y710787D02*
G02X89851I-8574J-10787D01*
G03X91339Y713869I-2449J3083D01*
G01Y719685D01*
G02X105512I7086J0D01*
G01Y713869D01*
G03X106999Y710787I3937J0D01*
G01D02*
G02X89851I-8574J-10787D01*
G03X91339Y713869I-2449J3083D01*
G01Y719685D01*
G02X105512I7086J0D01*
G01Y713869D01*
G03X106999Y710787I3937J0D01*
G01D02*
G02X89851I-8574J-10787D01*
G03X91339Y713869I-2449J3083D01*
G01Y719685D01*
G02X105512I7086J0D01*
G01Y713869D01*
G03X106999Y710787I3937J0D01*
G01D02*
G02X89851I-8574J-10787D01*
G03X91339Y713869I-2449J3083D01*
G01Y719685D01*
G02X105512I7086J0D01*
G01Y713869D01*
G03X106999Y710787I3937J0D01*
G01X98426Y-31696D02*
Y-39125D01*
G01Y716685D02*
Y-31696D01*
G01X102896Y1254872D02*
G03I-2952J0D01*
G01Y1274557D02*
G03I-2952J0D01*
G01X96991Y1316880D02*
X671794D01*
G01X96991Y1332628D02*
Y1316880D01*
G01Y1336565D02*
X671794D01*
G01Y1332628D02*
X96991D01*
G01Y1352313D02*
Y1336565D01*
G01X671794Y1352313D02*
X96991D01*
G01Y1356250D02*
Y1427117D01*
G01Y1419242D02*
X392266D01*
G01X102362Y-25504D02*
Y-26837D01*
X110065Y-34540D01*
Y-40117D01*
G01X102362Y346606D02*
Y-25504D01*
G01X101426Y105512D02*
X838200D01*
G01X105362Y349606D02*
X812512D01*
G01X101426Y719685D02*
X864902D01*
G01X142266Y1184991D02*
X110770D01*
G01D02*
X152109D01*
G01X122581Y1254872D02*
G03I-2952J0D01*
G01Y1274557D02*
G03I-2952J0D01*
G01X137682Y1165858D02*
X138432Y1165025D01*
X139307Y1164525D01*
X140432Y1164358D01*
X141557Y1164691D01*
X142432Y1165358D01*
X143057Y1166525D01*
X143182Y1167858D01*
X142932Y1169191D01*
X142307Y1170025D01*
X141432Y1170691D01*
X140557Y1170858D01*
X139682Y1170691D01*
X138557Y1170025D01*
X138932Y1174358D01*
X142307D01*
G01X147182Y1164358D02*
Y1174358D01*
X150432Y1166025D01*
X153682Y1174358D01*
Y1164358D01*
G01X157182D02*
Y1174358D01*
X160432Y1166025D01*
X163682Y1174358D01*
Y1164358D01*
G01X142266Y1247371D02*
Y1177117D01*
G01Y1254872D02*
G03I-2952J0D01*
G01Y1274557D02*
G03I-2952J0D01*
G01X193448Y1157431D02*
X161951D01*
G01D02*
X203290D01*
G01X161951Y1247721D02*
Y1177117D01*
G01Y1184991D02*
X193448D01*
G01D02*
X152109D01*
G01X161951Y1257825D02*
X167857D01*
G01Y1251920D02*
X161951D01*
G01D02*
Y1257825D01*
G01X167857Y1271605D02*
X161951D01*
G01D02*
Y1277510D01*
G01D02*
X167857D01*
G01Y1257825D02*
Y1251920D01*
G01Y1277510D02*
Y1271605D01*
G01X190682Y1134458D02*
X191432Y1133625D01*
X192307Y1133125D01*
X193432Y1132958D01*
X194557Y1133291D01*
X195432Y1133958D01*
X196057Y1135125D01*
X196182Y1136458D01*
X195932Y1137791D01*
X195307Y1138625D01*
X194432Y1139291D01*
X193557Y1139458D01*
X192682Y1139291D01*
X191557Y1138625D01*
X191932Y1142958D01*
X195307D01*
G01X200182Y1132958D02*
Y1142958D01*
X203432Y1134625D01*
X206682Y1142958D01*
Y1132958D01*
G01X210182D02*
Y1142958D01*
X213432Y1134625D01*
X216682Y1142958D01*
Y1132958D01*
G01X193448Y1247983D02*
Y1149557D01*
G01X213133Y1209133D02*
X181637D01*
G01D02*
X216085D01*
G01X187542Y1257825D02*
X193448D01*
G01Y1251920D02*
X187542D01*
G01X193448Y1257825D02*
Y1251920D01*
G01X187542D02*
Y1257825D01*
G01X193448Y1271605D02*
X187542D01*
G01X193448Y1277510D02*
Y1271605D01*
G01X187542D02*
Y1277510D01*
G01D02*
X193448D01*
G01X244629Y1157431D02*
X203290D01*
G01X221493Y-176864D02*
Y-251864D01*
G01Y-226864D02*
X324493D01*
Y-201864D01*
G01X221493D02*
X324493D01*
G01X213133Y1247983D02*
Y1149557D01*
G01Y1157431D02*
X244629D01*
G01X219038Y1247298D02*
Y1201259D01*
G01X213133Y1243799D02*
Y1201259D01*
G01X219038Y1209133D02*
X285564D01*
G01D02*
X216085D01*
G01X213133Y1257825D02*
X219038D01*
G01Y1251920D02*
X213133D01*
G01X219038Y1257825D02*
Y1251920D01*
G01X213133D02*
Y1257825D01*
G01X219038Y1271605D02*
X213133D01*
G01X219038Y1277510D02*
Y1271605D01*
G01X213133D02*
Y1277510D01*
G01X222975Y1271605D02*
X342705D01*
G01X213133Y1277510D02*
X219038D01*
G01X222975D02*
X342705D01*
G01X247847Y1212085D02*
Y1222085D01*
X246347Y1220085D01*
G01Y1212085D02*
X249347D01*
G01X257847Y1211752D02*
X257597Y1211918D01*
Y1212252D01*
X257847Y1212418D01*
X258097Y1212252D01*
Y1211918D01*
X257847Y1211752D01*
G01X265097Y1213585D02*
X265847Y1212752D01*
X266722Y1212252D01*
X267847Y1212085D01*
X268972Y1212418D01*
X269847Y1213085D01*
X270472Y1214252D01*
X270597Y1215585D01*
X270347Y1216918D01*
X269722Y1217752D01*
X268847Y1218418D01*
X267972Y1218585D01*
X267097Y1218418D01*
X265972Y1217752D01*
X266347Y1222085D01*
X269722D01*
G01X274597Y1212085D02*
Y1222085D01*
X277847Y1213752D01*
X281097Y1222085D01*
Y1212085D01*
G01X284597D02*
Y1222085D01*
X287847Y1213752D01*
X291097Y1222085D01*
Y1212085D01*
G01X325973Y1167597D02*
X315973D01*
X317973Y1166097D01*
G01X325973D02*
Y1169097D01*
G01X326306Y1177597D02*
X326140Y1177347D01*
X325806D01*
X325640Y1177597D01*
X325806Y1177847D01*
X326140D01*
X326306Y1177597D01*
G01X324473Y1184847D02*
X325306Y1185597D01*
X325806Y1186472D01*
X325973Y1187597D01*
X325640Y1188722D01*
X324973Y1189597D01*
X323806Y1190222D01*
X322473Y1190347D01*
X321140Y1190097D01*
X320306Y1189472D01*
X319640Y1188597D01*
X319473Y1187722D01*
X319640Y1186847D01*
X320306Y1185722D01*
X315973Y1186097D01*
Y1189472D01*
G01X325973Y1194347D02*
X315973D01*
X324306Y1197597D01*
X315973Y1200847D01*
X325973D01*
G01Y1204347D02*
X315973D01*
X324306Y1207597D01*
X315973Y1210847D01*
X325973D01*
G01X332000Y-236864D02*
Y-231864D01*
X333266D01*
X333773Y-232114D01*
X334153Y-232447D01*
X334470Y-232947D01*
X334723Y-233531D01*
X334786Y-234364D01*
X334723Y-235197D01*
X334470Y-235781D01*
X334153Y-236281D01*
X333773Y-236614D01*
X333266Y-236864D01*
X332000D01*
G01X336910D02*
X338493Y-231864D01*
X340076Y-236864D01*
G01X339506Y-235114D02*
X337480D01*
G01X343593Y-231864D02*
Y-236864D01*
G01X342136Y-231864D02*
X345050D01*
G01X349960Y-236864D02*
X347426D01*
Y-231864D01*
X349960D01*
G01X348946Y-234281D02*
X347426D01*
G01X353793Y-237031D02*
X353666Y-236947D01*
Y-236781D01*
X353793Y-236697D01*
X353920Y-236781D01*
Y-236947D01*
X353793Y-237031D01*
G01Y-234781D02*
X353666Y-234697D01*
Y-234531D01*
X353793Y-234447D01*
X353920Y-234531D01*
Y-234697D01*
X353793Y-234781D01*
G01X326493Y-176864D02*
Y-251864D01*
G01X324493Y-176864D02*
Y-251864D01*
G01X326493Y-226864D02*
X526493D01*
G01X332126Y-211864D02*
Y-206864D01*
X333646D01*
X334153Y-207114D01*
X334533Y-207697D01*
X334660Y-208364D01*
X334533Y-209031D01*
X334216Y-209531D01*
X333646Y-209781D01*
X332126D01*
G01X337353Y-212031D02*
X339633Y-206864D01*
G01X342136Y-211864D02*
Y-206864D01*
X345050Y-211864D01*
Y-206864D01*
G01X348693Y-212031D02*
X348566Y-211947D01*
Y-211781D01*
X348693Y-211697D01*
X348820Y-211781D01*
Y-211947D01*
X348693Y-212031D01*
G01Y-209781D02*
X348566Y-209697D01*
Y-209531D01*
X348693Y-209447D01*
X348820Y-209531D01*
Y-209697D01*
X348693Y-209781D01*
G01X326493Y-201864D02*
X526493D01*
G01X332126Y-186864D02*
Y-181864D01*
X333646D01*
X334153Y-182114D01*
X334533Y-182697D01*
X334660Y-183364D01*
X334533Y-184031D01*
X334216Y-184531D01*
X333646Y-184781D01*
X332126D01*
G01X337226Y-186864D02*
Y-181864D01*
X338810D01*
X339316Y-182114D01*
X339633Y-182447D01*
X339760Y-183114D01*
X339633Y-183781D01*
X339253Y-184197D01*
X338810Y-184447D01*
X337226D01*
G01X338810D02*
X339760Y-186864D01*
G01X343593D02*
X343086Y-186781D01*
X342643Y-186447D01*
X342263Y-185947D01*
X342010Y-185364D01*
X341883Y-184697D01*
Y-184031D01*
X342010Y-183364D01*
X342263Y-182781D01*
X342643Y-182281D01*
X343086Y-181947D01*
X343593Y-181864D01*
X344100Y-181947D01*
X344543Y-182281D01*
X344923Y-182781D01*
X345176Y-183364D01*
X345303Y-184031D01*
Y-184697D01*
X345176Y-185364D01*
X344923Y-185947D01*
X344543Y-186447D01*
X344100Y-186781D01*
X343593Y-186864D01*
G01X347426Y-185864D02*
X347743Y-186364D01*
X348123Y-186697D01*
X348566Y-186864D01*
X349073Y-186697D01*
X349453Y-186364D01*
X349833Y-185864D01*
X349960Y-185197D01*
Y-181864D01*
G01X355060Y-186864D02*
X352526D01*
Y-181864D01*
X355060D01*
G01X354046Y-184281D02*
X352526D01*
G01X360286Y-182281D02*
X359906Y-182031D01*
X359463Y-181864D01*
X358956D01*
X358386Y-182114D01*
X357943Y-182531D01*
X357626Y-183031D01*
X357373Y-183864D01*
X357310Y-184614D01*
X357436Y-185364D01*
X357626Y-185864D01*
X358006Y-186364D01*
X358450Y-186697D01*
X358893Y-186864D01*
X359336D01*
X359780Y-186697D01*
X360160Y-186447D01*
X360476Y-186114D01*
G01X363993Y-181864D02*
Y-186864D01*
G01X362536Y-181864D02*
X365450D01*
G01X369093Y-187031D02*
X368966Y-186947D01*
Y-186781D01*
X369093Y-186697D01*
X369220Y-186781D01*
Y-186947D01*
X369093Y-187031D01*
G01Y-184781D02*
X368966Y-184697D01*
Y-184531D01*
X369093Y-184447D01*
X369220Y-184531D01*
Y-184697D01*
X369093Y-184781D01*
G01X327026Y821652D02*
X328915Y819773D01*
X328976Y819712D01*
Y792323D01*
G03X336457I3740J0D01*
G01Y819673D01*
X336476Y819692D01*
X338446Y821652D01*
G01X328970Y822725D02*
Y845153D01*
G01X336431Y822707D02*
Y846647D01*
G01X334831Y1271605D02*
Y1175786D01*
G01D02*
Y1274557D01*
G01Y1277510D02*
Y1309006D01*
G01D02*
Y1274557D01*
G01X378606Y821652D02*
X338446D01*
G01X352266Y1422195D02*
Y1432195D01*
X350766Y1430195D01*
G01Y1422195D02*
X353766D01*
G01X362266Y1432195D02*
X361266Y1431862D01*
X360516Y1431028D01*
X360016Y1430028D01*
X359641Y1428695D01*
X359516Y1427195D01*
X359641Y1425695D01*
X360016Y1424362D01*
X360516Y1423361D01*
X361266Y1422528D01*
X362266Y1422195D01*
X363266Y1422528D01*
X364016Y1423361D01*
X364516Y1424362D01*
X364891Y1425695D01*
X365016Y1427195D01*
X364891Y1428695D01*
X364516Y1430028D01*
X364016Y1431028D01*
X363266Y1431862D01*
X362266Y1432195D01*
G01X372266D02*
X371266Y1431862D01*
X370516Y1431028D01*
X370016Y1430028D01*
X369641Y1428695D01*
X369516Y1427195D01*
X369641Y1425695D01*
X370016Y1424362D01*
X370516Y1423361D01*
X371266Y1422528D01*
X372266Y1422195D01*
X373266Y1422528D01*
X374016Y1423361D01*
X374516Y1424362D01*
X374891Y1425695D01*
X375016Y1427195D01*
X374891Y1428695D01*
X374516Y1430028D01*
X374016Y1431028D01*
X373266Y1431862D01*
X372266Y1432195D01*
G01X380641Y1425528D02*
X383891D01*
G01X392266Y1422195D02*
Y1432195D01*
X390766Y1430195D01*
G01Y1422195D02*
X393766D01*
G01X399516Y1423695D02*
X400266Y1422862D01*
X401141Y1422362D01*
X402266Y1422195D01*
X403391Y1422528D01*
X404266Y1423195D01*
X404891Y1424362D01*
X405016Y1425695D01*
X404766Y1427028D01*
X404141Y1427862D01*
X403266Y1428528D01*
X402391Y1428695D01*
X401516Y1428528D01*
X400391Y1427862D01*
X400766Y1432195D01*
X404141D01*
G01X412266D02*
X411266Y1431862D01*
X410516Y1431028D01*
X410016Y1430028D01*
X409641Y1428695D01*
X409516Y1427195D01*
X409641Y1425695D01*
X410016Y1424362D01*
X410516Y1423361D01*
X411266Y1422528D01*
X412266Y1422195D01*
X413266Y1422528D01*
X414016Y1423361D01*
X414516Y1424362D01*
X414891Y1425695D01*
X415016Y1427195D01*
X414891Y1428695D01*
X414516Y1430028D01*
X414016Y1431028D01*
X413266Y1431862D01*
X412266Y1432195D01*
G01X419016Y1422195D02*
Y1432195D01*
X422266Y1423862D01*
X425516Y1432195D01*
Y1422195D01*
G01X429016D02*
Y1432195D01*
X432266Y1423862D01*
X435516Y1432195D01*
Y1422195D01*
G01X378606Y821652D02*
X380551Y819707D01*
Y741142D01*
G01X380540Y822544D02*
Y847680D01*
G01X389839Y931117D02*
X787402D01*
G01X687542Y1419242D02*
X392266D01*
G01X413386Y374165D02*
Y-15363D01*
G01X406929Y741142D02*
Y819675D01*
X406946Y819692D01*
X408916Y821652D01*
G01X685296D02*
X408916D01*
G01X406929Y822628D02*
Y848972D01*
G01X416386Y377165D02*
X816568D01*
G01X447126Y-236864D02*
Y-231864D01*
X448710D01*
X449216Y-232114D01*
X449533Y-232447D01*
X449660Y-233114D01*
X449533Y-233781D01*
X449153Y-234197D01*
X448710Y-234447D01*
X447126D01*
G01X448710D02*
X449660Y-236864D01*
G01X454760D02*
X452226D01*
Y-231864D01*
X454760D01*
G01X453746Y-234281D02*
X452226D01*
G01X457010Y-231864D02*
X458593Y-236864D01*
X460176Y-231864D01*
G01X463693Y-237031D02*
X463566Y-236947D01*
Y-236781D01*
X463693Y-236697D01*
X463820Y-236781D01*
Y-236947D01*
X463693Y-237031D01*
G01Y-234781D02*
X463566Y-234697D01*
Y-234531D01*
X463693Y-234447D01*
X463820Y-234531D01*
Y-234697D01*
X463693Y-234781D01*
G01X441493Y-226864D02*
Y-251864D01*
G01X490493Y-226864D02*
Y-251864D01*
G01X481102Y31528D02*
Y-34967D01*
G01X484102Y34528D02*
X796734D01*
G01X636932Y1398058D02*
Y1408058D01*
X632307Y1400891D01*
X638557D01*
G01X642182Y1398058D02*
Y1408058D01*
X645432Y1399725D01*
X648682Y1408058D01*
Y1398058D01*
G01X652182D02*
Y1408058D01*
X655432Y1399725D01*
X658682Y1408058D01*
Y1398058D01*
G01X671794Y1391683D02*
X640298D01*
G01D02*
X679668D01*
G01X697857Y96166D02*
G02X680096I-8880J-10536D01*
G03X681496Y99177I-2537J3011D01*
G01Y105315D01*
G02X696457I7481J0D01*
G01Y99177D01*
G03X697857Y96166I3937J0D01*
G01D02*
G02X680096I-8880J-10536D01*
G03X681496Y99177I-2537J3011D01*
G01Y105315D01*
G02X696457I7481J0D01*
G01Y99177D01*
G03X697857Y96166I3937J0D01*
G01D02*
G02X680096I-8880J-10536D01*
G03X681496Y99177I-2537J3011D01*
G01Y105315D01*
G02X696457I7481J0D01*
G01Y99177D01*
G03X697857Y96166I3937J0D01*
G01D02*
G02X680096I-8880J-10536D01*
G03X681496Y99177I-2537J3011D01*
G01Y105315D01*
G02X696457I7481J0D01*
G01Y99177D01*
G03X697857Y96166I3937J0D01*
G01X681496Y713350D02*
Y719488D01*
G02X696457I7481J0D01*
G01Y713350D01*
G03X697857Y710340I3937J0D01*
G02X680096I-8880J-10537D01*
G03X681496Y713350I-2537J3011D01*
G01D02*
Y719488D01*
G02X696457I7481J0D01*
G01Y713350D01*
G03X697857Y710340I3937J0D01*
G02X680096I-8880J-10537D01*
G03X681496Y713350I-2537J3011D01*
G01D02*
Y719488D01*
G02X696457I7481J0D01*
G01Y713350D01*
G03X697857Y710340I3937J0D01*
G02X680096I-8880J-10537D01*
G03X681496Y713350I-2537J3011D01*
G01D02*
Y719488D01*
G02X696457I7481J0D01*
G01Y713350D01*
G03X697857Y710340I3937J0D01*
G02X680096I-8880J-10537D01*
G03X681496Y713350I-2537J3011D01*
G01X671794Y1316880D02*
X687542Y1324754D01*
G01X722975Y1336565D02*
X679668D01*
G01X722975Y1332628D02*
X679668D01*
G01X687542Y1324754D02*
X671794Y1332628D01*
G01Y1336565D02*
X687542Y1344439D01*
G01D02*
X671794Y1352313D01*
G01Y1356250D02*
Y1399557D01*
G01X719038Y1391683D02*
X679668D01*
G01X688977Y716488D02*
Y-24152D01*
G01X696716Y821652D02*
X694746Y819692D01*
X694724Y819670D01*
Y792323D01*
G02X687244I-3740J0D01*
G01Y819710D01*
X686388Y820566D01*
X685296Y821652D01*
G01X736866D02*
X696716D01*
G01X687244Y821647D02*
Y856434D01*
G01X694724Y821211D02*
Y855250D01*
G01X687542Y1348376D02*
Y1399557D01*
G01Y1348376D02*
Y1427117D01*
G01Y1391683D02*
X719038D01*
G01X703594Y1293450D02*
Y1336757D01*
G01X730075Y0D02*
X907360D01*
G01X730075Y821654D02*
X907360D01*
G01X727532Y1301258D02*
X717532D01*
X719532Y1299758D01*
G01X727532D02*
Y1302758D01*
G01Y1308008D02*
X717532D01*
X725865Y1311258D01*
X717532Y1314508D01*
X727532D01*
G01Y1318008D02*
X717532D01*
X725865Y1321258D01*
X717532Y1324508D01*
X727532D01*
G01X787402Y681338D02*
Y934117D01*
G01X782402Y930117D02*
X787402Y931117D01*
X782402Y932117D01*
Y930117D01*
G01X903360Y5000D02*
X904360Y0D01*
X905360Y5000D01*
X903360D01*
G01X905360Y816654D02*
X904360Y821654D01*
X903360Y816654D01*
X905360D01*
G01X904360Y428267D02*
Y0D01*
G01Y480817D02*
Y821654D01*
G01X985393Y18075D02*
Y28075D01*
X987893D01*
X988893Y27575D01*
X989643Y26908D01*
X990268Y25908D01*
X990768Y24741D01*
X990893Y23075D01*
X990768Y21408D01*
X990268Y20242D01*
X989643Y19241D01*
X988893Y18575D01*
X987893Y18075D01*
X985393D01*
G01X1000643D02*
X995643D01*
Y28075D01*
X1000643D01*
G01X998643Y23242D02*
X995643D01*
G01X1008143Y28075D02*
Y18075D01*
G01X1005268Y28075D02*
X1011018D01*
G01X1015018Y18075D02*
X1018143Y28075D01*
X1021268Y18075D01*
G01X1020143Y21575D02*
X1016143D01*
G01X1026643Y28075D02*
X1029643D01*
G01X1028143D02*
Y18075D01*
G01X1026643D02*
X1029643D01*
G01X1035643Y28075D02*
Y18075D01*
X1040643D01*
G01X1055018D02*
X1058143Y28075D01*
X1061268Y18075D01*
G01X1060143Y21575D02*
X1056143D01*
G01X1069971Y10570D02*
Y1016670D01*
X1346771D01*
Y10570D01*
X1069971D01*
G01Y42520D02*
X1346771D01*
G01X1069971Y74470D02*
X1346771D01*
G01X1069971Y106420D02*
X1346771D01*
G01X1069971Y138370D02*
X1346771D01*
G01X1069971Y170320D02*
X1346771D01*
G01X1069971Y202270D02*
X1346771D01*
G01X1069971Y234220D02*
X1346771D01*
G01X1069971Y266170D02*
X1346771D01*
G01X1069971Y298120D02*
X1346771D01*
G01X1069971Y330070D02*
X1346771D01*
G01X1069971Y362020D02*
X1346771D01*
G01X1069971Y393970D02*
X1346771D01*
G01X1069971Y425920D02*
X1346771D01*
G01X1069971Y457870D02*
X1346771D01*
G01X1069971Y489820D02*
X1346771D01*
G01X1069971Y521770D02*
X1346771D01*
G01X1069971Y553720D02*
X1346771D01*
G01X1069971Y585670D02*
X1346771D01*
G01X1069971Y617620D02*
X1346771D01*
G01X1069971Y649570D02*
X1346771D01*
G01X1069971Y681520D02*
X1346771D01*
G01X1069971Y713470D02*
X1346771D01*
G01X1069971Y745420D02*
X1346771D01*
G01X1069971Y777370D02*
X1346771D01*
G01X1069971Y809320D02*
X1346771D01*
G01X1069971Y841270D02*
X1346771D01*
G01X1069971Y873220D02*
X1346771D01*
G01X1069971Y905170D02*
X1346771D01*
G01X1069971Y937120D02*
X1346771D01*
G01X1069971Y969070D02*
X1346771D01*
G01X1069971Y980370D02*
X1346771D01*
G01X1069971Y991670D02*
X1346771D01*
G01X1106971Y980370D02*
Y10570D01*
G01X1184771Y980370D02*
Y10570D01*
G01X1262571Y980370D02*
Y10570D01*
G01X1314871Y980370D02*
Y10570D01*
G01X1656118Y153247D02*
G03I-95259J0D01*
G01X1492221Y168647D02*
X1492691Y169277D01*
X1493239Y169592D01*
X1493866Y169697D01*
X1494649Y169487D01*
X1495197Y168962D01*
X1495354Y168332D01*
X1495276Y167702D01*
X1494962Y167177D01*
X1493396Y166127D01*
X1492691Y165392D01*
X1492221Y164342D01*
X1492064Y163397D01*
X1495354D01*
G01X1500009D02*
X1500557Y163502D01*
X1501184Y163817D01*
X1501576Y164342D01*
X1501732Y165077D01*
X1501576Y165812D01*
X1501106Y166442D01*
X1500401Y166757D01*
X1499617D01*
X1499147Y166967D01*
X1498756Y167492D01*
X1498599Y168227D01*
X1498834Y168962D01*
X1499382Y169487D01*
X1500009Y169697D01*
X1500636Y169487D01*
X1501184Y168962D01*
X1501419Y168227D01*
X1501262Y167492D01*
X1500871Y166967D01*
X1500401Y166757D01*
X1499617D01*
X1498912Y166442D01*
X1498442Y165812D01*
X1498286Y165077D01*
X1498442Y164342D01*
X1498834Y163817D01*
X1499461Y163502D01*
X1500009Y163397D01*
G01X1506309Y163187D02*
X1506152Y163292D01*
Y163502D01*
X1506309Y163607D01*
X1506466Y163502D01*
Y163292D01*
X1506309Y163187D01*
G01X1512609Y169697D02*
X1511982Y169487D01*
X1511512Y168962D01*
X1511199Y168332D01*
X1510964Y167492D01*
X1510886Y166547D01*
X1510964Y165602D01*
X1511199Y164762D01*
X1511512Y164132D01*
X1511982Y163607D01*
X1512609Y163397D01*
X1513236Y163607D01*
X1513706Y164132D01*
X1514019Y164762D01*
X1514254Y165602D01*
X1514332Y166547D01*
X1514254Y167492D01*
X1514019Y168332D01*
X1513706Y168962D01*
X1513236Y169487D01*
X1512609Y169697D01*
G01X1518909D02*
X1518282Y169487D01*
X1517812Y168962D01*
X1517499Y168332D01*
X1517264Y167492D01*
X1517186Y166547D01*
X1517264Y165602D01*
X1517499Y164762D01*
X1517812Y164132D01*
X1518282Y163607D01*
X1518909Y163397D01*
X1519536Y163607D01*
X1520006Y164132D01*
X1520319Y164762D01*
X1520554Y165602D01*
X1520632Y166547D01*
X1520554Y167492D01*
X1520319Y168332D01*
X1520006Y168962D01*
X1519536Y169487D01*
X1518909Y169697D01*
G01X1535792Y82747D02*
X1534859Y83997D01*
X1534392Y85247D01*
Y90247D01*
X1534859Y91497D01*
X1535792Y92747D01*
G01X1541892Y85247D02*
Y92747D01*
X1544132D01*
X1544879Y92372D01*
X1545439Y91497D01*
X1545626Y90497D01*
X1545439Y89497D01*
X1544972Y88747D01*
X1544132Y88372D01*
X1541892D01*
G01X1549392Y92747D02*
Y85247D01*
X1553126D01*
G01X1556426D02*
X1558759Y92747D01*
X1561092Y85247D01*
G01X1560252Y87872D02*
X1557266D01*
G01X1566259Y92747D02*
Y85247D01*
G01X1564112Y92747D02*
X1568406D01*
G01X1575626Y85247D02*
X1571892D01*
Y92747D01*
X1575626D01*
G01X1574132Y89122D02*
X1571892D01*
G01X1579206Y85247D02*
Y92747D01*
X1581072D01*
X1581819Y92372D01*
X1582379Y91872D01*
X1582846Y91122D01*
X1583219Y90247D01*
X1583312Y88997D01*
X1583219Y87747D01*
X1582846Y86872D01*
X1582379Y86122D01*
X1581819Y85622D01*
X1581072Y85247D01*
X1579206D01*
G01X1589226Y82747D02*
X1590159Y83997D01*
X1590626Y85247D01*
Y90247D01*
X1590159Y91497D01*
X1589226Y92747D01*
G01X1532284Y166547D02*
X1553059D01*
G01X1531112Y208247D02*
Y215747D01*
X1535406Y208247D01*
Y215747D01*
G01X1540759Y208247D02*
X1540012Y208372D01*
X1539359Y208872D01*
X1538799Y209622D01*
X1538426Y210497D01*
X1538239Y211497D01*
Y212497D01*
X1538426Y213497D01*
X1538799Y214372D01*
X1539359Y215122D01*
X1540012Y215622D01*
X1540759Y215747D01*
X1541506Y215622D01*
X1542159Y215122D01*
X1542719Y214372D01*
X1543092Y213497D01*
X1543279Y212497D01*
Y211497D01*
X1543092Y210497D01*
X1542719Y209622D01*
X1542159Y208872D01*
X1541506Y208372D01*
X1540759Y208247D01*
G01X1553799Y209247D02*
X1554546Y208622D01*
X1555386Y208247D01*
X1556132D01*
X1556879Y208622D01*
X1557439Y209247D01*
X1557719Y210122D01*
X1557532Y210997D01*
X1557066Y211747D01*
X1556226Y212247D01*
X1555106Y212497D01*
X1554452Y212997D01*
X1554172Y213872D01*
X1554359Y214747D01*
X1554826Y215372D01*
X1555479Y215747D01*
X1556132D01*
X1556786Y215497D01*
X1557346Y214872D01*
G01X1565312Y215122D02*
X1564752Y215497D01*
X1564099Y215747D01*
X1563352D01*
X1562512Y215372D01*
X1561859Y214747D01*
X1561392Y213997D01*
X1561019Y212747D01*
X1560926Y211622D01*
X1561112Y210497D01*
X1561392Y209747D01*
X1561952Y208997D01*
X1562606Y208497D01*
X1563259Y208247D01*
X1563912D01*
X1564566Y208497D01*
X1565126Y208872D01*
X1565592Y209372D01*
G01X1568426Y208247D02*
X1570759Y215747D01*
X1573092Y208247D01*
G01X1572252Y210872D02*
X1569266D01*
G01X1576392Y215747D02*
Y208247D01*
X1580126D01*
G01X1587626D02*
X1583892D01*
Y215747D01*
X1587626D01*
G01X1586132Y212122D02*
X1583892D01*
G01X1523959Y220747D02*
Y230747D01*
X1526459D01*
X1527459Y230247D01*
X1528209Y229580D01*
X1528834Y228580D01*
X1529334Y227413D01*
X1529459Y225747D01*
X1529334Y224080D01*
X1528834Y222914D01*
X1528209Y221913D01*
X1527459Y221247D01*
X1526459Y220747D01*
X1523959D01*
G01X1539209D02*
X1534209D01*
Y230747D01*
X1539209D01*
G01X1537209Y225914D02*
X1534209D01*
G01X1546709Y230747D02*
Y220747D01*
G01X1543834Y230747D02*
X1549584D01*
G01X1553584Y220747D02*
X1556709Y230747D01*
X1559834Y220747D01*
G01X1558709Y224247D02*
X1554709D01*
G01X1565209Y230747D02*
X1568209D01*
G01X1566709D02*
Y220747D01*
G01X1565209D02*
X1568209D01*
G01X1574209Y230747D02*
Y220747D01*
X1579209D01*
G01X1593584D02*
X1596709Y230747D01*
X1599834Y220747D01*
G01X1598709Y224247D02*
X1594709D01*
G01X1522959Y218247D02*
X1602959D01*
G01X1548842Y67547D02*
X1547909Y68797D01*
X1547442Y70047D01*
Y75047D01*
X1547909Y76297D01*
X1548842Y77547D01*
G01X1555036Y76297D02*
X1555596Y77047D01*
X1556249Y77422D01*
X1556996Y77547D01*
X1557929Y77297D01*
X1558582Y76672D01*
X1558769Y75922D01*
X1558676Y75172D01*
X1558302Y74547D01*
X1556436Y73297D01*
X1555596Y72422D01*
X1555036Y71172D01*
X1554849Y70047D01*
X1558769D01*
G01X1562349D02*
X1566269Y77547D01*
G01X1562349D02*
X1566269Y70047D01*
G01X1572276Y67547D02*
X1573209Y68797D01*
X1573676Y70047D01*
Y75047D01*
X1573209Y76297D01*
X1572276Y77547D01*
G01X1553059Y118847D02*
Y138047D01*
G01Y118847D02*
G03X1568659I7800J0D01*
G01Y138047D02*
G03X1553059I-7800J0D01*
G01Y143247D02*
Y170547D01*
G01X1563659Y165547D02*
X1568659Y166547D01*
X1563659Y167547D01*
Y165547D01*
G01X1553059Y166547D02*
X1568659D01*
G01X1558059Y167547D02*
X1553059Y166547D01*
X1558059Y165547D01*
Y167547D01*
G01X1565859Y111047D02*
X1611859D01*
G01X1568659Y138047D02*
Y118847D01*
G01X1565859Y145847D02*
X1611859D01*
G01X1568659Y143247D02*
Y170547D01*
G01X1606859Y116047D02*
X1607859Y111047D01*
X1608859Y116047D01*
X1606859D01*
G01X1607859Y145847D02*
Y111047D01*
G01X1608859Y140847D02*
X1607859Y145847D01*
X1606859Y140847D01*
X1608859D01*
G01X1607859Y159922D02*
Y145847D01*
G01X1611009Y166997D02*
X1604709D01*
X1605969Y166057D01*
G01X1611009D02*
Y167937D01*
G01X1605759Y171809D02*
X1605129Y172279D01*
X1604814Y172827D01*
X1604709Y173454D01*
X1604919Y174237D01*
X1605444Y174785D01*
X1606074Y174942D01*
X1606704Y174864D01*
X1607229Y174550D01*
X1608279Y172984D01*
X1609014Y172279D01*
X1610064Y171809D01*
X1611009Y171652D01*
Y174942D01*
G01Y180537D02*
X1604709D01*
X1609224Y177639D01*
Y181555D01*
G01X1611219Y185897D02*
X1611114Y185740D01*
X1610904D01*
X1610799Y185897D01*
X1610904Y186054D01*
X1611114D01*
X1611219Y185897D01*
G01X1604709Y192197D02*
X1604919Y191570D01*
X1605444Y191100D01*
X1606074Y190787D01*
X1606914Y190552D01*
X1607859Y190474D01*
X1608804Y190552D01*
X1609644Y190787D01*
X1610274Y191100D01*
X1610799Y191570D01*
X1611009Y192197D01*
X1610799Y192824D01*
X1610274Y193294D01*
X1609644Y193607D01*
X1608804Y193842D01*
X1607859Y193920D01*
X1606914Y193842D01*
X1606074Y193607D01*
X1605444Y193294D01*
X1604919Y192824D01*
X1604709Y192197D01*
G01Y198497D02*
X1604919Y197870D01*
X1605444Y197400D01*
X1606074Y197087D01*
X1606914Y196852D01*
X1607859Y196774D01*
X1608804Y196852D01*
X1609644Y197087D01*
X1610274Y197400D01*
X1610799Y197870D01*
X1611009Y198497D01*
X1610799Y199124D01*
X1610274Y199594D01*
X1609644Y199907D01*
X1608804Y200142D01*
X1607859Y200220D01*
X1606914Y200142D01*
X1606074Y199907D01*
X1605444Y199594D01*
X1604919Y199124D01*
X1604709Y198497D01*
G01X-1043962Y-705877D02*
Y2342823D01*
X2300638D01*
Y-705877D01*
X-1043962D01*
G01X-102533Y3150D02*
X-103160Y2940D01*
X-103630Y2415D01*
X-103943Y1785D01*
X-104178Y945D01*
X-104256Y0D01*
X-104178Y-945D01*
X-103943Y-1785D01*
X-103630Y-2415D01*
X-103160Y-2940D01*
X-102533Y-3150D01*
X-101906Y-2940D01*
X-101436Y-2415D01*
X-101123Y-1785D01*
X-100888Y-945D01*
X-100810Y0D01*
X-100888Y945D01*
X-101123Y1785D01*
X-101436Y2415D01*
X-101906Y2940D01*
X-102533Y3150D01*
G01X0Y-81077D02*
X-627Y-81287D01*
X-1097Y-81812D01*
X-1410Y-82442D01*
X-1645Y-83282D01*
X-1723Y-84227D01*
X-1645Y-85172D01*
X-1410Y-86012D01*
X-1097Y-86642D01*
X-627Y-87167D01*
X0Y-87377D01*
X627Y-87167D01*
X1097Y-86642D01*
X1410Y-86012D01*
X1645Y-85172D01*
X1723Y-84227D01*
X1645Y-83282D01*
X1410Y-82442D01*
X1097Y-81812D01*
X627Y-81287D01*
X0Y-81077D01*
G01X30232Y1551258D02*
X30832Y1550591D01*
X31532Y1550191D01*
X32432Y1550058D01*
X33332Y1550325D01*
X34032Y1550858D01*
X34532Y1551791D01*
X34632Y1552858D01*
X34432Y1553925D01*
X33932Y1554591D01*
X33232Y1555125D01*
X32532Y1555258D01*
X31832Y1555125D01*
X30932Y1554591D01*
X31232Y1558058D01*
X33932D01*
G01X40432Y1549791D02*
X40232Y1549925D01*
Y1550191D01*
X40432Y1550325D01*
X40632Y1550191D01*
Y1549925D01*
X40432Y1549791D01*
G01X46432Y1550058D02*
Y1558058D01*
X48832D01*
X49632Y1557658D01*
X50232Y1556725D01*
X50432Y1555658D01*
X50232Y1554591D01*
X49732Y1553791D01*
X48832Y1553391D01*
X46432D01*
G01X58432Y1550058D02*
X54432D01*
Y1558058D01*
X58432D01*
G01X56832Y1554191D02*
X54432D01*
G01X66432Y1550058D02*
X62432D01*
Y1558058D01*
X66432D01*
G01X64832Y1554191D02*
X62432D01*
G01X70432Y1558058D02*
Y1550058D01*
X74432D01*
G01X79232Y1558058D02*
X81632D01*
G01X80432D02*
Y1550058D01*
G01X79232D02*
X81632D01*
G01X86132D02*
Y1558058D01*
X90732Y1550058D01*
Y1558058D01*
G01X97032Y1554058D02*
X99032D01*
Y1551658D01*
X98432Y1550858D01*
X97732Y1550325D01*
X96732Y1550058D01*
X95732Y1550325D01*
X95032Y1550858D01*
X94432Y1551658D01*
X94032Y1552591D01*
X93832Y1553658D01*
Y1554591D01*
X94032Y1555391D01*
X94432Y1556325D01*
X95032Y1557125D01*
X95632Y1557658D01*
X96432Y1558058D01*
X97132D01*
X97932Y1557791D01*
X98532Y1557258D01*
G01X110332Y1551124D02*
X111132Y1550458D01*
X112032Y1550058D01*
X112832D01*
X113632Y1550458D01*
X114232Y1551124D01*
X114532Y1552058D01*
X114332Y1552991D01*
X113832Y1553791D01*
X112932Y1554325D01*
X111732Y1554591D01*
X111032Y1555125D01*
X110732Y1556058D01*
X110932Y1556991D01*
X111432Y1557658D01*
X112132Y1558058D01*
X112832D01*
X113532Y1557791D01*
X114132Y1557125D01*
G01X120432Y1558058D02*
Y1550058D01*
G01X118132Y1558058D02*
X122732D01*
G01X126432Y1550058D02*
Y1558058D01*
X128932D01*
X129732Y1557658D01*
X130232Y1557125D01*
X130432Y1556058D01*
X130232Y1554991D01*
X129632Y1554325D01*
X128932Y1553925D01*
X126432D01*
G01X128932D02*
X130432Y1550058D01*
G01X138432D02*
X134432D01*
Y1558058D01*
X138432D01*
G01X136832Y1554191D02*
X134432D01*
G01X142132Y1550058D02*
Y1558058D01*
X146732Y1550058D01*
Y1558058D01*
G01X153032Y1554058D02*
X155032D01*
Y1551658D01*
X154432Y1550858D01*
X153732Y1550325D01*
X152732Y1550058D01*
X151732Y1550325D01*
X151032Y1550858D01*
X150432Y1551658D01*
X150032Y1552591D01*
X149832Y1553658D01*
Y1554591D01*
X150032Y1555391D01*
X150432Y1556325D01*
X151032Y1557125D01*
X151632Y1557658D01*
X152432Y1558058D01*
X153132D01*
X153932Y1557791D01*
X154532Y1557258D01*
G01X160432Y1558058D02*
Y1550058D01*
G01X158132Y1558058D02*
X162732D01*
G01X166332Y1550058D02*
Y1558058D01*
G01X170532D02*
Y1550058D01*
G01Y1554058D02*
X166332D01*
G01X181932Y1550058D02*
X184432Y1558058D01*
X186932Y1550058D01*
G01X186032Y1552858D02*
X182832D01*
G01X190132Y1550058D02*
Y1558058D01*
X194732Y1550058D01*
Y1558058D01*
G01X198232Y1550058D02*
Y1558058D01*
X200232D01*
X201032Y1557658D01*
X201632Y1557125D01*
X202132Y1556325D01*
X202532Y1555391D01*
X202632Y1554058D01*
X202532Y1552725D01*
X202132Y1551791D01*
X201632Y1550991D01*
X201032Y1550458D01*
X200232Y1550058D01*
X198232D01*
G01X217232Y1554325D02*
X217632Y1554725D01*
X217932Y1555391D01*
X218132Y1556325D01*
X217932Y1557125D01*
X217532Y1557658D01*
X216832Y1558058D01*
X214132D01*
Y1550058D01*
X217432D01*
X218132Y1550591D01*
X218532Y1551391D01*
X218732Y1552325D01*
X218532Y1553258D01*
X217932Y1554058D01*
X217232Y1554325D01*
X214132D01*
G01X225032Y1554058D02*
X227032D01*
Y1551658D01*
X226432Y1550858D01*
X225732Y1550325D01*
X224732Y1550058D01*
X223732Y1550325D01*
X223032Y1550858D01*
X222432Y1551658D01*
X222032Y1552591D01*
X221832Y1553658D01*
Y1554591D01*
X222032Y1555391D01*
X222432Y1556325D01*
X223032Y1557125D01*
X223632Y1557658D01*
X224432Y1558058D01*
X225132D01*
X225932Y1557791D01*
X226532Y1557258D01*
G01X229932Y1550058D02*
X232432Y1558058D01*
X234932Y1550058D01*
G01X234032Y1552858D02*
X230832D01*
G01X246432Y1550058D02*
Y1558058D01*
X248832D01*
X249632Y1557658D01*
X250232Y1556725D01*
X250432Y1555658D01*
X250232Y1554591D01*
X249732Y1553791D01*
X248832Y1553391D01*
X246432D01*
G01X253932Y1550058D02*
X256432Y1558058D01*
X258932Y1550058D01*
G01X258032Y1552858D02*
X254832D01*
G01X262232Y1550058D02*
Y1558058D01*
X264232D01*
X265032Y1557658D01*
X265632Y1557125D01*
X266132Y1556325D01*
X266532Y1555391D01*
X266632Y1554058D01*
X266532Y1552725D01*
X266132Y1551791D01*
X265632Y1550991D01*
X265032Y1550458D01*
X264232Y1550058D01*
X262232D01*
G01X270332Y1551124D02*
X271132Y1550458D01*
X272032Y1550058D01*
X272832D01*
X273632Y1550458D01*
X274232Y1551124D01*
X274532Y1552058D01*
X274332Y1552991D01*
X273832Y1553791D01*
X272932Y1554325D01*
X271732Y1554591D01*
X271032Y1555125D01*
X270732Y1556058D01*
X270932Y1556991D01*
X271432Y1557658D01*
X272132Y1558058D01*
X272832D01*
X273532Y1557791D01*
X274132Y1557125D01*
G01X285932Y1550058D02*
X288432Y1558058D01*
X290932Y1550058D01*
G01X290032Y1552858D02*
X286832D01*
G01X294232Y1550058D02*
Y1558058D01*
X296232D01*
X297032Y1557658D01*
X297632Y1557125D01*
X298132Y1556325D01*
X298532Y1555391D01*
X298632Y1554058D01*
X298532Y1552725D01*
X298132Y1551791D01*
X297632Y1550991D01*
X297032Y1550458D01*
X296232Y1550058D01*
X294232D01*
G01X302332D02*
Y1558058D01*
G01X306532D02*
Y1550058D01*
G01Y1554058D02*
X302332D01*
G01X314432Y1550058D02*
X310432D01*
Y1558058D01*
X314432D01*
G01X312832Y1554191D02*
X310432D01*
G01X318332Y1551124D02*
X319132Y1550458D01*
X320032Y1550058D01*
X320832D01*
X321632Y1550458D01*
X322232Y1551124D01*
X322532Y1552058D01*
X322332Y1552991D01*
X321832Y1553791D01*
X320932Y1554325D01*
X319732Y1554591D01*
X319032Y1555125D01*
X318732Y1556058D01*
X318932Y1556991D01*
X319432Y1557658D01*
X320132Y1558058D01*
X320832D01*
X321532Y1557791D01*
X322132Y1557125D01*
G01X327232Y1558058D02*
X329632D01*
G01X328432D02*
Y1550058D01*
G01X327232D02*
X329632D01*
G01X336432D02*
X335632Y1550191D01*
X334932Y1550725D01*
X334332Y1551525D01*
X333932Y1552458D01*
X333732Y1553525D01*
Y1554591D01*
X333932Y1555658D01*
X334332Y1556591D01*
X334932Y1557391D01*
X335632Y1557925D01*
X336432Y1558058D01*
X337232Y1557925D01*
X337932Y1557391D01*
X338532Y1556591D01*
X338932Y1555658D01*
X339132Y1554591D01*
Y1553525D01*
X338932Y1552458D01*
X338532Y1551525D01*
X337932Y1550725D01*
X337232Y1550191D01*
X336432Y1550058D01*
G01X342132D02*
Y1558058D01*
X346732Y1550058D01*
Y1558058D01*
G01X360432D02*
Y1550058D01*
G01X358132Y1558058D02*
X362732D01*
G01X370432Y1550058D02*
X366432D01*
Y1558058D01*
X370432D01*
G01X368832Y1554191D02*
X366432D01*
G01X374332Y1551124D02*
X375132Y1550458D01*
X376032Y1550058D01*
X376832D01*
X377632Y1550458D01*
X378232Y1551124D01*
X378532Y1552058D01*
X378332Y1552991D01*
X377832Y1553791D01*
X376932Y1554325D01*
X375732Y1554591D01*
X375032Y1555125D01*
X374732Y1556058D01*
X374932Y1556991D01*
X375432Y1557658D01*
X376132Y1558058D01*
X376832D01*
X377532Y1557791D01*
X378132Y1557125D01*
G01X384432Y1558058D02*
Y1550058D01*
G01X382132Y1558058D02*
X386732D01*
G01X398432Y1550058D02*
Y1558058D01*
X400832D01*
X401632Y1557658D01*
X402232Y1556725D01*
X402432Y1555658D01*
X402232Y1554591D01*
X401732Y1553791D01*
X400832Y1553391D01*
X398432D01*
G01X405932Y1550058D02*
X408432Y1558058D01*
X410932Y1550058D01*
G01X410032Y1552858D02*
X406832D01*
G01X416432Y1558058D02*
Y1550058D01*
G01X414132Y1558058D02*
X418732D01*
G01X424432D02*
Y1550058D01*
G01X422132Y1558058D02*
X426732D01*
G01X434432Y1550058D02*
X430432D01*
Y1558058D01*
X434432D01*
G01X432832Y1554191D02*
X430432D01*
G01X438432Y1550058D02*
Y1558058D01*
X440932D01*
X441732Y1557658D01*
X442232Y1557125D01*
X442432Y1556058D01*
X442232Y1554991D01*
X441632Y1554325D01*
X440932Y1553925D01*
X438432D01*
G01X440932D02*
X442432Y1550058D01*
G01X446132D02*
Y1558058D01*
X450732Y1550058D01*
Y1558058D01*
G01X454332Y1551124D02*
X455132Y1550458D01*
X456032Y1550058D01*
X456832D01*
X457632Y1550458D01*
X458232Y1551124D01*
X458532Y1552058D01*
X458332Y1552991D01*
X457832Y1553791D01*
X456932Y1554325D01*
X455732Y1554591D01*
X455032Y1555125D01*
X454732Y1556058D01*
X454932Y1556991D01*
X455432Y1557658D01*
X456132Y1558058D01*
X456832D01*
X457532Y1557791D01*
X458132Y1557125D01*
G01X464432Y1549791D02*
X464232Y1549925D01*
Y1550191D01*
X464432Y1550325D01*
X464632Y1550191D01*
Y1549925D01*
X464432Y1549791D01*
G01X33632Y1640058D02*
Y1648058D01*
X29932Y1642325D01*
X34932D01*
G01X40432Y1639791D02*
X40232Y1639925D01*
Y1640191D01*
X40432Y1640325D01*
X40632Y1640191D01*
Y1639925D01*
X40432Y1639791D01*
G01X50632Y1647391D02*
X50032Y1647791D01*
X49332Y1648058D01*
X48532D01*
X47632Y1647658D01*
X46932Y1646991D01*
X46432Y1646191D01*
X46032Y1644858D01*
X45932Y1643658D01*
X46132Y1642458D01*
X46432Y1641658D01*
X47032Y1640858D01*
X47732Y1640325D01*
X48432Y1640058D01*
X49132D01*
X49832Y1640325D01*
X50432Y1640725D01*
X50932Y1641258D01*
G01X56432Y1640058D02*
X55632Y1640191D01*
X54932Y1640725D01*
X54332Y1641525D01*
X53932Y1642458D01*
X53732Y1643525D01*
Y1644591D01*
X53932Y1645658D01*
X54332Y1646591D01*
X54932Y1647391D01*
X55632Y1647925D01*
X56432Y1648058D01*
X57232Y1647925D01*
X57932Y1647391D01*
X58532Y1646591D01*
X58932Y1645658D01*
X59132Y1644591D01*
Y1643525D01*
X58932Y1642458D01*
X58532Y1641525D01*
X57932Y1640725D01*
X57232Y1640191D01*
X56432Y1640058D01*
G01X62132D02*
Y1648058D01*
X66732Y1640058D01*
Y1648058D01*
G01X72432D02*
Y1640058D01*
G01X70132Y1648058D02*
X74732D01*
G01X78432Y1640058D02*
Y1648058D01*
X80932D01*
X81732Y1647658D01*
X82232Y1647125D01*
X82432Y1646058D01*
X82232Y1644991D01*
X81632Y1644325D01*
X80932Y1643925D01*
X78432D01*
G01X80932D02*
X82432Y1640058D01*
G01X88432D02*
X87632Y1640191D01*
X86932Y1640725D01*
X86332Y1641525D01*
X85932Y1642458D01*
X85732Y1643525D01*
Y1644591D01*
X85932Y1645658D01*
X86332Y1646591D01*
X86932Y1647391D01*
X87632Y1647925D01*
X88432Y1648058D01*
X89232Y1647925D01*
X89932Y1647391D01*
X90532Y1646591D01*
X90932Y1645658D01*
X91132Y1644591D01*
Y1643525D01*
X90932Y1642458D01*
X90532Y1641525D01*
X89932Y1640725D01*
X89232Y1640191D01*
X88432Y1640058D01*
G01X94432Y1648058D02*
Y1640058D01*
X98432D01*
G01X102432Y1648058D02*
Y1640058D01*
X106432D01*
G01X114432D02*
X110432D01*
Y1648058D01*
X114432D01*
G01X112832Y1644191D02*
X110432D01*
G01X118232Y1640058D02*
Y1648058D01*
X120232D01*
X121032Y1647658D01*
X121632Y1647125D01*
X122132Y1646325D01*
X122532Y1645391D01*
X122632Y1644058D01*
X122532Y1642725D01*
X122132Y1641791D01*
X121632Y1640991D01*
X121032Y1640458D01*
X120232Y1640058D01*
X118232D01*
G01X135232Y1648058D02*
X137632D01*
G01X136432D02*
Y1640058D01*
G01X135232D02*
X137632D01*
G01X141832D02*
Y1648058D01*
X144432Y1641391D01*
X147032Y1648058D01*
Y1640058D01*
G01X150432D02*
Y1648058D01*
X152832D01*
X153632Y1647658D01*
X154232Y1646725D01*
X154432Y1645658D01*
X154232Y1644591D01*
X153732Y1643791D01*
X152832Y1643391D01*
X150432D01*
G01X162432Y1640058D02*
X158432D01*
Y1648058D01*
X162432D01*
G01X160832Y1644191D02*
X158432D01*
G01X166232Y1640058D02*
Y1648058D01*
X168232D01*
X169032Y1647658D01*
X169632Y1647125D01*
X170132Y1646325D01*
X170532Y1645391D01*
X170632Y1644058D01*
X170532Y1642725D01*
X170132Y1641791D01*
X169632Y1640991D01*
X169032Y1640458D01*
X168232Y1640058D01*
X166232D01*
G01X173932D02*
X176432Y1648058D01*
X178932Y1640058D01*
G01X178032Y1642858D02*
X174832D01*
G01X182132Y1640058D02*
Y1648058D01*
X186732Y1640058D01*
Y1648058D01*
G01X194632Y1647391D02*
X194032Y1647791D01*
X193332Y1648058D01*
X192532D01*
X191632Y1647658D01*
X190932Y1646991D01*
X190432Y1646191D01*
X190032Y1644858D01*
X189932Y1643658D01*
X190132Y1642458D01*
X190432Y1641658D01*
X191032Y1640858D01*
X191732Y1640325D01*
X192432Y1640058D01*
X193132D01*
X193832Y1640325D01*
X194432Y1640725D01*
X194932Y1641258D01*
G01X202432Y1640058D02*
X198432D01*
Y1648058D01*
X202432D01*
G01X200832Y1644191D02*
X198432D01*
G01X217232Y1644325D02*
X217632Y1644725D01*
X217932Y1645391D01*
X218132Y1646325D01*
X217932Y1647125D01*
X217532Y1647658D01*
X216832Y1648058D01*
X214132D01*
Y1640058D01*
X217432D01*
X218132Y1640591D01*
X218532Y1641391D01*
X218732Y1642325D01*
X218532Y1643258D01*
X217932Y1644058D01*
X217232Y1644325D01*
X214132D01*
G01X224432Y1640058D02*
X223632Y1640191D01*
X222932Y1640725D01*
X222332Y1641525D01*
X221932Y1642458D01*
X221732Y1643525D01*
Y1644591D01*
X221932Y1645658D01*
X222332Y1646591D01*
X222932Y1647391D01*
X223632Y1647925D01*
X224432Y1648058D01*
X225232Y1647925D01*
X225932Y1647391D01*
X226532Y1646591D01*
X226932Y1645658D01*
X227132Y1644591D01*
Y1643525D01*
X226932Y1642458D01*
X226532Y1641525D01*
X225932Y1640725D01*
X225232Y1640191D01*
X224432Y1640058D01*
G01X229932D02*
X232432Y1648058D01*
X234932Y1640058D01*
G01X234032Y1642858D02*
X230832D01*
G01X238432Y1640058D02*
Y1648058D01*
X240932D01*
X241732Y1647658D01*
X242232Y1647125D01*
X242432Y1646058D01*
X242232Y1644991D01*
X241632Y1644325D01*
X240932Y1643925D01*
X238432D01*
G01X240932D02*
X242432Y1640058D01*
G01X246232D02*
Y1648058D01*
X248232D01*
X249032Y1647658D01*
X249632Y1647125D01*
X250132Y1646325D01*
X250532Y1645391D01*
X250632Y1644058D01*
X250532Y1642725D01*
X250132Y1641791D01*
X249632Y1640991D01*
X249032Y1640458D01*
X248232Y1640058D01*
X246232D01*
G01X256432Y1639791D02*
X256232Y1639925D01*
Y1640191D01*
X256432Y1640325D01*
X256632Y1640191D01*
Y1639925D01*
X256432Y1639791D01*
G01X270332Y1641124D02*
X271132Y1640458D01*
X272032Y1640058D01*
X272832D01*
X273632Y1640458D01*
X274232Y1641124D01*
X274532Y1642058D01*
X274332Y1642991D01*
X273832Y1643791D01*
X272932Y1644325D01*
X271732Y1644591D01*
X271032Y1645125D01*
X270732Y1646058D01*
X270932Y1646991D01*
X271432Y1647658D01*
X272132Y1648058D01*
X272832D01*
X273532Y1647791D01*
X274132Y1647125D01*
G01X282432Y1640058D02*
X278432D01*
Y1648058D01*
X282432D01*
G01X280832Y1644191D02*
X278432D01*
G01X290432Y1640058D02*
X286432D01*
Y1648058D01*
X290432D01*
G01X288832Y1644191D02*
X286432D01*
G01X302432Y1648058D02*
Y1640058D01*
X306432D01*
G01X309932D02*
X312432Y1648058D01*
X314932Y1640058D01*
G01X314032Y1642858D02*
X310832D01*
G01X320432Y1640058D02*
Y1643658D01*
X318432Y1648058D01*
G01X322432D02*
X320432Y1643658D01*
G01X330432Y1640058D02*
X326432D01*
Y1648058D01*
X330432D01*
G01X328832Y1644191D02*
X326432D01*
G01X334432Y1640058D02*
Y1648058D01*
X336932D01*
X337732Y1647658D01*
X338232Y1647125D01*
X338432Y1646058D01*
X338232Y1644991D01*
X337632Y1644325D01*
X336932Y1643925D01*
X334432D01*
G01X336932D02*
X338432Y1640058D01*
G01X350332Y1641124D02*
X351132Y1640458D01*
X352032Y1640058D01*
X352832D01*
X353632Y1640458D01*
X354232Y1641124D01*
X354532Y1642058D01*
X354332Y1642991D01*
X353832Y1643791D01*
X352932Y1644325D01*
X351732Y1644591D01*
X351032Y1645125D01*
X350732Y1646058D01*
X350932Y1646991D01*
X351432Y1647658D01*
X352132Y1648058D01*
X352832D01*
X353532Y1647791D01*
X354132Y1647125D01*
G01X360432Y1648058D02*
Y1640058D01*
G01X358132Y1648058D02*
X362732D01*
G01X365932Y1640058D02*
X368432Y1648058D01*
X370932Y1640058D01*
G01X370032Y1642858D02*
X366832D01*
G01X378632Y1647391D02*
X378032Y1647791D01*
X377332Y1648058D01*
X376532D01*
X375632Y1647658D01*
X374932Y1646991D01*
X374432Y1646191D01*
X374032Y1644858D01*
X373932Y1643658D01*
X374132Y1642458D01*
X374432Y1641658D01*
X375032Y1640858D01*
X375732Y1640325D01*
X376432Y1640058D01*
X377132D01*
X377832Y1640325D01*
X378432Y1640725D01*
X378932Y1641258D01*
G01X382232Y1640058D02*
Y1648058D01*
G01X386032D02*
X382232Y1643124D01*
G01X386632Y1640058D02*
X383932Y1645391D01*
G01X390232Y1648058D02*
Y1642325D01*
X390632Y1641124D01*
X391432Y1640325D01*
X392432Y1640058D01*
X393432Y1640325D01*
X394232Y1641124D01*
X394632Y1642325D01*
Y1648058D01*
G01X398432Y1640058D02*
Y1648058D01*
X400832D01*
X401632Y1647658D01*
X402232Y1646725D01*
X402432Y1645658D01*
X402232Y1644591D01*
X401732Y1643791D01*
X400832Y1643391D01*
X398432D01*
G01X413932Y1640058D02*
X416432Y1648058D01*
X418932Y1640058D01*
G01X418032Y1642858D02*
X414832D01*
G01X422132Y1640058D02*
Y1648058D01*
X426732Y1640058D01*
Y1648058D01*
G01X430232Y1640058D02*
Y1648058D01*
X432232D01*
X433032Y1647658D01*
X433632Y1647125D01*
X434132Y1646325D01*
X434532Y1645391D01*
X434632Y1644058D01*
X434532Y1642725D01*
X434132Y1641791D01*
X433632Y1640991D01*
X433032Y1640458D01*
X432232Y1640058D01*
X430232D01*
G01X447232Y1648058D02*
X449632D01*
G01X448432D02*
Y1640058D01*
G01X447232D02*
X449632D01*
G01X453832D02*
Y1648058D01*
X456432Y1641391D01*
X459032Y1648058D01*
Y1640058D01*
G01X462432D02*
Y1648058D01*
X464832D01*
X465632Y1647658D01*
X466232Y1646725D01*
X466432Y1645658D01*
X466232Y1644591D01*
X465732Y1643791D01*
X464832Y1643391D01*
X462432D01*
G01X474432Y1640058D02*
X470432D01*
Y1648058D01*
X474432D01*
G01X472832Y1644191D02*
X470432D01*
G01X478232Y1640058D02*
Y1648058D01*
X480232D01*
X481032Y1647658D01*
X481632Y1647125D01*
X482132Y1646325D01*
X482532Y1645391D01*
X482632Y1644058D01*
X482532Y1642725D01*
X482132Y1641791D01*
X481632Y1640991D01*
X481032Y1640458D01*
X480232Y1640058D01*
X478232D01*
G01X485932D02*
X488432Y1648058D01*
X490932Y1640058D01*
G01X490032Y1642858D02*
X486832D01*
G01X494132Y1640058D02*
Y1648058D01*
X498732Y1640058D01*
Y1648058D01*
G01X506632Y1647391D02*
X506032Y1647791D01*
X505332Y1648058D01*
X504532D01*
X503632Y1647658D01*
X502932Y1646991D01*
X502432Y1646191D01*
X502032Y1644858D01*
X501932Y1643658D01*
X502132Y1642458D01*
X502432Y1641658D01*
X503032Y1640858D01*
X503732Y1640325D01*
X504432Y1640058D01*
X505132D01*
X505832Y1640325D01*
X506432Y1640725D01*
X506932Y1641258D01*
G01X514432Y1640058D02*
X510432D01*
Y1648058D01*
X514432D01*
G01X512832Y1644191D02*
X510432D01*
G01X37198Y-238524D02*
X37825Y-239049D01*
X38530Y-239364D01*
X39156D01*
X39783Y-239049D01*
X40253Y-238524D01*
X40488Y-237789D01*
X40331Y-237054D01*
X39940Y-236424D01*
X39235Y-236004D01*
X38295Y-235794D01*
X37746Y-235374D01*
X37511Y-234639D01*
X37668Y-233904D01*
X38060Y-233379D01*
X38608Y-233064D01*
X39156D01*
X39705Y-233274D01*
X40175Y-233799D01*
G01X43498Y-239364D02*
Y-233064D01*
G01X46788D02*
Y-239364D01*
G01Y-236214D02*
X43498D01*
G01X50503Y-233064D02*
X52383D01*
G01X51443D02*
Y-239364D01*
G01X50503D02*
X52383D01*
G01X59310D02*
X56176D01*
Y-233064D01*
X59310D01*
G01X58056Y-236109D02*
X56176D01*
G01X62241Y-239364D02*
Y-233064D01*
X65845Y-239364D01*
Y-233064D01*
G01X70186Y-240519D02*
X70500Y-239154D01*
G01X76643Y-233064D02*
Y-239364D01*
G01X74841Y-233064D02*
X78445D01*
G01X80985Y-239364D02*
X82943Y-233064D01*
X84901Y-239364D01*
G01X84196Y-237159D02*
X81690D01*
G01X88303Y-233064D02*
X90183D01*
G01X89243D02*
Y-239364D01*
G01X88303D02*
X90183D01*
G01X93193Y-233064D02*
X94290Y-239364D01*
X95543Y-233064D01*
X96796Y-239364D01*
X97893Y-233064D01*
G01X99885Y-239364D02*
X101843Y-233064D01*
X103801Y-239364D01*
G01X103096Y-237159D02*
X100590D01*
G01X106341Y-239364D02*
Y-233064D01*
X109945Y-239364D01*
Y-233064D01*
G01X119176Y-239364D02*
Y-233064D01*
X121135D01*
X121761Y-233379D01*
X122153Y-233799D01*
X122310Y-234639D01*
X122153Y-235479D01*
X121683Y-236004D01*
X121135Y-236319D01*
X119176D01*
G01X121135D02*
X122310Y-239364D01*
G01X127043Y-239574D02*
X126886Y-239469D01*
Y-239259D01*
X127043Y-239154D01*
X127200Y-239259D01*
Y-239469D01*
X127043Y-239574D01*
G01X133343Y-239364D02*
X132716Y-239259D01*
X132168Y-238839D01*
X131698Y-238209D01*
X131385Y-237474D01*
X131228Y-236634D01*
Y-235794D01*
X131385Y-234954D01*
X131698Y-234219D01*
X132168Y-233589D01*
X132716Y-233169D01*
X133343Y-233064D01*
X133970Y-233169D01*
X134518Y-233589D01*
X134988Y-234219D01*
X135301Y-234954D01*
X135458Y-235794D01*
Y-236634D01*
X135301Y-237474D01*
X134988Y-238209D01*
X134518Y-238839D01*
X133970Y-239259D01*
X133343Y-239364D01*
G01X139643Y-239574D02*
X139486Y-239469D01*
Y-239259D01*
X139643Y-239154D01*
X139800Y-239259D01*
Y-239469D01*
X139643Y-239574D01*
G01X147666Y-233589D02*
X147196Y-233274D01*
X146648Y-233064D01*
X146021D01*
X145316Y-233379D01*
X144768Y-233904D01*
X144376Y-234534D01*
X144063Y-235584D01*
X143985Y-236529D01*
X144141Y-237474D01*
X144376Y-238104D01*
X144846Y-238734D01*
X145395Y-239154D01*
X145943Y-239364D01*
X146491D01*
X147040Y-239154D01*
X147510Y-238839D01*
X147901Y-238419D01*
G01X152243Y-239574D02*
X152086Y-239469D01*
Y-239259D01*
X152243Y-239154D01*
X152400Y-239259D01*
Y-239469D01*
X152243Y-239574D01*
G01X37120Y-229364D02*
Y-223064D01*
G01X40096D02*
X37120Y-226949D01*
G01X40566Y-229364D02*
X38451Y-225164D01*
G01X43420Y-223064D02*
Y-227579D01*
X43733Y-228524D01*
X44360Y-229154D01*
X45143Y-229364D01*
X45926Y-229154D01*
X46553Y-228524D01*
X46866Y-227579D01*
Y-223064D01*
G01X53010Y-229364D02*
X49876D01*
Y-223064D01*
X53010D01*
G01X51756Y-226109D02*
X49876D01*
G01X56803Y-223064D02*
X58683D01*
G01X57743D02*
Y-229364D01*
G01X56803D02*
X58683D01*
G01X68698Y-228524D02*
X69325Y-229049D01*
X70030Y-229364D01*
X70656D01*
X71283Y-229049D01*
X71753Y-228524D01*
X71988Y-227789D01*
X71831Y-227054D01*
X71440Y-226424D01*
X70735Y-226004D01*
X69795Y-225794D01*
X69246Y-225374D01*
X69011Y-224639D01*
X69168Y-223904D01*
X69560Y-223379D01*
X70108Y-223064D01*
X70656D01*
X71205Y-223274D01*
X71675Y-223799D01*
G01X74998Y-229364D02*
Y-223064D01*
G01X78288D02*
Y-229364D01*
G01Y-226214D02*
X74998D01*
G01X80985Y-229364D02*
X82943Y-223064D01*
X84901Y-229364D01*
G01X84196Y-227159D02*
X81690D01*
G01X87441Y-229364D02*
Y-223064D01*
X91045Y-229364D01*
Y-223064D01*
G01X100198Y-229364D02*
Y-223064D01*
G01X103488D02*
Y-229364D01*
G01Y-226214D02*
X100198D01*
G01X106498Y-228524D02*
X107125Y-229049D01*
X107830Y-229364D01*
X108456D01*
X109083Y-229049D01*
X109553Y-228524D01*
X109788Y-227789D01*
X109631Y-227054D01*
X109240Y-226424D01*
X108535Y-226004D01*
X107595Y-225794D01*
X107046Y-225374D01*
X106811Y-224639D01*
X106968Y-223904D01*
X107360Y-223379D01*
X107908Y-223064D01*
X108456D01*
X109005Y-223274D01*
X109475Y-223799D01*
G01X113503Y-223064D02*
X115383D01*
G01X114443D02*
Y-229364D01*
G01X113503D02*
X115383D01*
G01X118785D02*
X120743Y-223064D01*
X122701Y-229364D01*
G01X121996Y-227159D02*
X119490D01*
G01X125241Y-229364D02*
Y-223064D01*
X128845Y-229364D01*
Y-223064D01*
G01X133813Y-226214D02*
X135380D01*
Y-228104D01*
X134910Y-228734D01*
X134361Y-229154D01*
X133578Y-229364D01*
X132795Y-229154D01*
X132246Y-228734D01*
X131776Y-228104D01*
X131463Y-227369D01*
X131306Y-226529D01*
Y-225794D01*
X131463Y-225164D01*
X131776Y-224429D01*
X132246Y-223799D01*
X132716Y-223379D01*
X133343Y-223064D01*
X133891D01*
X134518Y-223274D01*
X134988Y-223694D01*
G01X139486Y-230519D02*
X139800Y-229154D01*
G01X145943Y-223064D02*
Y-229364D01*
G01X144141Y-223064D02*
X147745D01*
G01X150285Y-229364D02*
X152243Y-223064D01*
X154201Y-229364D01*
G01X153496Y-227159D02*
X150990D01*
G01X158543Y-229364D02*
X157916Y-229259D01*
X157368Y-228839D01*
X156898Y-228209D01*
X156585Y-227474D01*
X156428Y-226634D01*
Y-225794D01*
X156585Y-224954D01*
X156898Y-224219D01*
X157368Y-223589D01*
X157916Y-223169D01*
X158543Y-223064D01*
X159170Y-223169D01*
X159718Y-223589D01*
X160188Y-224219D01*
X160501Y-224954D01*
X160658Y-225794D01*
Y-226634D01*
X160501Y-227474D01*
X160188Y-228209D01*
X159718Y-228839D01*
X159170Y-229259D01*
X158543Y-229364D01*
G01X171143D02*
Y-226529D01*
X169576Y-223064D01*
G01X172710D02*
X171143Y-226529D01*
G01X175720Y-223064D02*
Y-227579D01*
X176033Y-228524D01*
X176660Y-229154D01*
X177443Y-229364D01*
X178226Y-229154D01*
X178853Y-228524D01*
X179166Y-227579D01*
Y-223064D01*
G01X181785Y-229364D02*
X183743Y-223064D01*
X185701Y-229364D01*
G01X184996Y-227159D02*
X182490D01*
G01X188241Y-229364D02*
Y-223064D01*
X191845Y-229364D01*
Y-223064D01*
G01X37041Y-219364D02*
Y-213064D01*
X40645Y-219364D01*
Y-213064D01*
G01X45143Y-219364D02*
X44516Y-219259D01*
X43968Y-218839D01*
X43498Y-218209D01*
X43185Y-217474D01*
X43028Y-216634D01*
Y-215794D01*
X43185Y-214954D01*
X43498Y-214219D01*
X43968Y-213589D01*
X44516Y-213169D01*
X45143Y-213064D01*
X45770Y-213169D01*
X46318Y-213589D01*
X46788Y-214219D01*
X47101Y-214954D01*
X47258Y-215794D01*
Y-216634D01*
X47101Y-217474D01*
X46788Y-218209D01*
X46318Y-218839D01*
X45770Y-219259D01*
X45143Y-219364D01*
G01X51443Y-219574D02*
X51286Y-219469D01*
Y-219259D01*
X51443Y-219154D01*
X51600Y-219259D01*
Y-219469D01*
X51443Y-219574D01*
G01X57743Y-219364D02*
Y-213064D01*
X56803Y-214324D01*
G01Y-219364D02*
X58683D01*
G01X64043D02*
X64591Y-219259D01*
X65218Y-218944D01*
X65610Y-218419D01*
X65766Y-217684D01*
X65610Y-216949D01*
X65140Y-216319D01*
X64435Y-216004D01*
X63651D01*
X63181Y-215794D01*
X62790Y-215269D01*
X62633Y-214534D01*
X62868Y-213799D01*
X63416Y-213274D01*
X64043Y-213064D01*
X64670Y-213274D01*
X65218Y-213799D01*
X65453Y-214534D01*
X65296Y-215269D01*
X64905Y-215794D01*
X64435Y-216004D01*
X63651D01*
X62946Y-216319D01*
X62476Y-216949D01*
X62320Y-217684D01*
X62476Y-218419D01*
X62868Y-218944D01*
X63495Y-219259D01*
X64043Y-219364D01*
G01X70343D02*
X70891Y-219259D01*
X71518Y-218944D01*
X71910Y-218419D01*
X72066Y-217684D01*
X71910Y-216949D01*
X71440Y-216319D01*
X70735Y-216004D01*
X69951D01*
X69481Y-215794D01*
X69090Y-215269D01*
X68933Y-214534D01*
X69168Y-213799D01*
X69716Y-213274D01*
X70343Y-213064D01*
X70970Y-213274D01*
X71518Y-213799D01*
X71753Y-214534D01*
X71596Y-215269D01*
X71205Y-215794D01*
X70735Y-216004D01*
X69951D01*
X69246Y-216319D01*
X68776Y-216949D01*
X68620Y-217684D01*
X68776Y-218419D01*
X69168Y-218944D01*
X69795Y-219259D01*
X70343Y-219364D01*
G01X76486Y-220519D02*
X76800Y-219154D01*
G01X80593Y-213064D02*
X81690Y-219364D01*
X82943Y-213064D01*
X84196Y-219364D01*
X85293Y-213064D01*
G01X90810Y-219364D02*
X87676D01*
Y-213064D01*
X90810D01*
G01X89556Y-216109D02*
X87676D01*
G01X93741Y-219364D02*
Y-213064D01*
X97345Y-219364D01*
Y-213064D01*
G01X106498Y-219364D02*
Y-213064D01*
G01X109788D02*
Y-219364D01*
G01Y-216214D02*
X106498D01*
G01X112093Y-213064D02*
X113190Y-219364D01*
X114443Y-213064D01*
X115696Y-219364D01*
X116793Y-213064D01*
G01X118785Y-219364D02*
X120743Y-213064D01*
X122701Y-219364D01*
G01X121996Y-217159D02*
X119490D01*
G01X131855Y-214114D02*
X132325Y-213484D01*
X132873Y-213169D01*
X133500Y-213064D01*
X134283Y-213274D01*
X134831Y-213799D01*
X134988Y-214429D01*
X134910Y-215059D01*
X134596Y-215584D01*
X133030Y-216634D01*
X132325Y-217369D01*
X131855Y-218419D01*
X131698Y-219364D01*
X134988D01*
G01X137841D02*
Y-213064D01*
X141445Y-219364D01*
Y-213064D01*
G01X144220Y-219364D02*
Y-213064D01*
X145786D01*
X146413Y-213379D01*
X146883Y-213799D01*
X147275Y-214429D01*
X147588Y-215164D01*
X147666Y-216214D01*
X147588Y-217264D01*
X147275Y-217999D01*
X146883Y-218629D01*
X146413Y-219049D01*
X145786Y-219364D01*
X144220D01*
G01X156976D02*
Y-213064D01*
X158935D01*
X159561Y-213379D01*
X159953Y-213799D01*
X160110Y-214639D01*
X159953Y-215479D01*
X159483Y-216004D01*
X158935Y-216319D01*
X156976D01*
G01X158935D02*
X160110Y-219364D01*
G01X163120D02*
Y-213064D01*
X164686D01*
X165313Y-213379D01*
X165783Y-213799D01*
X166175Y-214429D01*
X166488Y-215164D01*
X166566Y-216214D01*
X166488Y-217264D01*
X166175Y-217999D01*
X165783Y-218629D01*
X165313Y-219049D01*
X164686Y-219364D01*
X163120D01*
G01X171143Y-219574D02*
X170986Y-219469D01*
Y-219259D01*
X171143Y-219154D01*
X171300Y-219259D01*
Y-219469D01*
X171143Y-219574D01*
G01X48032Y1509058D02*
X50032D01*
Y1506658D01*
X49432Y1505858D01*
X48732Y1505325D01*
X47732Y1505058D01*
X46732Y1505325D01*
X46032Y1505858D01*
X45432Y1506658D01*
X45032Y1507591D01*
X44832Y1508658D01*
Y1509591D01*
X45032Y1510391D01*
X45432Y1511325D01*
X46032Y1512125D01*
X46632Y1512658D01*
X47432Y1513058D01*
X48132D01*
X48932Y1512791D01*
X49532Y1512258D01*
G01X53432Y1505058D02*
Y1513058D01*
X55932D01*
X56732Y1512658D01*
X57232Y1512125D01*
X57432Y1511058D01*
X57232Y1509991D01*
X56632Y1509325D01*
X55932Y1508925D01*
X53432D01*
G01X55932D02*
X57432Y1505058D01*
G01X63432D02*
X62632Y1505191D01*
X61932Y1505725D01*
X61332Y1506525D01*
X60932Y1507458D01*
X60732Y1508525D01*
Y1509591D01*
X60932Y1510658D01*
X61332Y1511591D01*
X61932Y1512391D01*
X62632Y1512925D01*
X63432Y1513058D01*
X64232Y1512925D01*
X64932Y1512391D01*
X65532Y1511591D01*
X65932Y1510658D01*
X66132Y1509591D01*
Y1508525D01*
X65932Y1507458D01*
X65532Y1506525D01*
X64932Y1505725D01*
X64232Y1505191D01*
X63432Y1505058D01*
G01X69232Y1513058D02*
Y1507325D01*
X69632Y1506124D01*
X70432Y1505325D01*
X71432Y1505058D01*
X72432Y1505325D01*
X73232Y1506124D01*
X73632Y1507325D01*
Y1513058D01*
G01X77432Y1505058D02*
Y1513058D01*
X79832D01*
X80632Y1512658D01*
X81232Y1511725D01*
X81432Y1510658D01*
X81232Y1509591D01*
X80732Y1508791D01*
X79832Y1508391D01*
X77432D01*
G01X85332Y1506124D02*
X86132Y1505458D01*
X87032Y1505058D01*
X87832D01*
X88632Y1505458D01*
X89232Y1506124D01*
X89532Y1507058D01*
X89332Y1507991D01*
X88832Y1508791D01*
X87932Y1509325D01*
X86732Y1509591D01*
X86032Y1510125D01*
X85732Y1511058D01*
X85932Y1511991D01*
X86432Y1512658D01*
X87132Y1513058D01*
X87832D01*
X88532Y1512791D01*
X89132Y1512125D01*
G01X100932Y1505058D02*
X103432Y1513058D01*
X105932Y1505058D01*
G01X105032Y1507858D02*
X101832D01*
G01X116932Y1505058D02*
X119432Y1513058D01*
X121932Y1505058D01*
G01X121032Y1507858D02*
X117832D01*
G01X125132Y1505058D02*
Y1513058D01*
X129732Y1505058D01*
Y1513058D01*
G01X133232Y1505058D02*
Y1513058D01*
X135232D01*
X136032Y1512658D01*
X136632Y1512125D01*
X137132Y1511325D01*
X137532Y1510391D01*
X137632Y1509058D01*
X137532Y1507725D01*
X137132Y1506791D01*
X136632Y1505991D01*
X136032Y1505458D01*
X135232Y1505058D01*
X133232D01*
G01X152232Y1509325D02*
X152632Y1509725D01*
X152932Y1510391D01*
X153132Y1511325D01*
X152932Y1512125D01*
X152532Y1512658D01*
X151832Y1513058D01*
X149132D01*
Y1505058D01*
X152432D01*
X153132Y1505591D01*
X153532Y1506391D01*
X153732Y1507325D01*
X153532Y1508258D01*
X152932Y1509058D01*
X152232Y1509325D01*
X149132D01*
G01X159232Y1503591D02*
X159632Y1505325D01*
G01X167432Y1513058D02*
Y1505058D01*
G01X165132Y1513058D02*
X169732D01*
G01X173332Y1505058D02*
Y1513058D01*
G01X177532D02*
Y1505058D01*
G01Y1509058D02*
X173332D01*
G01X185432Y1505058D02*
X181432D01*
Y1513058D01*
X185432D01*
G01X183832Y1509191D02*
X181432D01*
G01X189132Y1505058D02*
Y1513058D01*
X193732Y1505058D01*
Y1513058D01*
G01X208032Y1509058D02*
X210032D01*
Y1506658D01*
X209432Y1505858D01*
X208732Y1505325D01*
X207732Y1505058D01*
X206732Y1505325D01*
X206032Y1505858D01*
X205432Y1506658D01*
X205032Y1507591D01*
X204832Y1508658D01*
Y1509591D01*
X205032Y1510391D01*
X205432Y1511325D01*
X206032Y1512125D01*
X206632Y1512658D01*
X207432Y1513058D01*
X208132D01*
X208932Y1512791D01*
X209532Y1512258D01*
G01X213432Y1505058D02*
Y1513058D01*
X215932D01*
X216732Y1512658D01*
X217232Y1512125D01*
X217432Y1511058D01*
X217232Y1509991D01*
X216632Y1509325D01*
X215932Y1508925D01*
X213432D01*
G01X215932D02*
X217432Y1505058D01*
G01X223432D02*
X222632Y1505191D01*
X221932Y1505725D01*
X221332Y1506525D01*
X220932Y1507458D01*
X220732Y1508525D01*
Y1509591D01*
X220932Y1510658D01*
X221332Y1511591D01*
X221932Y1512391D01*
X222632Y1512925D01*
X223432Y1513058D01*
X224232Y1512925D01*
X224932Y1512391D01*
X225532Y1511591D01*
X225932Y1510658D01*
X226132Y1509591D01*
Y1508525D01*
X225932Y1507458D01*
X225532Y1506525D01*
X224932Y1505725D01*
X224232Y1505191D01*
X223432Y1505058D01*
G01X229232Y1513058D02*
Y1507325D01*
X229632Y1506124D01*
X230432Y1505325D01*
X231432Y1505058D01*
X232432Y1505325D01*
X233232Y1506124D01*
X233632Y1507325D01*
Y1513058D01*
G01X237432Y1505058D02*
Y1513058D01*
X239832D01*
X240632Y1512658D01*
X241232Y1511725D01*
X241432Y1510658D01*
X241232Y1509591D01*
X240732Y1508791D01*
X239832Y1508391D01*
X237432D01*
G01X252932Y1505058D02*
X255432Y1513058D01*
X257932Y1505058D01*
G01X257032Y1507858D02*
X253832D01*
G01X273632Y1512391D02*
X273032Y1512791D01*
X272332Y1513058D01*
X271532D01*
X270632Y1512658D01*
X269932Y1511991D01*
X269432Y1511191D01*
X269032Y1509858D01*
X268932Y1508658D01*
X269132Y1507458D01*
X269432Y1506658D01*
X270032Y1505858D01*
X270732Y1505325D01*
X271432Y1505058D01*
X272132D01*
X272832Y1505325D01*
X273432Y1505725D01*
X273932Y1506258D01*
G01X276932Y1505058D02*
X279432Y1513058D01*
X281932Y1505058D01*
G01X281032Y1507858D02*
X277832D01*
G01X285132Y1505058D02*
Y1513058D01*
X289732Y1505058D01*
Y1513058D01*
G01X304232Y1509325D02*
X304632Y1509725D01*
X304932Y1510391D01*
X305132Y1511325D01*
X304932Y1512125D01*
X304532Y1512658D01*
X303832Y1513058D01*
X301132D01*
Y1505058D01*
X304432D01*
X305132Y1505591D01*
X305532Y1506391D01*
X305732Y1507325D01*
X305532Y1508258D01*
X304932Y1509058D01*
X304232Y1509325D01*
X301132D01*
G01X313432Y1505058D02*
X309432D01*
Y1513058D01*
X313432D01*
G01X311832Y1509191D02*
X309432D01*
G01X325432Y1505058D02*
Y1513058D01*
X327832D01*
X328632Y1512658D01*
X329232Y1511725D01*
X329432Y1510658D01*
X329232Y1509591D01*
X328732Y1508791D01*
X327832Y1508391D01*
X325432D01*
G01X333432Y1513058D02*
Y1505058D01*
X337432D01*
G01X340932D02*
X343432Y1513058D01*
X345932Y1505058D01*
G01X345032Y1507858D02*
X341832D01*
G01X353632Y1512391D02*
X353032Y1512791D01*
X352332Y1513058D01*
X351532D01*
X350632Y1512658D01*
X349932Y1511991D01*
X349432Y1511191D01*
X349032Y1509858D01*
X348932Y1508658D01*
X349132Y1507458D01*
X349432Y1506658D01*
X350032Y1505858D01*
X350732Y1505325D01*
X351432Y1505058D01*
X352132D01*
X352832Y1505325D01*
X353432Y1505725D01*
X353932Y1506258D01*
G01X361432Y1505058D02*
X357432D01*
Y1513058D01*
X361432D01*
G01X359832Y1509191D02*
X357432D01*
G01X365232Y1505058D02*
Y1513058D01*
X367232D01*
X368032Y1512658D01*
X368632Y1512125D01*
X369132Y1511325D01*
X369532Y1510391D01*
X369632Y1509058D01*
X369532Y1507725D01*
X369132Y1506791D01*
X368632Y1505991D01*
X368032Y1505458D01*
X367232Y1505058D01*
X365232D01*
G01X381332Y1506124D02*
X382132Y1505458D01*
X383032Y1505058D01*
X383832D01*
X384632Y1505458D01*
X385232Y1506124D01*
X385532Y1507058D01*
X385332Y1507991D01*
X384832Y1508791D01*
X383932Y1509325D01*
X382732Y1509591D01*
X382032Y1510125D01*
X381732Y1511058D01*
X381932Y1511991D01*
X382432Y1512658D01*
X383132Y1513058D01*
X383832D01*
X384532Y1512791D01*
X385132Y1512125D01*
G01X393432Y1505058D02*
X389432D01*
Y1513058D01*
X393432D01*
G01X391832Y1509191D02*
X389432D01*
G01X397432Y1505058D02*
Y1513058D01*
X399832D01*
X400632Y1512658D01*
X401232Y1511725D01*
X401432Y1510658D01*
X401232Y1509591D01*
X400732Y1508791D01*
X399832Y1508391D01*
X397432D01*
G01X404932Y1505058D02*
X407432Y1513058D01*
X409932Y1505058D01*
G01X409032Y1507858D02*
X405832D01*
G01X413432Y1505058D02*
Y1513058D01*
X415932D01*
X416732Y1512658D01*
X417232Y1512125D01*
X417432Y1511058D01*
X417232Y1509991D01*
X416632Y1509325D01*
X415932Y1508925D01*
X413432D01*
G01X415932D02*
X417432Y1505058D01*
G01X420932D02*
X423432Y1513058D01*
X425932Y1505058D01*
G01X425032Y1507858D02*
X421832D01*
G01X431432Y1513058D02*
Y1505058D01*
G01X429132Y1513058D02*
X433732D01*
G01X441432Y1505058D02*
X437432D01*
Y1513058D01*
X441432D01*
G01X439832Y1509191D02*
X437432D01*
G01X445432Y1513058D02*
Y1505058D01*
X449432D01*
G01X455432D02*
Y1508658D01*
X453432Y1513058D01*
G01X457432D02*
X455432Y1508658D01*
G01X469532Y1505058D02*
Y1513058D01*
X473332D01*
G01X471932Y1509191D02*
X469532D01*
G01X477432Y1505058D02*
Y1513058D01*
X479932D01*
X480732Y1512658D01*
X481232Y1512125D01*
X481432Y1511058D01*
X481232Y1509991D01*
X480632Y1509325D01*
X479932Y1508925D01*
X477432D01*
G01X479932D02*
X481432Y1505058D01*
G01X487432D02*
X486632Y1505191D01*
X485932Y1505725D01*
X485332Y1506525D01*
X484932Y1507458D01*
X484732Y1508525D01*
Y1509591D01*
X484932Y1510658D01*
X485332Y1511591D01*
X485932Y1512391D01*
X486632Y1512925D01*
X487432Y1513058D01*
X488232Y1512925D01*
X488932Y1512391D01*
X489532Y1511591D01*
X489932Y1510658D01*
X490132Y1509591D01*
Y1508525D01*
X489932Y1507458D01*
X489532Y1506525D01*
X488932Y1505725D01*
X488232Y1505191D01*
X487432Y1505058D01*
G01X492832D02*
Y1513058D01*
X495432Y1506391D01*
X498032Y1513058D01*
Y1505058D01*
G01X512032Y1509058D02*
X514032D01*
Y1506658D01*
X513432Y1505858D01*
X512732Y1505325D01*
X511732Y1505058D01*
X510732Y1505325D01*
X510032Y1505858D01*
X509432Y1506658D01*
X509032Y1507591D01*
X508832Y1508658D01*
Y1509591D01*
X509032Y1510391D01*
X509432Y1511325D01*
X510032Y1512125D01*
X510632Y1512658D01*
X511432Y1513058D01*
X512132D01*
X512932Y1512791D01*
X513532Y1512258D01*
G01X517432Y1505058D02*
Y1513058D01*
X519932D01*
X520732Y1512658D01*
X521232Y1512125D01*
X521432Y1511058D01*
X521232Y1509991D01*
X520632Y1509325D01*
X519932Y1508925D01*
X517432D01*
G01X519932D02*
X521432Y1505058D01*
G01X527432D02*
X526632Y1505191D01*
X525932Y1505725D01*
X525332Y1506525D01*
X524932Y1507458D01*
X524732Y1508525D01*
Y1509591D01*
X524932Y1510658D01*
X525332Y1511591D01*
X525932Y1512391D01*
X526632Y1512925D01*
X527432Y1513058D01*
X528232Y1512925D01*
X528932Y1512391D01*
X529532Y1511591D01*
X529932Y1510658D01*
X530132Y1509591D01*
Y1508525D01*
X529932Y1507458D01*
X529532Y1506525D01*
X528932Y1505725D01*
X528232Y1505191D01*
X527432Y1505058D01*
G01X533232Y1513058D02*
Y1507325D01*
X533632Y1506124D01*
X534432Y1505325D01*
X535432Y1505058D01*
X536432Y1505325D01*
X537232Y1506124D01*
X537632Y1507325D01*
Y1513058D01*
G01X541432Y1505058D02*
Y1513058D01*
X543832D01*
X544632Y1512658D01*
X545232Y1511725D01*
X545432Y1510658D01*
X545232Y1509591D01*
X544732Y1508791D01*
X543832Y1508391D01*
X541432D01*
G01X560232Y1509325D02*
X560632Y1509725D01*
X560932Y1510391D01*
X561132Y1511325D01*
X560932Y1512125D01*
X560532Y1512658D01*
X559832Y1513058D01*
X557132D01*
Y1505058D01*
X560432D01*
X561132Y1505591D01*
X561532Y1506391D01*
X561732Y1507325D01*
X561532Y1508258D01*
X560932Y1509058D01*
X560232Y1509325D01*
X557132D01*
G01X567432Y1504791D02*
X567232Y1504925D01*
Y1505191D01*
X567432Y1505325D01*
X567632Y1505191D01*
Y1504925D01*
X567432Y1504791D01*
G01X47432Y1528058D02*
Y1520058D01*
G01X45132Y1528058D02*
X49732D01*
G01X55432Y1520058D02*
X54632Y1520191D01*
X53932Y1520725D01*
X53332Y1521525D01*
X52932Y1522458D01*
X52732Y1523525D01*
Y1524591D01*
X52932Y1525658D01*
X53332Y1526591D01*
X53932Y1527391D01*
X54632Y1527925D01*
X55432Y1528058D01*
X56232Y1527925D01*
X56932Y1527391D01*
X57532Y1526591D01*
X57932Y1525658D01*
X58132Y1524591D01*
Y1523525D01*
X57932Y1522458D01*
X57532Y1521525D01*
X56932Y1520725D01*
X56232Y1520191D01*
X55432Y1520058D01*
G01X71432Y1528058D02*
Y1520058D01*
G01X69132Y1528058D02*
X73732D01*
G01X77332Y1520058D02*
Y1528058D01*
G01X81532D02*
Y1520058D01*
G01Y1524058D02*
X77332D01*
G01X89432Y1520058D02*
X85432D01*
Y1528058D01*
X89432D01*
G01X87832Y1524191D02*
X85432D01*
G01X104232Y1524325D02*
X104632Y1524725D01*
X104932Y1525391D01*
X105132Y1526325D01*
X104932Y1527125D01*
X104532Y1527658D01*
X103832Y1528058D01*
X101132D01*
Y1520058D01*
X104432D01*
X105132Y1520591D01*
X105532Y1521391D01*
X105732Y1522325D01*
X105532Y1523258D01*
X104932Y1524058D01*
X104232Y1524325D01*
X101132D01*
G01X111432Y1520058D02*
X110632Y1520191D01*
X109932Y1520725D01*
X109332Y1521525D01*
X108932Y1522458D01*
X108732Y1523525D01*
Y1524591D01*
X108932Y1525658D01*
X109332Y1526591D01*
X109932Y1527391D01*
X110632Y1527925D01*
X111432Y1528058D01*
X112232Y1527925D01*
X112932Y1527391D01*
X113532Y1526591D01*
X113932Y1525658D01*
X114132Y1524591D01*
Y1523525D01*
X113932Y1522458D01*
X113532Y1521525D01*
X112932Y1520725D01*
X112232Y1520191D01*
X111432Y1520058D01*
G01X116932D02*
X119432Y1528058D01*
X121932Y1520058D01*
G01X121032Y1522858D02*
X117832D01*
G01X125432Y1520058D02*
Y1528058D01*
X127932D01*
X128732Y1527658D01*
X129232Y1527125D01*
X129432Y1526058D01*
X129232Y1524991D01*
X128632Y1524325D01*
X127932Y1523925D01*
X125432D01*
G01X127932D02*
X129432Y1520058D01*
G01X133232D02*
Y1528058D01*
X135232D01*
X136032Y1527658D01*
X136632Y1527125D01*
X137132Y1526325D01*
X137532Y1525391D01*
X137632Y1524058D01*
X137532Y1522725D01*
X137132Y1521791D01*
X136632Y1520991D01*
X136032Y1520458D01*
X135232Y1520058D01*
X133232D01*
G01X153632Y1527391D02*
X153032Y1527791D01*
X152332Y1528058D01*
X151532D01*
X150632Y1527658D01*
X149932Y1526991D01*
X149432Y1526191D01*
X149032Y1524858D01*
X148932Y1523658D01*
X149132Y1522458D01*
X149432Y1521658D01*
X150032Y1520858D01*
X150732Y1520325D01*
X151432Y1520058D01*
X152132D01*
X152832Y1520325D01*
X153432Y1520725D01*
X153932Y1521258D01*
G01X159432Y1520058D02*
X158632Y1520191D01*
X157932Y1520725D01*
X157332Y1521525D01*
X156932Y1522458D01*
X156732Y1523525D01*
Y1524591D01*
X156932Y1525658D01*
X157332Y1526591D01*
X157932Y1527391D01*
X158632Y1527925D01*
X159432Y1528058D01*
X160232Y1527925D01*
X160932Y1527391D01*
X161532Y1526591D01*
X161932Y1525658D01*
X162132Y1524591D01*
Y1523525D01*
X161932Y1522458D01*
X161532Y1521525D01*
X160932Y1520725D01*
X160232Y1520191D01*
X159432Y1520058D01*
G01X165232Y1528058D02*
Y1522325D01*
X165632Y1521124D01*
X166432Y1520325D01*
X167432Y1520058D01*
X168432Y1520325D01*
X169232Y1521124D01*
X169632Y1522325D01*
Y1528058D01*
G01X173432Y1520058D02*
Y1528058D01*
X175832D01*
X176632Y1527658D01*
X177232Y1526725D01*
X177432Y1525658D01*
X177232Y1524591D01*
X176732Y1523791D01*
X175832Y1523391D01*
X173432D01*
G01X183432Y1520058D02*
X182632Y1520191D01*
X181932Y1520725D01*
X181332Y1521525D01*
X180932Y1522458D01*
X180732Y1523525D01*
Y1524591D01*
X180932Y1525658D01*
X181332Y1526591D01*
X181932Y1527391D01*
X182632Y1527925D01*
X183432Y1528058D01*
X184232Y1527925D01*
X184932Y1527391D01*
X185532Y1526591D01*
X185932Y1525658D01*
X186132Y1524591D01*
Y1523525D01*
X185932Y1522458D01*
X185532Y1521525D01*
X184932Y1520725D01*
X184232Y1520191D01*
X183432Y1520058D01*
G01X189132D02*
Y1528058D01*
X193732Y1520058D01*
Y1528058D01*
G01X197332Y1521124D02*
X198132Y1520458D01*
X199032Y1520058D01*
X199832D01*
X200632Y1520458D01*
X201232Y1521124D01*
X201532Y1522058D01*
X201332Y1522991D01*
X200832Y1523791D01*
X199932Y1524325D01*
X198732Y1524591D01*
X198032Y1525125D01*
X197732Y1526058D01*
X197932Y1526991D01*
X198432Y1527658D01*
X199132Y1528058D01*
X199832D01*
X200532Y1527791D01*
X201132Y1527125D01*
G01X207432Y1519791D02*
X207232Y1519925D01*
Y1520191D01*
X207432Y1520325D01*
X207632Y1520191D01*
Y1519925D01*
X207432Y1519791D01*
G01X214232Y1528058D02*
X216632D01*
G01X215432D02*
Y1520058D01*
G01X214232D02*
X216632D01*
G01X221532D02*
Y1528058D01*
X225332D01*
G01X223932Y1524191D02*
X221532D01*
G01X238232Y1528058D02*
X240632D01*
G01X239432D02*
Y1520058D01*
G01X238232D02*
X240632D01*
G01X247432Y1528058D02*
Y1520058D01*
G01X245132Y1528058D02*
X249732D01*
G01X262232D02*
X264632D01*
G01X263432D02*
Y1520058D01*
G01X262232D02*
X264632D01*
G01X269332Y1521124D02*
X270132Y1520458D01*
X271032Y1520058D01*
X271832D01*
X272632Y1520458D01*
X273232Y1521124D01*
X273532Y1522058D01*
X273332Y1522991D01*
X272832Y1523791D01*
X271932Y1524325D01*
X270732Y1524591D01*
X270032Y1525125D01*
X269732Y1526058D01*
X269932Y1526991D01*
X270432Y1527658D01*
X271132Y1528058D01*
X271832D01*
X272532Y1527791D01*
X273132Y1527125D01*
G01X285132Y1520058D02*
Y1528058D01*
X289732Y1520058D01*
Y1528058D01*
G01X295432Y1520058D02*
X294632Y1520191D01*
X293932Y1520725D01*
X293332Y1521525D01*
X292932Y1522458D01*
X292732Y1523525D01*
Y1524591D01*
X292932Y1525658D01*
X293332Y1526591D01*
X293932Y1527391D01*
X294632Y1527925D01*
X295432Y1528058D01*
X296232Y1527925D01*
X296932Y1527391D01*
X297532Y1526591D01*
X297932Y1525658D01*
X298132Y1524591D01*
Y1523525D01*
X297932Y1522458D01*
X297532Y1521525D01*
X296932Y1520725D01*
X296232Y1520191D01*
X295432Y1520058D01*
G01X303432Y1528058D02*
Y1520058D01*
G01X301132Y1528058D02*
X305732D01*
G01X317432Y1520058D02*
Y1528058D01*
X319832D01*
X320632Y1527658D01*
X321232Y1526725D01*
X321432Y1525658D01*
X321232Y1524591D01*
X320732Y1523791D01*
X319832Y1523391D01*
X317432D01*
G01X327432Y1520058D02*
X326632Y1520191D01*
X325932Y1520725D01*
X325332Y1521525D01*
X324932Y1522458D01*
X324732Y1523525D01*
Y1524591D01*
X324932Y1525658D01*
X325332Y1526591D01*
X325932Y1527391D01*
X326632Y1527925D01*
X327432Y1528058D01*
X328232Y1527925D01*
X328932Y1527391D01*
X329532Y1526591D01*
X329932Y1525658D01*
X330132Y1524591D01*
Y1523525D01*
X329932Y1522458D01*
X329532Y1521525D01*
X328932Y1520725D01*
X328232Y1520191D01*
X327432Y1520058D01*
G01X333332Y1521124D02*
X334132Y1520458D01*
X335032Y1520058D01*
X335832D01*
X336632Y1520458D01*
X337232Y1521124D01*
X337532Y1522058D01*
X337332Y1522991D01*
X336832Y1523791D01*
X335932Y1524325D01*
X334732Y1524591D01*
X334032Y1525125D01*
X333732Y1526058D01*
X333932Y1526991D01*
X334432Y1527658D01*
X335132Y1528058D01*
X335832D01*
X336532Y1527791D01*
X337132Y1527125D01*
G01X341332Y1521124D02*
X342132Y1520458D01*
X343032Y1520058D01*
X343832D01*
X344632Y1520458D01*
X345232Y1521124D01*
X345532Y1522058D01*
X345332Y1522991D01*
X344832Y1523791D01*
X343932Y1524325D01*
X342732Y1524591D01*
X342032Y1525125D01*
X341732Y1526058D01*
X341932Y1526991D01*
X342432Y1527658D01*
X343132Y1528058D01*
X343832D01*
X344532Y1527791D01*
X345132Y1527125D01*
G01X350232Y1528058D02*
X352632D01*
G01X351432D02*
Y1520058D01*
G01X350232D02*
X352632D01*
G01X360232Y1524325D02*
X360632Y1524725D01*
X360932Y1525391D01*
X361132Y1526325D01*
X360932Y1527125D01*
X360532Y1527658D01*
X359832Y1528058D01*
X357132D01*
Y1520058D01*
X360432D01*
X361132Y1520591D01*
X361532Y1521391D01*
X361732Y1522325D01*
X361532Y1523258D01*
X360932Y1524058D01*
X360232Y1524325D01*
X357132D01*
G01X365432Y1528058D02*
Y1520058D01*
X369432D01*
G01X377432D02*
X373432D01*
Y1528058D01*
X377432D01*
G01X375832Y1524191D02*
X373432D01*
G01X391432Y1528058D02*
Y1520058D01*
G01X389132Y1528058D02*
X393732D01*
G01X399432Y1520058D02*
X398632Y1520191D01*
X397932Y1520725D01*
X397332Y1521525D01*
X396932Y1522458D01*
X396732Y1523525D01*
Y1524591D01*
X396932Y1525658D01*
X397332Y1526591D01*
X397932Y1527391D01*
X398632Y1527925D01*
X399432Y1528058D01*
X400232Y1527925D01*
X400932Y1527391D01*
X401532Y1526591D01*
X401932Y1525658D01*
X402132Y1524591D01*
Y1523525D01*
X401932Y1522458D01*
X401532Y1521525D01*
X400932Y1520725D01*
X400232Y1520191D01*
X399432Y1520058D01*
G01X413532D02*
Y1528058D01*
X417332D01*
G01X415932Y1524191D02*
X413532D01*
G01X421432Y1528058D02*
Y1520058D01*
X425432D01*
G01X429432Y1528058D02*
Y1520058D01*
X433432D01*
G01X439432D02*
X438632Y1520191D01*
X437932Y1520725D01*
X437332Y1521525D01*
X436932Y1522458D01*
X436732Y1523525D01*
Y1524591D01*
X436932Y1525658D01*
X437332Y1526591D01*
X437932Y1527391D01*
X438632Y1527925D01*
X439432Y1528058D01*
X440232Y1527925D01*
X440932Y1527391D01*
X441532Y1526591D01*
X441932Y1525658D01*
X442132Y1524591D01*
Y1523525D01*
X441932Y1522458D01*
X441532Y1521525D01*
X440932Y1520725D01*
X440232Y1520191D01*
X439432Y1520058D01*
G01X444432Y1528058D02*
X445832Y1520058D01*
X447432Y1528058D01*
X449032Y1520058D01*
X450432Y1528058D01*
G01X457432Y1520058D02*
X453432D01*
Y1528058D01*
X457432D01*
G01X455832Y1524191D02*
X453432D01*
G01X461432Y1520058D02*
Y1528058D01*
X463932D01*
X464732Y1527658D01*
X465232Y1527125D01*
X465432Y1526058D01*
X465232Y1524991D01*
X464632Y1524325D01*
X463932Y1523925D01*
X461432D01*
G01X463932D02*
X465432Y1520058D01*
G01X479432Y1528058D02*
Y1520058D01*
G01X477132Y1528058D02*
X481732D01*
G01X485332Y1520058D02*
Y1528058D01*
G01X489532D02*
Y1520058D01*
G01Y1524058D02*
X485332D01*
G01X497432Y1520058D02*
X493432D01*
Y1528058D01*
X497432D01*
G01X495832Y1524191D02*
X493432D01*
G01X509432Y1528058D02*
Y1520058D01*
X513432D01*
G01X519432D02*
X518632Y1520191D01*
X517932Y1520725D01*
X517332Y1521525D01*
X516932Y1522458D01*
X516732Y1523525D01*
Y1524591D01*
X516932Y1525658D01*
X517332Y1526591D01*
X517932Y1527391D01*
X518632Y1527925D01*
X519432Y1528058D01*
X520232Y1527925D01*
X520932Y1527391D01*
X521532Y1526591D01*
X521932Y1525658D01*
X522132Y1524591D01*
Y1523525D01*
X521932Y1522458D01*
X521532Y1521525D01*
X520932Y1520725D01*
X520232Y1520191D01*
X519432Y1520058D01*
G01X529632Y1527391D02*
X529032Y1527791D01*
X528332Y1528058D01*
X527532D01*
X526632Y1527658D01*
X525932Y1526991D01*
X525432Y1526191D01*
X525032Y1524858D01*
X524932Y1523658D01*
X525132Y1522458D01*
X525432Y1521658D01*
X526032Y1520858D01*
X526732Y1520325D01*
X527432Y1520058D01*
X528132D01*
X528832Y1520325D01*
X529432Y1520725D01*
X529932Y1521258D01*
G01X532932Y1520058D02*
X535432Y1528058D01*
X537932Y1520058D01*
G01X537032Y1522858D02*
X533832D01*
G01X543432Y1528058D02*
Y1520058D01*
G01X541132Y1528058D02*
X545732D01*
G01X550232D02*
X552632D01*
G01X551432D02*
Y1520058D01*
G01X550232D02*
X552632D01*
G01X559432D02*
X558632Y1520191D01*
X557932Y1520725D01*
X557332Y1521525D01*
X556932Y1522458D01*
X556732Y1523525D01*
Y1524591D01*
X556932Y1525658D01*
X557332Y1526591D01*
X557932Y1527391D01*
X558632Y1527925D01*
X559432Y1528058D01*
X560232Y1527925D01*
X560932Y1527391D01*
X561532Y1526591D01*
X561932Y1525658D01*
X562132Y1524591D01*
Y1523525D01*
X561932Y1522458D01*
X561532Y1521525D01*
X560932Y1520725D01*
X560232Y1520191D01*
X559432Y1520058D01*
G01X565132D02*
Y1528058D01*
X569732Y1520058D01*
Y1528058D01*
G01X573332Y1521124D02*
X574132Y1520458D01*
X575032Y1520058D01*
X575832D01*
X576632Y1520458D01*
X577232Y1521124D01*
X577532Y1522058D01*
X577332Y1522991D01*
X576832Y1523791D01*
X575932Y1524325D01*
X574732Y1524591D01*
X574032Y1525125D01*
X573732Y1526058D01*
X573932Y1526991D01*
X574432Y1527658D01*
X575132Y1528058D01*
X575832D01*
X576532Y1527791D01*
X577132Y1527125D01*
G01X589532Y1520058D02*
Y1528058D01*
X593332D01*
G01X591932Y1524191D02*
X589532D01*
G01X599432Y1520058D02*
X598632Y1520191D01*
X597932Y1520725D01*
X597332Y1521525D01*
X596932Y1522458D01*
X596732Y1523525D01*
Y1524591D01*
X596932Y1525658D01*
X597332Y1526591D01*
X597932Y1527391D01*
X598632Y1527925D01*
X599432Y1528058D01*
X600232Y1527925D01*
X600932Y1527391D01*
X601532Y1526591D01*
X601932Y1525658D01*
X602132Y1524591D01*
Y1523525D01*
X601932Y1522458D01*
X601532Y1521525D01*
X600932Y1520725D01*
X600232Y1520191D01*
X599432Y1520058D01*
G01X605432D02*
Y1528058D01*
X607932D01*
X608732Y1527658D01*
X609232Y1527125D01*
X609432Y1526058D01*
X609232Y1524991D01*
X608632Y1524325D01*
X607932Y1523925D01*
X605432D01*
G01X607932D02*
X609432Y1520058D01*
G01X624232Y1524325D02*
X624632Y1524725D01*
X624932Y1525391D01*
X625132Y1526325D01*
X624932Y1527125D01*
X624532Y1527658D01*
X623832Y1528058D01*
X621132D01*
Y1520058D01*
X624432D01*
X625132Y1520591D01*
X625532Y1521391D01*
X625732Y1522325D01*
X625532Y1523258D01*
X624932Y1524058D01*
X624232Y1524325D01*
X621132D01*
G01X631432Y1520058D02*
X630632Y1520191D01*
X629932Y1520725D01*
X629332Y1521525D01*
X628932Y1522458D01*
X628732Y1523525D01*
Y1524591D01*
X628932Y1525658D01*
X629332Y1526591D01*
X629932Y1527391D01*
X630632Y1527925D01*
X631432Y1528058D01*
X632232Y1527925D01*
X632932Y1527391D01*
X633532Y1526591D01*
X633932Y1525658D01*
X634132Y1524591D01*
Y1523525D01*
X633932Y1522458D01*
X633532Y1521525D01*
X632932Y1520725D01*
X632232Y1520191D01*
X631432Y1520058D01*
G01X639432Y1528058D02*
Y1520058D01*
G01X637132Y1528058D02*
X641732D01*
G01X645332Y1520058D02*
Y1528058D01*
G01X649532D02*
Y1520058D01*
G01Y1524058D02*
X645332D01*
G01X45432Y1535058D02*
Y1543058D01*
X47832D01*
X48632Y1542658D01*
X49232Y1541725D01*
X49432Y1540658D01*
X49232Y1539591D01*
X48732Y1538791D01*
X47832Y1538391D01*
X45432D01*
G01X53432Y1543058D02*
Y1535058D01*
X57432D01*
G01X65432D02*
X61432D01*
Y1543058D01*
X65432D01*
G01X63832Y1539191D02*
X61432D01*
G01X68932Y1535058D02*
X71432Y1543058D01*
X73932Y1535058D01*
G01X73032Y1537858D02*
X69832D01*
G01X77332Y1536124D02*
X78132Y1535458D01*
X79032Y1535058D01*
X79832D01*
X80632Y1535458D01*
X81232Y1536124D01*
X81532Y1537058D01*
X81332Y1537991D01*
X80832Y1538791D01*
X79932Y1539325D01*
X78732Y1539591D01*
X78032Y1540125D01*
X77732Y1541058D01*
X77932Y1541991D01*
X78432Y1542658D01*
X79132Y1543058D01*
X79832D01*
X80532Y1542791D01*
X81132Y1542125D01*
G01X89432Y1535058D02*
X85432D01*
Y1543058D01*
X89432D01*
G01X87832Y1539191D02*
X85432D01*
G01X101532Y1535058D02*
Y1543058D01*
X105332D01*
G01X103932Y1539191D02*
X101532D01*
G01X111432Y1535058D02*
X110632Y1535191D01*
X109932Y1535725D01*
X109332Y1536525D01*
X108932Y1537458D01*
X108732Y1538525D01*
Y1539591D01*
X108932Y1540658D01*
X109332Y1541591D01*
X109932Y1542391D01*
X110632Y1542925D01*
X111432Y1543058D01*
X112232Y1542925D01*
X112932Y1542391D01*
X113532Y1541591D01*
X113932Y1540658D01*
X114132Y1539591D01*
Y1538525D01*
X113932Y1537458D01*
X113532Y1536525D01*
X112932Y1535725D01*
X112232Y1535191D01*
X111432Y1535058D01*
G01X117432Y1543058D02*
Y1535058D01*
X121432D01*
G01X125432Y1543058D02*
Y1535058D01*
X129432D01*
G01X135432D02*
X134632Y1535191D01*
X133932Y1535725D01*
X133332Y1536525D01*
X132932Y1537458D01*
X132732Y1538525D01*
Y1539591D01*
X132932Y1540658D01*
X133332Y1541591D01*
X133932Y1542391D01*
X134632Y1542925D01*
X135432Y1543058D01*
X136232Y1542925D01*
X136932Y1542391D01*
X137532Y1541591D01*
X137932Y1540658D01*
X138132Y1539591D01*
Y1538525D01*
X137932Y1537458D01*
X137532Y1536525D01*
X136932Y1535725D01*
X136232Y1535191D01*
X135432Y1535058D01*
G01X140432Y1543058D02*
X141832Y1535058D01*
X143432Y1543058D01*
X145032Y1535058D01*
X146432Y1543058D01*
G01X159432D02*
Y1535058D01*
G01X157132Y1543058D02*
X161732D01*
G01X165332Y1535058D02*
Y1543058D01*
G01X169532D02*
Y1535058D01*
G01Y1539058D02*
X165332D01*
G01X177432Y1535058D02*
X173432D01*
Y1543058D01*
X177432D01*
G01X175832Y1539191D02*
X173432D01*
G01X189332Y1536124D02*
X190132Y1535458D01*
X191032Y1535058D01*
X191832D01*
X192632Y1535458D01*
X193232Y1536124D01*
X193532Y1537058D01*
X193332Y1537991D01*
X192832Y1538791D01*
X191932Y1539325D01*
X190732Y1539591D01*
X190032Y1540125D01*
X189732Y1541058D01*
X189932Y1541991D01*
X190432Y1542658D01*
X191132Y1543058D01*
X191832D01*
X192532Y1542791D01*
X193132Y1542125D01*
G01X197432Y1543058D02*
Y1535058D01*
X201432D01*
G01X206232Y1543058D02*
X208632D01*
G01X207432D02*
Y1535058D01*
G01X206232D02*
X208632D01*
G01X213232D02*
Y1543058D01*
X215232D01*
X216032Y1542658D01*
X216632Y1542125D01*
X217132Y1541325D01*
X217532Y1540391D01*
X217632Y1539058D01*
X217532Y1537725D01*
X217132Y1536791D01*
X216632Y1535991D01*
X216032Y1535458D01*
X215232Y1535058D01*
X213232D01*
G01X225432D02*
X221432D01*
Y1543058D01*
X225432D01*
G01X223832Y1539191D02*
X221432D01*
G01X229332Y1536124D02*
X230132Y1535458D01*
X231032Y1535058D01*
X231832D01*
X232632Y1535458D01*
X233232Y1536124D01*
X233532Y1537058D01*
X233332Y1537991D01*
X232832Y1538791D01*
X231932Y1539325D01*
X230732Y1539591D01*
X230032Y1540125D01*
X229732Y1541058D01*
X229932Y1541991D01*
X230432Y1542658D01*
X231132Y1543058D01*
X231832D01*
X232532Y1542791D01*
X233132Y1542125D01*
G01X247432Y1543058D02*
Y1535058D01*
G01X245132Y1543058D02*
X249732D01*
G01X255432Y1535058D02*
X254632Y1535191D01*
X253932Y1535725D01*
X253332Y1536525D01*
X252932Y1537458D01*
X252732Y1538525D01*
Y1539591D01*
X252932Y1540658D01*
X253332Y1541591D01*
X253932Y1542391D01*
X254632Y1542925D01*
X255432Y1543058D01*
X256232Y1542925D01*
X256932Y1542391D01*
X257532Y1541591D01*
X257932Y1540658D01*
X258132Y1539591D01*
Y1538525D01*
X257932Y1537458D01*
X257532Y1536525D01*
X256932Y1535725D01*
X256232Y1535191D01*
X255432Y1535058D01*
G01X272032Y1539058D02*
X274032D01*
Y1536658D01*
X273432Y1535858D01*
X272732Y1535325D01*
X271732Y1535058D01*
X270732Y1535325D01*
X270032Y1535858D01*
X269432Y1536658D01*
X269032Y1537591D01*
X268832Y1538658D01*
Y1539591D01*
X269032Y1540391D01*
X269432Y1541325D01*
X270032Y1542125D01*
X270632Y1542658D01*
X271432Y1543058D01*
X272132D01*
X272932Y1542791D01*
X273532Y1542258D01*
G01X281432Y1535058D02*
X277432D01*
Y1543058D01*
X281432D01*
G01X279832Y1539191D02*
X277432D01*
G01X285132Y1535058D02*
Y1543058D01*
X289732Y1535058D01*
Y1543058D01*
G01X297432Y1535058D02*
X293432D01*
Y1543058D01*
X297432D01*
G01X295832Y1539191D02*
X293432D01*
G01X301432Y1535058D02*
Y1543058D01*
X303932D01*
X304732Y1542658D01*
X305232Y1542125D01*
X305432Y1541058D01*
X305232Y1539991D01*
X304632Y1539325D01*
X303932Y1538925D01*
X301432D01*
G01X303932D02*
X305432Y1535058D01*
G01X308932D02*
X311432Y1543058D01*
X313932Y1535058D01*
G01X313032Y1537858D02*
X309832D01*
G01X319432Y1543058D02*
Y1535058D01*
G01X317132Y1543058D02*
X321732D01*
G01X329432Y1535058D02*
X325432D01*
Y1543058D01*
X329432D01*
G01X327832Y1539191D02*
X325432D01*
G01X343432Y1543058D02*
Y1535058D01*
G01X341132Y1543058D02*
X345732D01*
G01X349332Y1535058D02*
Y1543058D01*
G01X353532D02*
Y1535058D01*
G01Y1539058D02*
X349332D01*
G01X361432Y1535058D02*
X357432D01*
Y1543058D01*
X361432D01*
G01X359832Y1539191D02*
X357432D01*
G01X373432Y1535058D02*
Y1543058D01*
X375832D01*
X376632Y1542658D01*
X377232Y1541725D01*
X377432Y1540658D01*
X377232Y1539591D01*
X376732Y1538791D01*
X375832Y1538391D01*
X373432D01*
G01X380932Y1535058D02*
X383432Y1543058D01*
X385932Y1535058D01*
G01X385032Y1537858D02*
X381832D01*
G01X389232Y1535058D02*
Y1543058D01*
X391232D01*
X392032Y1542658D01*
X392632Y1542125D01*
X393132Y1541325D01*
X393532Y1540391D01*
X393632Y1539058D01*
X393532Y1537725D01*
X393132Y1536791D01*
X392632Y1535991D01*
X392032Y1535458D01*
X391232Y1535058D01*
X389232D01*
G01X397332Y1536124D02*
X398132Y1535458D01*
X399032Y1535058D01*
X399832D01*
X400632Y1535458D01*
X401232Y1536124D01*
X401532Y1537058D01*
X401332Y1537991D01*
X400832Y1538791D01*
X399932Y1539325D01*
X398732Y1539591D01*
X398032Y1540125D01*
X397732Y1541058D01*
X397932Y1541991D01*
X398432Y1542658D01*
X399132Y1543058D01*
X399832D01*
X400532Y1542791D01*
X401132Y1542125D01*
G01X412932Y1535058D02*
X415432Y1543058D01*
X417932Y1535058D01*
G01X417032Y1537858D02*
X413832D01*
G01X421132Y1535058D02*
Y1543058D01*
X425732Y1535058D01*
Y1543058D01*
G01X429232Y1535058D02*
Y1543058D01*
X431232D01*
X432032Y1542658D01*
X432632Y1542125D01*
X433132Y1541325D01*
X433532Y1540391D01*
X433632Y1539058D01*
X433532Y1537725D01*
X433132Y1536791D01*
X432632Y1535991D01*
X432032Y1535458D01*
X431232Y1535058D01*
X429232D01*
G01X444832D02*
Y1543058D01*
X447432Y1536391D01*
X450032Y1543058D01*
Y1535058D01*
G01X452932D02*
X455432Y1543058D01*
X457932Y1535058D01*
G01X457032Y1537858D02*
X453832D01*
G01X461332Y1536124D02*
X462132Y1535458D01*
X463032Y1535058D01*
X463832D01*
X464632Y1535458D01*
X465232Y1536124D01*
X465532Y1537058D01*
X465332Y1537991D01*
X464832Y1538791D01*
X463932Y1539325D01*
X462732Y1539591D01*
X462032Y1540125D01*
X461732Y1541058D01*
X461932Y1541991D01*
X462432Y1542658D01*
X463132Y1543058D01*
X463832D01*
X464532Y1542791D01*
X465132Y1542125D01*
G01X469232Y1535058D02*
Y1543058D01*
G01X473032D02*
X469232Y1538124D01*
G01X473632Y1535058D02*
X470932Y1540391D01*
G01X484932Y1535058D02*
X487432Y1543058D01*
X489932Y1535058D01*
G01X489032Y1537858D02*
X485832D01*
G01X493132Y1535058D02*
Y1543058D01*
X497732Y1535058D01*
Y1543058D01*
G01X501232Y1535058D02*
Y1543058D01*
X503232D01*
X504032Y1542658D01*
X504632Y1542125D01*
X505132Y1541325D01*
X505532Y1540391D01*
X505632Y1539058D01*
X505532Y1537725D01*
X505132Y1536791D01*
X504632Y1535991D01*
X504032Y1535458D01*
X503232Y1535058D01*
X501232D01*
G01X516932D02*
X519432Y1543058D01*
X521932Y1535058D01*
G01X521032Y1537858D02*
X517832D01*
G01X525232Y1535058D02*
Y1543058D01*
X527232D01*
X528032Y1542658D01*
X528632Y1542125D01*
X529132Y1541325D01*
X529532Y1540391D01*
X529632Y1539058D01*
X529532Y1537725D01*
X529132Y1536791D01*
X528632Y1535991D01*
X528032Y1535458D01*
X527232Y1535058D01*
X525232D01*
G01X533232D02*
Y1543058D01*
X535232D01*
X536032Y1542658D01*
X536632Y1542125D01*
X537132Y1541325D01*
X537532Y1540391D01*
X537632Y1539058D01*
X537532Y1537725D01*
X537132Y1536791D01*
X536632Y1535991D01*
X536032Y1535458D01*
X535232Y1535058D01*
X533232D01*
G01X551432Y1543058D02*
Y1535058D01*
G01X549132Y1543058D02*
X553732D01*
G01X557332Y1535058D02*
Y1543058D01*
G01X561532D02*
Y1535058D01*
G01Y1539058D02*
X557332D01*
G01X569432Y1535058D02*
X565432D01*
Y1543058D01*
X569432D01*
G01X567832Y1539191D02*
X565432D01*
G01X583432Y1543058D02*
Y1535058D01*
G01X581132Y1543058D02*
X585732D01*
G01X593432Y1535058D02*
X589432D01*
Y1543058D01*
X593432D01*
G01X591832Y1539191D02*
X589432D01*
G01X597332Y1536124D02*
X598132Y1535458D01*
X599032Y1535058D01*
X599832D01*
X600632Y1535458D01*
X601232Y1536124D01*
X601532Y1537058D01*
X601332Y1537991D01*
X600832Y1538791D01*
X599932Y1539325D01*
X598732Y1539591D01*
X598032Y1540125D01*
X597732Y1541058D01*
X597932Y1541991D01*
X598432Y1542658D01*
X599132Y1543058D01*
X599832D01*
X600532Y1542791D01*
X601132Y1542125D01*
G01X607432Y1543058D02*
Y1535058D01*
G01X605132Y1543058D02*
X609732D01*
G01X621432Y1535058D02*
Y1543058D01*
X623832D01*
X624632Y1542658D01*
X625232Y1541725D01*
X625432Y1540658D01*
X625232Y1539591D01*
X624732Y1538791D01*
X623832Y1538391D01*
X621432D01*
G01X628932Y1535058D02*
X631432Y1543058D01*
X633932Y1535058D01*
G01X633032Y1537858D02*
X629832D01*
G01X637232Y1535058D02*
Y1543058D01*
X639232D01*
X640032Y1542658D01*
X640632Y1542125D01*
X641132Y1541325D01*
X641532Y1540391D01*
X641632Y1539058D01*
X641532Y1537725D01*
X641132Y1536791D01*
X640632Y1535991D01*
X640032Y1535458D01*
X639232Y1535058D01*
X637232D01*
G01X645332Y1536124D02*
X646132Y1535458D01*
X647032Y1535058D01*
X647832D01*
X648632Y1535458D01*
X649232Y1536124D01*
X649532Y1537058D01*
X649332Y1537991D01*
X648832Y1538791D01*
X647932Y1539325D01*
X646732Y1539591D01*
X646032Y1540125D01*
X645732Y1541058D01*
X645932Y1541991D01*
X646432Y1542658D01*
X647132Y1543058D01*
X647832D01*
X648532Y1542791D01*
X649132Y1542125D01*
G01X32232Y1761658D02*
X32832Y1760725D01*
X33632Y1760191D01*
X34532Y1760058D01*
X35332Y1760191D01*
X36132Y1760858D01*
X36632Y1761658D01*
X36732Y1762458D01*
X36532Y1763391D01*
X35832Y1764058D01*
X35132Y1764325D01*
X34232D01*
G01X35132D02*
X35732Y1764725D01*
X36232Y1765391D01*
X36432Y1766191D01*
X36232Y1766991D01*
X35732Y1767658D01*
X34832Y1768058D01*
X33932Y1767925D01*
X33032Y1767391D01*
G01X42432Y1759791D02*
X42232Y1759925D01*
Y1760191D01*
X42432Y1760325D01*
X42632Y1760191D01*
Y1759925D01*
X42432Y1759791D01*
G01X48432Y1760058D02*
Y1768058D01*
X50832D01*
X51632Y1767658D01*
X52232Y1766725D01*
X52432Y1765658D01*
X52232Y1764591D01*
X51732Y1763791D01*
X50832Y1763391D01*
X48432D01*
G01X60632Y1767391D02*
X60032Y1767791D01*
X59332Y1768058D01*
X58532D01*
X57632Y1767658D01*
X56932Y1766991D01*
X56432Y1766191D01*
X56032Y1764858D01*
X55932Y1763658D01*
X56132Y1762458D01*
X56432Y1761658D01*
X57032Y1760858D01*
X57732Y1760325D01*
X58432Y1760058D01*
X59132D01*
X59832Y1760325D01*
X60432Y1760725D01*
X60932Y1761258D01*
G01X67232Y1764325D02*
X67632Y1764725D01*
X67932Y1765391D01*
X68132Y1766325D01*
X67932Y1767125D01*
X67532Y1767658D01*
X66832Y1768058D01*
X64132D01*
Y1760058D01*
X67432D01*
X68132Y1760591D01*
X68532Y1761391D01*
X68732Y1762325D01*
X68532Y1763258D01*
X67932Y1764058D01*
X67232Y1764325D01*
X64132D01*
G01X80432Y1760058D02*
Y1768058D01*
X82832D01*
X83632Y1767658D01*
X84232Y1766725D01*
X84432Y1765658D01*
X84232Y1764591D01*
X83732Y1763791D01*
X82832Y1763391D01*
X80432D01*
G01X88432Y1760058D02*
Y1768058D01*
X90932D01*
X91732Y1767658D01*
X92232Y1767125D01*
X92432Y1766058D01*
X92232Y1764991D01*
X91632Y1764325D01*
X90932Y1763925D01*
X88432D01*
G01X90932D02*
X92432Y1760058D01*
G01X98432D02*
X97632Y1760191D01*
X96932Y1760725D01*
X96332Y1761525D01*
X95932Y1762458D01*
X95732Y1763525D01*
Y1764591D01*
X95932Y1765658D01*
X96332Y1766591D01*
X96932Y1767391D01*
X97632Y1767925D01*
X98432Y1768058D01*
X99232Y1767925D01*
X99932Y1767391D01*
X100532Y1766591D01*
X100932Y1765658D01*
X101132Y1764591D01*
Y1763525D01*
X100932Y1762458D01*
X100532Y1761525D01*
X99932Y1760725D01*
X99232Y1760191D01*
X98432Y1760058D01*
G01X108632Y1767391D02*
X108032Y1767791D01*
X107332Y1768058D01*
X106532D01*
X105632Y1767658D01*
X104932Y1766991D01*
X104432Y1766191D01*
X104032Y1764858D01*
X103932Y1763658D01*
X104132Y1762458D01*
X104432Y1761658D01*
X105032Y1760858D01*
X105732Y1760325D01*
X106432Y1760058D01*
X107132D01*
X107832Y1760325D01*
X108432Y1760725D01*
X108932Y1761258D01*
G01X116432Y1760058D02*
X112432D01*
Y1768058D01*
X116432D01*
G01X114832Y1764191D02*
X112432D01*
G01X120332Y1761124D02*
X121132Y1760458D01*
X122032Y1760058D01*
X122832D01*
X123632Y1760458D01*
X124232Y1761124D01*
X124532Y1762058D01*
X124332Y1762991D01*
X123832Y1763791D01*
X122932Y1764325D01*
X121732Y1764591D01*
X121032Y1765125D01*
X120732Y1766058D01*
X120932Y1766991D01*
X121432Y1767658D01*
X122132Y1768058D01*
X122832D01*
X123532Y1767791D01*
X124132Y1767125D01*
G01X128332Y1761124D02*
X129132Y1760458D01*
X130032Y1760058D01*
X130832D01*
X131632Y1760458D01*
X132232Y1761124D01*
X132532Y1762058D01*
X132332Y1762991D01*
X131832Y1763791D01*
X130932Y1764325D01*
X129732Y1764591D01*
X129032Y1765125D01*
X128732Y1766058D01*
X128932Y1766991D01*
X129432Y1767658D01*
X130132Y1768058D01*
X130832D01*
X131532Y1767791D01*
X132132Y1767125D01*
G01X138432Y1759791D02*
X138232Y1759925D01*
Y1760191D01*
X138432Y1760325D01*
X138632Y1760191D01*
Y1759925D01*
X138432Y1759791D01*
G01Y1763391D02*
X138232Y1763525D01*
Y1763791D01*
X138432Y1763925D01*
X138632Y1763791D01*
Y1763525D01*
X138432Y1763391D01*
G01X32532Y1781725D02*
X33132Y1782525D01*
X33832Y1782925D01*
X34632Y1783058D01*
X35632Y1782791D01*
X36332Y1782125D01*
X36532Y1781325D01*
X36432Y1780524D01*
X36032Y1779858D01*
X34032Y1778525D01*
X33132Y1777591D01*
X32532Y1776258D01*
X32332Y1775058D01*
X36532D01*
G01X42432Y1774791D02*
X42232Y1774925D01*
Y1775191D01*
X42432Y1775325D01*
X42632Y1775191D01*
Y1774925D01*
X42432Y1774791D01*
G01X48532Y1775058D02*
Y1783058D01*
X52332D01*
G01X50932Y1779191D02*
X48532D01*
G01X55932Y1775058D02*
X58432Y1783058D01*
X60932Y1775058D01*
G01X60032Y1777858D02*
X56832D01*
G01X67232Y1779325D02*
X67632Y1779725D01*
X67932Y1780391D01*
X68132Y1781325D01*
X67932Y1782125D01*
X67532Y1782658D01*
X66832Y1783058D01*
X64132D01*
Y1775058D01*
X67432D01*
X68132Y1775591D01*
X68532Y1776391D01*
X68732Y1777325D01*
X68532Y1778258D01*
X67932Y1779058D01*
X67232Y1779325D01*
X64132D01*
G01X72432Y1775058D02*
Y1783058D01*
X74932D01*
X75732Y1782658D01*
X76232Y1782125D01*
X76432Y1781058D01*
X76232Y1779991D01*
X75632Y1779325D01*
X74932Y1778925D01*
X72432D01*
G01X74932D02*
X76432Y1775058D01*
G01X81232Y1783058D02*
X83632D01*
G01X82432D02*
Y1775058D01*
G01X81232D02*
X83632D01*
G01X92632Y1782391D02*
X92032Y1782791D01*
X91332Y1783058D01*
X90532D01*
X89632Y1782658D01*
X88932Y1781991D01*
X88432Y1781191D01*
X88032Y1779858D01*
X87932Y1778658D01*
X88132Y1777458D01*
X88432Y1776658D01*
X89032Y1775858D01*
X89732Y1775325D01*
X90432Y1775058D01*
X91132D01*
X91832Y1775325D01*
X92432Y1775725D01*
X92932Y1776258D01*
G01X95932Y1775058D02*
X98432Y1783058D01*
X100932Y1775058D01*
G01X100032Y1777858D02*
X96832D01*
G01X106432Y1783058D02*
Y1775058D01*
G01X104132Y1783058D02*
X108732D01*
G01X116432Y1775058D02*
X112432D01*
Y1783058D01*
X116432D01*
G01X114832Y1779191D02*
X112432D01*
G01X128432Y1775058D02*
Y1783058D01*
X130832D01*
X131632Y1782658D01*
X132232Y1781725D01*
X132432Y1780658D01*
X132232Y1779591D01*
X131732Y1778791D01*
X130832Y1778391D01*
X128432D01*
G01X140432Y1775058D02*
X136432D01*
Y1783058D01*
X140432D01*
G01X138832Y1779191D02*
X136432D01*
G01X144432Y1775058D02*
Y1783058D01*
X146932D01*
X147732Y1782658D01*
X148232Y1782125D01*
X148432Y1781058D01*
X148232Y1779991D01*
X147632Y1779325D01*
X146932Y1778925D01*
X144432D01*
G01X146932D02*
X148432Y1775058D01*
G01X162432D02*
X161632Y1775191D01*
X160932Y1775725D01*
X160332Y1776525D01*
X159932Y1777458D01*
X159732Y1778525D01*
Y1779591D01*
X159932Y1780658D01*
X160332Y1781591D01*
X160932Y1782391D01*
X161632Y1782925D01*
X162432Y1783058D01*
X163232Y1782925D01*
X163932Y1782391D01*
X164532Y1781591D01*
X164932Y1780658D01*
X165132Y1779591D01*
Y1778525D01*
X164932Y1777458D01*
X164532Y1776525D01*
X163932Y1775725D01*
X163232Y1775191D01*
X162432Y1775058D01*
G01X163232Y1777191D02*
X164432Y1775058D01*
G01X168232Y1783058D02*
Y1777325D01*
X168632Y1776124D01*
X169432Y1775325D01*
X170432Y1775058D01*
X171432Y1775325D01*
X172232Y1776124D01*
X172632Y1777325D01*
Y1783058D01*
G01X175932Y1775058D02*
X178432Y1783058D01*
X180932Y1775058D01*
G01X180032Y1777858D02*
X176832D01*
G01X184132Y1775058D02*
Y1783058D01*
X188732Y1775058D01*
Y1783058D01*
G01X194432D02*
Y1775058D01*
G01X192132Y1783058D02*
X196732D01*
G01X199932Y1775058D02*
X202432Y1783058D01*
X204932Y1775058D01*
G01X204032Y1777858D02*
X200832D01*
G01X216432Y1775058D02*
Y1783058D01*
X218832D01*
X219632Y1782658D01*
X220232Y1781725D01*
X220432Y1780658D01*
X220232Y1779591D01*
X219732Y1778791D01*
X218832Y1778391D01*
X216432D01*
G01X228632Y1782391D02*
X228032Y1782791D01*
X227332Y1783058D01*
X226532D01*
X225632Y1782658D01*
X224932Y1781991D01*
X224432Y1781191D01*
X224032Y1779858D01*
X223932Y1778658D01*
X224132Y1777458D01*
X224432Y1776658D01*
X225032Y1775858D01*
X225732Y1775325D01*
X226432Y1775058D01*
X227132D01*
X227832Y1775325D01*
X228432Y1775725D01*
X228932Y1776258D01*
G01X235232Y1779325D02*
X235632Y1779725D01*
X235932Y1780391D01*
X236132Y1781325D01*
X235932Y1782125D01*
X235532Y1782658D01*
X234832Y1783058D01*
X232132D01*
Y1775058D01*
X235432D01*
X236132Y1775591D01*
X236532Y1776391D01*
X236732Y1777325D01*
X236532Y1778258D01*
X235932Y1779058D01*
X235232Y1779325D01*
X232132D01*
G01X248332Y1776124D02*
X249132Y1775458D01*
X250032Y1775058D01*
X250832D01*
X251632Y1775458D01*
X252232Y1776124D01*
X252532Y1777058D01*
X252332Y1777991D01*
X251832Y1778791D01*
X250932Y1779325D01*
X249732Y1779591D01*
X249032Y1780125D01*
X248732Y1781058D01*
X248932Y1781991D01*
X249432Y1782658D01*
X250132Y1783058D01*
X250832D01*
X251532Y1782791D01*
X252132Y1782125D01*
G01X256432Y1775058D02*
Y1783058D01*
X258832D01*
X259632Y1782658D01*
X260232Y1781725D01*
X260432Y1780658D01*
X260232Y1779591D01*
X259732Y1778791D01*
X258832Y1778391D01*
X256432D01*
G01X268432Y1775058D02*
X264432D01*
Y1783058D01*
X268432D01*
G01X266832Y1779191D02*
X264432D01*
G01X276632Y1782391D02*
X276032Y1782791D01*
X275332Y1783058D01*
X274532D01*
X273632Y1782658D01*
X272932Y1781991D01*
X272432Y1781191D01*
X272032Y1779858D01*
X271932Y1778658D01*
X272132Y1777458D01*
X272432Y1776658D01*
X273032Y1775858D01*
X273732Y1775325D01*
X274432Y1775058D01*
X275132D01*
X275832Y1775325D01*
X276432Y1775725D01*
X276932Y1776258D01*
G01X281232Y1783058D02*
X283632D01*
G01X282432D02*
Y1775058D01*
G01X281232D02*
X283632D01*
G01X288532D02*
Y1783058D01*
X292332D01*
G01X290932Y1779191D02*
X288532D01*
G01X297232Y1783058D02*
X299632D01*
G01X298432D02*
Y1775058D01*
G01X297232D02*
X299632D01*
G01X308632Y1782391D02*
X308032Y1782791D01*
X307332Y1783058D01*
X306532D01*
X305632Y1782658D01*
X304932Y1781991D01*
X304432Y1781191D01*
X304032Y1779858D01*
X303932Y1778658D01*
X304132Y1777458D01*
X304432Y1776658D01*
X305032Y1775858D01*
X305732Y1775325D01*
X306432Y1775058D01*
X307132D01*
X307832Y1775325D01*
X308432Y1775725D01*
X308932Y1776258D01*
G01X311932Y1775058D02*
X314432Y1783058D01*
X316932Y1775058D01*
G01X316032Y1777858D02*
X312832D01*
G01X322432Y1783058D02*
Y1775058D01*
G01X320132Y1783058D02*
X324732D01*
G01X329232D02*
X331632D01*
G01X330432D02*
Y1775058D01*
G01X329232D02*
X331632D01*
G01X338432D02*
X337632Y1775191D01*
X336932Y1775725D01*
X336332Y1776525D01*
X335932Y1777458D01*
X335732Y1778525D01*
Y1779591D01*
X335932Y1780658D01*
X336332Y1781591D01*
X336932Y1782391D01*
X337632Y1782925D01*
X338432Y1783058D01*
X339232Y1782925D01*
X339932Y1782391D01*
X340532Y1781591D01*
X340932Y1780658D01*
X341132Y1779591D01*
Y1778525D01*
X340932Y1777458D01*
X340532Y1776525D01*
X339932Y1775725D01*
X339232Y1775191D01*
X338432Y1775058D01*
G01X344132D02*
Y1783058D01*
X348732Y1775058D01*
Y1783058D01*
G01X354432Y1774791D02*
X354232Y1774925D01*
Y1775191D01*
X354432Y1775325D01*
X354632Y1775191D01*
Y1774925D01*
X354432Y1774791D01*
G01X34432Y1790058D02*
Y1798058D01*
X33232Y1796458D01*
G01Y1790058D02*
X35632D01*
G01X42432Y1789791D02*
X42232Y1789925D01*
Y1790191D01*
X42432Y1790325D01*
X42632Y1790191D01*
Y1789925D01*
X42432Y1789791D01*
G01X48432Y1790058D02*
Y1798058D01*
X50832D01*
X51632Y1797658D01*
X52232Y1796725D01*
X52432Y1795658D01*
X52232Y1794591D01*
X51732Y1793791D01*
X50832Y1793391D01*
X48432D01*
G01X60632Y1797391D02*
X60032Y1797791D01*
X59332Y1798058D01*
X58532D01*
X57632Y1797658D01*
X56932Y1796991D01*
X56432Y1796191D01*
X56032Y1794858D01*
X55932Y1793658D01*
X56132Y1792458D01*
X56432Y1791658D01*
X57032Y1790858D01*
X57732Y1790325D01*
X58432Y1790058D01*
X59132D01*
X59832Y1790325D01*
X60432Y1790725D01*
X60932Y1791258D01*
G01X67232Y1794325D02*
X67632Y1794725D01*
X67932Y1795391D01*
X68132Y1796325D01*
X67932Y1797125D01*
X67532Y1797658D01*
X66832Y1798058D01*
X64132D01*
Y1790058D01*
X67432D01*
X68132Y1790591D01*
X68532Y1791391D01*
X68732Y1792325D01*
X68532Y1793258D01*
X67932Y1794058D01*
X67232Y1794325D01*
X64132D01*
G01X80332Y1791124D02*
X81132Y1790458D01*
X82032Y1790058D01*
X82832D01*
X83632Y1790458D01*
X84232Y1791124D01*
X84532Y1792058D01*
X84332Y1792991D01*
X83832Y1793791D01*
X82932Y1794325D01*
X81732Y1794591D01*
X81032Y1795125D01*
X80732Y1796058D01*
X80932Y1796991D01*
X81432Y1797658D01*
X82132Y1798058D01*
X82832D01*
X83532Y1797791D01*
X84132Y1797125D01*
G01X89232Y1798058D02*
X91632D01*
G01X90432D02*
Y1790058D01*
G01X89232D02*
X91632D01*
G01X96532Y1798058D02*
X100332D01*
X96532Y1790058D01*
X100332D01*
G01X108432D02*
X104432D01*
Y1798058D01*
X108432D01*
G01X106832Y1794191D02*
X104432D01*
G01X138432Y1789791D02*
X138232Y1789925D01*
Y1790191D01*
X138432Y1790325D01*
X138632Y1790191D01*
Y1789925D01*
X138432Y1789791D01*
G01Y1793391D02*
X138232Y1793525D01*
Y1793791D01*
X138432Y1793925D01*
X138632Y1793791D01*
Y1793525D01*
X138432Y1793391D01*
G01X152532Y1790058D02*
Y1798058D01*
X156332D01*
G01X154932Y1794191D02*
X152532D01*
G01X162432Y1790058D02*
X161632Y1790191D01*
X160932Y1790725D01*
X160332Y1791525D01*
X159932Y1792458D01*
X159732Y1793525D01*
Y1794591D01*
X159932Y1795658D01*
X160332Y1796591D01*
X160932Y1797391D01*
X161632Y1797925D01*
X162432Y1798058D01*
X163232Y1797925D01*
X163932Y1797391D01*
X164532Y1796591D01*
X164932Y1795658D01*
X165132Y1794591D01*
Y1793525D01*
X164932Y1792458D01*
X164532Y1791525D01*
X163932Y1790725D01*
X163232Y1790191D01*
X162432Y1790058D01*
G01X168432Y1798058D02*
Y1790058D01*
X172432D01*
G01X176432Y1798058D02*
Y1790058D01*
X180432D01*
G01X186432D02*
X185632Y1790191D01*
X184932Y1790725D01*
X184332Y1791525D01*
X183932Y1792458D01*
X183732Y1793525D01*
Y1794591D01*
X183932Y1795658D01*
X184332Y1796591D01*
X184932Y1797391D01*
X185632Y1797925D01*
X186432Y1798058D01*
X187232Y1797925D01*
X187932Y1797391D01*
X188532Y1796591D01*
X188932Y1795658D01*
X189132Y1794591D01*
Y1793525D01*
X188932Y1792458D01*
X188532Y1791525D01*
X187932Y1790725D01*
X187232Y1790191D01*
X186432Y1790058D01*
G01X191432Y1798058D02*
X192832Y1790058D01*
X194432Y1798058D01*
X196032Y1790058D01*
X197432Y1798058D01*
G01X211032Y1794058D02*
X213032D01*
Y1791658D01*
X212432Y1790858D01*
X211732Y1790325D01*
X210732Y1790058D01*
X209732Y1790325D01*
X209032Y1790858D01*
X208432Y1791658D01*
X208032Y1792591D01*
X207832Y1793658D01*
Y1794591D01*
X208032Y1795391D01*
X208432Y1796325D01*
X209032Y1797125D01*
X209632Y1797658D01*
X210432Y1798058D01*
X211132D01*
X211932Y1797791D01*
X212532Y1797258D01*
G01X220432Y1790058D02*
X216432D01*
Y1798058D01*
X220432D01*
G01X218832Y1794191D02*
X216432D01*
G01X224432Y1790058D02*
Y1798058D01*
X226932D01*
X227732Y1797658D01*
X228232Y1797125D01*
X228432Y1796058D01*
X228232Y1794991D01*
X227632Y1794325D01*
X226932Y1793925D01*
X224432D01*
G01X226932D02*
X228432Y1790058D01*
G01X235232Y1794325D02*
X235632Y1794725D01*
X235932Y1795391D01*
X236132Y1796325D01*
X235932Y1797125D01*
X235532Y1797658D01*
X234832Y1798058D01*
X232132D01*
Y1790058D01*
X235432D01*
X236132Y1790591D01*
X236532Y1791391D01*
X236732Y1792325D01*
X236532Y1793258D01*
X235932Y1794058D01*
X235232Y1794325D01*
X232132D01*
G01X244432Y1790058D02*
X240432D01*
Y1798058D01*
X244432D01*
G01X242832Y1794191D02*
X240432D01*
G01X248432Y1790058D02*
Y1798058D01*
X250932D01*
X251732Y1797658D01*
X252232Y1797125D01*
X252432Y1796058D01*
X252232Y1794991D01*
X251632Y1794325D01*
X250932Y1793925D01*
X248432D01*
G01X250932D02*
X252432Y1790058D01*
G01X264532D02*
Y1798058D01*
X268332D01*
G01X266932Y1794191D02*
X264532D01*
G01X273232Y1798058D02*
X275632D01*
G01X274432D02*
Y1790058D01*
G01X273232D02*
X275632D01*
G01X280432Y1798058D02*
Y1790058D01*
X284432D01*
G01X292432D02*
X288432D01*
Y1798058D01*
X292432D01*
G01X290832Y1794191D02*
X288432D01*
G01X297732Y1787658D02*
X299132Y1789525D01*
Y1791391D01*
X297732D01*
Y1789525D01*
X299132D01*
G01Y1792725D02*
Y1794591D01*
X297732D01*
Y1792725D01*
X299132D01*
G01X311432Y1798058D02*
X312832Y1790058D01*
X314432Y1798058D01*
X316032Y1790058D01*
X317432Y1798058D01*
G01X321232D02*
X323632D01*
G01X322432D02*
Y1790058D01*
G01X321232D02*
X323632D01*
G01X330432Y1798058D02*
Y1790058D01*
G01X328132Y1798058D02*
X332732D01*
G01X336332Y1790058D02*
Y1798058D01*
G01X340532D02*
Y1790058D01*
G01Y1794058D02*
X336332D01*
G01X354432Y1798058D02*
Y1790058D01*
G01X352132Y1798058D02*
X356732D01*
G01X362432Y1790058D02*
X361632Y1790191D01*
X360932Y1790725D01*
X360332Y1791525D01*
X359932Y1792458D01*
X359732Y1793525D01*
Y1794591D01*
X359932Y1795658D01*
X360332Y1796591D01*
X360932Y1797391D01*
X361632Y1797925D01*
X362432Y1798058D01*
X363232Y1797925D01*
X363932Y1797391D01*
X364532Y1796591D01*
X364932Y1795658D01*
X365132Y1794591D01*
Y1793525D01*
X364932Y1792458D01*
X364532Y1791525D01*
X363932Y1790725D01*
X363232Y1790191D01*
X362432Y1790058D01*
G01X368432Y1798058D02*
Y1790058D01*
X372432D01*
G01X380432D02*
X376432D01*
Y1798058D01*
X380432D01*
G01X378832Y1794191D02*
X376432D01*
G01X384432Y1790058D02*
Y1798058D01*
X386932D01*
X387732Y1797658D01*
X388232Y1797125D01*
X388432Y1796058D01*
X388232Y1794991D01*
X387632Y1794325D01*
X386932Y1793925D01*
X384432D01*
G01X386932D02*
X388432Y1790058D01*
G01X391932D02*
X394432Y1798058D01*
X396932Y1790058D01*
G01X396032Y1792858D02*
X392832D01*
G01X400132Y1790058D02*
Y1798058D01*
X404732Y1790058D01*
Y1798058D01*
G01X412632Y1797391D02*
X412032Y1797791D01*
X411332Y1798058D01*
X410532D01*
X409632Y1797658D01*
X408932Y1796991D01*
X408432Y1796191D01*
X408032Y1794858D01*
X407932Y1793658D01*
X408132Y1792458D01*
X408432Y1791658D01*
X409032Y1790858D01*
X409732Y1790325D01*
X410432Y1790058D01*
X411132D01*
X411832Y1790325D01*
X412432Y1790725D01*
X412932Y1791258D01*
G01X420432Y1790058D02*
X416432D01*
Y1798058D01*
X420432D01*
G01X418832Y1794191D02*
X416432D01*
G01X433132Y1791525D02*
X435732D01*
G01Y1793925D02*
X433132D01*
G01X441332Y1792725D02*
X443732D01*
G01X442432Y1794458D02*
Y1790991D01*
G01X448632Y1789791D02*
X452232Y1798058D01*
G01X457132Y1792725D02*
X459732D01*
G01X466432Y1798058D02*
X465632Y1797791D01*
X465032Y1797125D01*
X464632Y1796325D01*
X464332Y1795258D01*
X464232Y1794058D01*
X464332Y1792858D01*
X464632Y1791791D01*
X465032Y1790991D01*
X465632Y1790325D01*
X466432Y1790058D01*
X467232Y1790325D01*
X467832Y1790991D01*
X468232Y1791791D01*
X468532Y1792858D01*
X468632Y1794058D01*
X468532Y1795258D01*
X468232Y1796325D01*
X467832Y1797125D01*
X467232Y1797791D01*
X466432Y1798058D01*
G01X474432Y1789791D02*
X474232Y1789925D01*
Y1790191D01*
X474432Y1790325D01*
X474632Y1790191D01*
Y1789925D01*
X474432Y1789791D01*
G01X482432Y1790058D02*
Y1798058D01*
X481232Y1796458D01*
G01Y1790058D02*
X483632D01*
G01X488232Y1791258D02*
X488832Y1790591D01*
X489532Y1790191D01*
X490432Y1790058D01*
X491332Y1790325D01*
X492032Y1790858D01*
X492532Y1791791D01*
X492632Y1792858D01*
X492432Y1793925D01*
X491932Y1794591D01*
X491232Y1795125D01*
X490532Y1795258D01*
X489832Y1795125D01*
X488932Y1794591D01*
X489232Y1798058D01*
X491932D01*
G01X495832Y1790058D02*
Y1798058D01*
X498432Y1791391D01*
X501032Y1798058D01*
Y1790058D01*
G01X503832D02*
Y1798058D01*
X506432Y1791391D01*
X509032Y1798058D01*
Y1790058D01*
G01X32132Y1805058D02*
Y1813058D01*
X36732Y1805058D01*
Y1813058D01*
G01X42432Y1805058D02*
X41632Y1805191D01*
X40932Y1805725D01*
X40332Y1806525D01*
X39932Y1807458D01*
X39732Y1808525D01*
Y1809591D01*
X39932Y1810658D01*
X40332Y1811591D01*
X40932Y1812391D01*
X41632Y1812925D01*
X42432Y1813058D01*
X43232Y1812925D01*
X43932Y1812391D01*
X44532Y1811591D01*
X44932Y1810658D01*
X45132Y1809591D01*
Y1808525D01*
X44932Y1807458D01*
X44532Y1806525D01*
X43932Y1805725D01*
X43232Y1805191D01*
X42432Y1805058D01*
G01X50432Y1813058D02*
Y1805058D01*
G01X48132Y1813058D02*
X52732D01*
G01X60432Y1805058D02*
X56432D01*
Y1813058D01*
X60432D01*
G01X58832Y1809191D02*
X56432D01*
G01X64332Y1806124D02*
X65132Y1805458D01*
X66032Y1805058D01*
X66832D01*
X67632Y1805458D01*
X68232Y1806124D01*
X68532Y1807058D01*
X68332Y1807991D01*
X67832Y1808791D01*
X66932Y1809325D01*
X65732Y1809591D01*
X65032Y1810125D01*
X64732Y1811058D01*
X64932Y1811991D01*
X65432Y1812658D01*
X66132Y1813058D01*
X66832D01*
X67532Y1812791D01*
X68132Y1812125D01*
G01X74432Y1804791D02*
X74232Y1804925D01*
Y1805191D01*
X74432Y1805325D01*
X74632Y1805191D01*
Y1804925D01*
X74432Y1804791D01*
G01Y1808391D02*
X74232Y1808525D01*
Y1808791D01*
X74432Y1808925D01*
X74632Y1808791D01*
Y1808525D01*
X74432Y1808391D01*
G01X81932Y1802391D02*
X80932Y1803725D01*
X80432Y1805058D01*
Y1810391D01*
X80932Y1811725D01*
X81932Y1813058D01*
G01X88232D02*
Y1807325D01*
X88632Y1806124D01*
X89432Y1805325D01*
X90432Y1805058D01*
X91432Y1805325D01*
X92232Y1806124D01*
X92632Y1807325D01*
Y1813058D01*
G01X96132Y1805058D02*
Y1813058D01*
X100732Y1805058D01*
Y1813058D01*
G01X104432D02*
Y1805058D01*
X108432D01*
G01X116432D02*
X112432D01*
Y1813058D01*
X116432D01*
G01X114832Y1809191D02*
X112432D01*
G01X120332Y1806124D02*
X121132Y1805458D01*
X122032Y1805058D01*
X122832D01*
X123632Y1805458D01*
X124232Y1806124D01*
X124532Y1807058D01*
X124332Y1807991D01*
X123832Y1808791D01*
X122932Y1809325D01*
X121732Y1809591D01*
X121032Y1810125D01*
X120732Y1811058D01*
X120932Y1811991D01*
X121432Y1812658D01*
X122132Y1813058D01*
X122832D01*
X123532Y1812791D01*
X124132Y1812125D01*
G01X128332Y1806124D02*
X129132Y1805458D01*
X130032Y1805058D01*
X130832D01*
X131632Y1805458D01*
X132232Y1806124D01*
X132532Y1807058D01*
X132332Y1807991D01*
X131832Y1808791D01*
X130932Y1809325D01*
X129732Y1809591D01*
X129032Y1810125D01*
X128732Y1811058D01*
X128932Y1811991D01*
X129432Y1812658D01*
X130132Y1813058D01*
X130832D01*
X131532Y1812791D01*
X132132Y1812125D01*
G01X146432Y1805058D02*
X145632Y1805191D01*
X144932Y1805725D01*
X144332Y1806525D01*
X143932Y1807458D01*
X143732Y1808525D01*
Y1809591D01*
X143932Y1810658D01*
X144332Y1811591D01*
X144932Y1812391D01*
X145632Y1812925D01*
X146432Y1813058D01*
X147232Y1812925D01*
X147932Y1812391D01*
X148532Y1811591D01*
X148932Y1810658D01*
X149132Y1809591D01*
Y1808525D01*
X148932Y1807458D01*
X148532Y1806525D01*
X147932Y1805725D01*
X147232Y1805191D01*
X146432Y1805058D01*
G01X154432Y1813058D02*
Y1805058D01*
G01X152132Y1813058D02*
X156732D01*
G01X160332Y1805058D02*
Y1813058D01*
G01X164532D02*
Y1805058D01*
G01Y1809058D02*
X160332D01*
G01X172432Y1805058D02*
X168432D01*
Y1813058D01*
X172432D01*
G01X170832Y1809191D02*
X168432D01*
G01X176432Y1805058D02*
Y1813058D01*
X178932D01*
X179732Y1812658D01*
X180232Y1812125D01*
X180432Y1811058D01*
X180232Y1809991D01*
X179632Y1809325D01*
X178932Y1808925D01*
X176432D01*
G01X178932D02*
X180432Y1805058D01*
G01X183432Y1813058D02*
X184832Y1805058D01*
X186432Y1813058D01*
X188032Y1805058D01*
X189432Y1813058D01*
G01X193232D02*
X195632D01*
G01X194432D02*
Y1805058D01*
G01X193232D02*
X195632D01*
G01X200332Y1806124D02*
X201132Y1805458D01*
X202032Y1805058D01*
X202832D01*
X203632Y1805458D01*
X204232Y1806124D01*
X204532Y1807058D01*
X204332Y1807991D01*
X203832Y1808791D01*
X202932Y1809325D01*
X201732Y1809591D01*
X201032Y1810125D01*
X200732Y1811058D01*
X200932Y1811991D01*
X201432Y1812658D01*
X202132Y1813058D01*
X202832D01*
X203532Y1812791D01*
X204132Y1812125D01*
G01X212432Y1805058D02*
X208432D01*
Y1813058D01*
X212432D01*
G01X210832Y1809191D02*
X208432D01*
G01X224332Y1806124D02*
X225132Y1805458D01*
X226032Y1805058D01*
X226832D01*
X227632Y1805458D01*
X228232Y1806124D01*
X228532Y1807058D01*
X228332Y1807991D01*
X227832Y1808791D01*
X226932Y1809325D01*
X225732Y1809591D01*
X225032Y1810125D01*
X224732Y1811058D01*
X224932Y1811991D01*
X225432Y1812658D01*
X226132Y1813058D01*
X226832D01*
X227532Y1812791D01*
X228132Y1812125D01*
G01X232432Y1805058D02*
Y1813058D01*
X234832D01*
X235632Y1812658D01*
X236232Y1811725D01*
X236432Y1810658D01*
X236232Y1809591D01*
X235732Y1808791D01*
X234832Y1808391D01*
X232432D01*
G01X244432Y1805058D02*
X240432D01*
Y1813058D01*
X244432D01*
G01X242832Y1809191D02*
X240432D01*
G01X252632Y1812391D02*
X252032Y1812791D01*
X251332Y1813058D01*
X250532D01*
X249632Y1812658D01*
X248932Y1811991D01*
X248432Y1811191D01*
X248032Y1809858D01*
X247932Y1808658D01*
X248132Y1807458D01*
X248432Y1806658D01*
X249032Y1805858D01*
X249732Y1805325D01*
X250432Y1805058D01*
X251132D01*
X251832Y1805325D01*
X252432Y1805725D01*
X252932Y1806258D01*
G01X257232Y1813058D02*
X259632D01*
G01X258432D02*
Y1805058D01*
G01X257232D02*
X259632D01*
G01X264532D02*
Y1813058D01*
X268332D01*
G01X266932Y1809191D02*
X264532D01*
G01X273232Y1813058D02*
X275632D01*
G01X274432D02*
Y1805058D01*
G01X273232D02*
X275632D01*
G01X284432D02*
X280432D01*
Y1813058D01*
X284432D01*
G01X282832Y1809191D02*
X280432D01*
G01X288232Y1805058D02*
Y1813058D01*
X290232D01*
X291032Y1812658D01*
X291632Y1812125D01*
X292132Y1811325D01*
X292532Y1810391D01*
X292632Y1809058D01*
X292532Y1807725D01*
X292132Y1806791D01*
X291632Y1805991D01*
X291032Y1805458D01*
X290232Y1805058D01*
X288232D01*
G01X305232Y1813058D02*
X307632D01*
G01X306432D02*
Y1805058D01*
G01X305232D02*
X307632D01*
G01X312132D02*
Y1813058D01*
X316732Y1805058D01*
Y1813058D01*
G01X330432D02*
Y1805058D01*
G01X328132Y1813058D02*
X332732D01*
G01X336532Y1808391D02*
X337232Y1809325D01*
X337832Y1809858D01*
X338632Y1810125D01*
X339332Y1809858D01*
X339832Y1809325D01*
X340232Y1808525D01*
X340332Y1807591D01*
X340232Y1806791D01*
X339832Y1805991D01*
X339232Y1805325D01*
X338532Y1805058D01*
X337732Y1805325D01*
X337032Y1806124D01*
X336632Y1807325D01*
X336532Y1808658D01*
X336732Y1810391D01*
X337032Y1811325D01*
X337532Y1812258D01*
X338232Y1812925D01*
X338932Y1813058D01*
X339632Y1812791D01*
X340132Y1812125D01*
G01X343832Y1805058D02*
Y1813058D01*
X346432Y1806391D01*
X349032Y1813058D01*
Y1805058D01*
G01X351432Y1802391D02*
X357432D01*
G01X364632Y1812391D02*
X364032Y1812791D01*
X363332Y1813058D01*
X362532D01*
X361632Y1812658D01*
X360932Y1811991D01*
X360432Y1811191D01*
X360032Y1809858D01*
X359932Y1808658D01*
X360132Y1807458D01*
X360432Y1806658D01*
X361032Y1805858D01*
X361732Y1805325D01*
X362432Y1805058D01*
X363132D01*
X363832Y1805325D01*
X364432Y1805725D01*
X364932Y1806258D01*
G01X367832Y1805058D02*
Y1813058D01*
X370432Y1806391D01*
X373032Y1813058D01*
Y1805058D01*
G01X375432Y1802391D02*
X381432D01*
G01X384232Y1805058D02*
Y1813058D01*
X386232D01*
X387032Y1812658D01*
X387632Y1812125D01*
X388132Y1811325D01*
X388532Y1810391D01*
X388632Y1809058D01*
X388532Y1807725D01*
X388132Y1806791D01*
X387632Y1805991D01*
X387032Y1805458D01*
X386232Y1805058D01*
X384232D01*
G01X391432Y1802391D02*
X397432D01*
G01X400432Y1805058D02*
Y1813058D01*
X402832D01*
X403632Y1812658D01*
X404232Y1811725D01*
X404432Y1810658D01*
X404232Y1809591D01*
X403732Y1808791D01*
X402832Y1808391D01*
X400432D01*
G01X412632Y1812391D02*
X412032Y1812791D01*
X411332Y1813058D01*
X410532D01*
X409632Y1812658D01*
X408932Y1811991D01*
X408432Y1811191D01*
X408032Y1809858D01*
X407932Y1808658D01*
X408132Y1807458D01*
X408432Y1806658D01*
X409032Y1805858D01*
X409732Y1805325D01*
X410432Y1805058D01*
X411132D01*
X411832Y1805325D01*
X412432Y1805725D01*
X412932Y1806258D01*
G01X419232Y1809325D02*
X419632Y1809725D01*
X419932Y1810391D01*
X420132Y1811325D01*
X419932Y1812125D01*
X419532Y1812658D01*
X418832Y1813058D01*
X416132D01*
Y1805058D01*
X419432D01*
X420132Y1805591D01*
X420532Y1806391D01*
X420732Y1807325D01*
X420532Y1808258D01*
X419932Y1809058D01*
X419232Y1809325D01*
X416132D01*
G01X423432Y1802391D02*
X429432D01*
G01X432332Y1806124D02*
X433132Y1805458D01*
X434032Y1805058D01*
X434832D01*
X435632Y1805458D01*
X436232Y1806124D01*
X436532Y1807058D01*
X436332Y1807991D01*
X435832Y1808791D01*
X434932Y1809325D01*
X433732Y1809591D01*
X433032Y1810125D01*
X432732Y1811058D01*
X432932Y1811991D01*
X433432Y1812658D01*
X434132Y1813058D01*
X434832D01*
X435532Y1812791D01*
X436132Y1812125D01*
G01X440432Y1805058D02*
Y1813058D01*
X442832D01*
X443632Y1812658D01*
X444232Y1811725D01*
X444432Y1810658D01*
X444232Y1809591D01*
X443732Y1808791D01*
X442832Y1808391D01*
X440432D01*
G01X452432Y1805058D02*
X448432D01*
Y1813058D01*
X452432D01*
G01X450832Y1809191D02*
X448432D01*
G01X460632Y1812391D02*
X460032Y1812791D01*
X459332Y1813058D01*
X458532D01*
X457632Y1812658D01*
X456932Y1811991D01*
X456432Y1811191D01*
X456032Y1809858D01*
X455932Y1808658D01*
X456132Y1807458D01*
X456432Y1806658D01*
X457032Y1805858D01*
X457732Y1805325D01*
X458432Y1805058D01*
X459132D01*
X459832Y1805325D01*
X460432Y1805725D01*
X460932Y1806258D01*
G01X466432Y1804791D02*
X466232Y1804925D01*
Y1805191D01*
X466432Y1805325D01*
X466632Y1805191D01*
Y1804925D01*
X466432Y1804791D01*
G01X472232Y1805058D02*
Y1813058D01*
X474232D01*
X475032Y1812658D01*
X475632Y1812125D01*
X476132Y1811325D01*
X476532Y1810391D01*
X476632Y1809058D01*
X476532Y1807725D01*
X476132Y1806791D01*
X475632Y1805991D01*
X475032Y1805458D01*
X474232Y1805058D01*
X472232D01*
G01X482432D02*
X481632Y1805191D01*
X480932Y1805725D01*
X480332Y1806525D01*
X479932Y1807458D01*
X479732Y1808525D01*
Y1809591D01*
X479932Y1810658D01*
X480332Y1811591D01*
X480932Y1812391D01*
X481632Y1812925D01*
X482432Y1813058D01*
X483232Y1812925D01*
X483932Y1812391D01*
X484532Y1811591D01*
X484932Y1810658D01*
X485132Y1809591D01*
Y1808525D01*
X484932Y1807458D01*
X484532Y1806525D01*
X483932Y1805725D01*
X483232Y1805191D01*
X482432Y1805058D01*
G01X492632Y1812391D02*
X492032Y1812791D01*
X491332Y1813058D01*
X490532D01*
X489632Y1812658D01*
X488932Y1811991D01*
X488432Y1811191D01*
X488032Y1809858D01*
X487932Y1808658D01*
X488132Y1807458D01*
X488432Y1806658D01*
X489032Y1805858D01*
X489732Y1805325D01*
X490432Y1805058D01*
X491132D01*
X491832Y1805325D01*
X492432Y1805725D01*
X492932Y1806258D01*
G01X498932Y1802391D02*
X499932Y1803725D01*
X500432Y1805058D01*
Y1810391D01*
X499932Y1811725D01*
X498932Y1813058D01*
G01X61143Y-206664D02*
X58623Y-206247D01*
X56418Y-204581D01*
X54528Y-202081D01*
X53268Y-199164D01*
X52638Y-195831D01*
Y-192497D01*
X53268Y-189164D01*
X54528Y-186247D01*
X56418Y-183748D01*
X58623Y-182081D01*
X61143Y-181664D01*
X63663Y-182081D01*
X65868Y-183748D01*
X67758Y-186247D01*
X69018Y-189164D01*
X69648Y-192497D01*
Y-195831D01*
X69018Y-199164D01*
X67758Y-202081D01*
X65868Y-204581D01*
X63663Y-206247D01*
X61143Y-206664D01*
G01X63663Y-199997D02*
X67443Y-206664D01*
G01X80988Y-189998D02*
Y-201664D01*
X82248Y-204581D01*
X84138Y-206247D01*
X86343Y-206664D01*
X88548Y-206247D01*
X90438Y-204581D01*
X91698Y-201664D01*
G01Y-206664D02*
Y-189998D01*
G01X117213Y-206664D02*
Y-189998D01*
G01Y-192914D02*
X115953Y-191248D01*
X114063Y-190414D01*
X111858Y-189998D01*
X109653Y-190831D01*
X107763Y-192497D01*
X106503Y-194998D01*
X105873Y-198331D01*
X106503Y-201664D01*
X107763Y-204165D01*
X109653Y-205831D01*
X111858Y-206664D01*
X114063Y-206247D01*
X115953Y-204998D01*
X117213Y-203331D01*
G01X131388Y-206664D02*
Y-189998D01*
G01Y-194164D02*
X132648Y-192081D01*
X134538Y-190414D01*
X137058Y-189998D01*
X139263Y-190414D01*
X141153Y-192081D01*
X142098Y-194998D01*
Y-206664D01*
G01X161943Y-181664D02*
Y-206664D01*
G01X157533Y-189998D02*
X166353D01*
G01X192813Y-206664D02*
Y-189998D01*
G01Y-192914D02*
X191553Y-191248D01*
X189663Y-190414D01*
X187458Y-189998D01*
X185253Y-190831D01*
X183363Y-192497D01*
X182103Y-194998D01*
X181473Y-198331D01*
X182103Y-201664D01*
X183363Y-204165D01*
X185253Y-205831D01*
X187458Y-206664D01*
X189663Y-206247D01*
X191553Y-204998D01*
X192813Y-203331D01*
G01X51811Y865532D02*
X45511D01*
X50026Y862634D01*
Y866550D01*
G01X51811Y870892D02*
X51706Y871440D01*
X51391Y872067D01*
X50866Y872459D01*
X50131Y872615D01*
X49396Y872459D01*
X48766Y871989D01*
X48451Y871284D01*
Y870500D01*
X48241Y870030D01*
X47716Y869639D01*
X46981Y869482D01*
X46246Y869717D01*
X45721Y870265D01*
X45511Y870892D01*
X45721Y871519D01*
X46246Y872067D01*
X46981Y872302D01*
X47716Y872145D01*
X48241Y871754D01*
X48451Y871284D01*
Y870500D01*
X48766Y869795D01*
X49396Y869325D01*
X50131Y869169D01*
X50866Y869325D01*
X51391Y869717D01*
X51706Y870344D01*
X51811Y870892D01*
G01X49186Y875704D02*
X48451Y876252D01*
X48031Y876722D01*
X47821Y877349D01*
X48031Y877897D01*
X48451Y878289D01*
X49081Y878602D01*
X49816Y878680D01*
X50446Y878602D01*
X51076Y878289D01*
X51601Y877819D01*
X51811Y877270D01*
X51601Y876644D01*
X50971Y876095D01*
X50026Y875782D01*
X48976Y875704D01*
X47611Y875860D01*
X46876Y876095D01*
X46141Y876487D01*
X45616Y877035D01*
X45511Y877584D01*
X45721Y878132D01*
X46246Y878524D01*
G01X52021Y883492D02*
X51916Y883335D01*
X51706D01*
X51601Y883492D01*
X51706Y883649D01*
X51916D01*
X52021Y883492D01*
G01X49186Y888304D02*
X48451Y888852D01*
X48031Y889322D01*
X47821Y889949D01*
X48031Y890497D01*
X48451Y890889D01*
X49081Y891202D01*
X49816Y891280D01*
X50446Y891202D01*
X51076Y890889D01*
X51601Y890419D01*
X51811Y889870D01*
X51601Y889244D01*
X50971Y888695D01*
X50026Y888382D01*
X48976Y888304D01*
X47611Y888460D01*
X46876Y888695D01*
X46141Y889087D01*
X45616Y889635D01*
X45511Y890184D01*
X45721Y890732D01*
X46246Y891124D01*
G01X51811Y896092D02*
X45511D01*
X46771Y895152D01*
G01X51811D02*
Y897032D01*
G01X49432Y1565058D02*
X48632Y1565191D01*
X47932Y1565725D01*
X47332Y1566525D01*
X46932Y1567458D01*
X46732Y1568525D01*
Y1569591D01*
X46932Y1570658D01*
X47332Y1571591D01*
X47932Y1572391D01*
X48632Y1572925D01*
X49432Y1573058D01*
X50232Y1572925D01*
X50932Y1572391D01*
X51532Y1571591D01*
X51932Y1570658D01*
X52132Y1569591D01*
Y1568525D01*
X51932Y1567458D01*
X51532Y1566525D01*
X50932Y1565725D01*
X50232Y1565191D01*
X49432Y1565058D01*
G01X50232Y1567191D02*
X51432Y1565058D01*
G01X55232Y1573058D02*
Y1567325D01*
X55632Y1566124D01*
X56432Y1565325D01*
X57432Y1565058D01*
X58432Y1565325D01*
X59232Y1566124D01*
X59632Y1567325D01*
Y1573058D01*
G01X62932Y1565058D02*
X65432Y1573058D01*
X67932Y1565058D01*
G01X67032Y1567858D02*
X63832D01*
G01X71132Y1565058D02*
Y1573058D01*
X75732Y1565058D01*
Y1573058D01*
G01X81432D02*
Y1565058D01*
G01X79132Y1573058D02*
X83732D01*
G01X86932Y1565058D02*
X89432Y1573058D01*
X91932Y1565058D01*
G01X91032Y1567858D02*
X87832D01*
G01X103432Y1565058D02*
Y1573058D01*
X105832D01*
X106632Y1572658D01*
X107232Y1571725D01*
X107432Y1570658D01*
X107232Y1569591D01*
X106732Y1568791D01*
X105832Y1568391D01*
X103432D01*
G01X111432Y1565058D02*
Y1573058D01*
X113932D01*
X114732Y1572658D01*
X115232Y1572125D01*
X115432Y1571058D01*
X115232Y1569991D01*
X114632Y1569325D01*
X113932Y1568925D01*
X111432D01*
G01X113932D02*
X115432Y1565058D01*
G01X120232Y1573058D02*
X122632D01*
G01X121432D02*
Y1565058D01*
G01X120232D02*
X122632D01*
G01X129432D02*
X128632Y1565191D01*
X127932Y1565725D01*
X127332Y1566525D01*
X126932Y1567458D01*
X126732Y1568525D01*
Y1569591D01*
X126932Y1570658D01*
X127332Y1571591D01*
X127932Y1572391D01*
X128632Y1572925D01*
X129432Y1573058D01*
X130232Y1572925D01*
X130932Y1572391D01*
X131532Y1571591D01*
X131932Y1570658D01*
X132132Y1569591D01*
Y1568525D01*
X131932Y1567458D01*
X131532Y1566525D01*
X130932Y1565725D01*
X130232Y1565191D01*
X129432Y1565058D01*
G01X135432D02*
Y1573058D01*
X137932D01*
X138732Y1572658D01*
X139232Y1572125D01*
X139432Y1571058D01*
X139232Y1569991D01*
X138632Y1569325D01*
X137932Y1568925D01*
X135432D01*
G01X137932D02*
X139432Y1565058D01*
G01X153432Y1573058D02*
Y1565058D01*
G01X151132Y1573058D02*
X155732D01*
G01X161432Y1565058D02*
X160632Y1565191D01*
X159932Y1565725D01*
X159332Y1566525D01*
X158932Y1567458D01*
X158732Y1568525D01*
Y1569591D01*
X158932Y1570658D01*
X159332Y1571591D01*
X159932Y1572391D01*
X160632Y1572925D01*
X161432Y1573058D01*
X162232Y1572925D01*
X162932Y1572391D01*
X163532Y1571591D01*
X163932Y1570658D01*
X164132Y1569591D01*
Y1568525D01*
X163932Y1567458D01*
X163532Y1566525D01*
X162932Y1565725D01*
X162232Y1565191D01*
X161432Y1565058D01*
G01X176232Y1573058D02*
X178632D01*
G01X177432D02*
Y1565058D01*
G01X176232D02*
X178632D01*
G01X185432Y1573058D02*
Y1565058D01*
G01X183132Y1573058D02*
X187732D01*
G01X191332Y1566124D02*
X192132Y1565458D01*
X193032Y1565058D01*
X193832D01*
X194632Y1565458D01*
X195232Y1566124D01*
X195532Y1567058D01*
X195332Y1567991D01*
X194832Y1568791D01*
X193932Y1569325D01*
X192732Y1569591D01*
X192032Y1570125D01*
X191732Y1571058D01*
X191932Y1571991D01*
X192432Y1572658D01*
X193132Y1573058D01*
X193832D01*
X194532Y1572791D01*
X195132Y1572125D01*
G01X208232Y1573058D02*
X210632D01*
G01X209432D02*
Y1565058D01*
G01X208232D02*
X210632D01*
G01X214832D02*
Y1573058D01*
X217432Y1566391D01*
X220032Y1573058D01*
Y1565058D01*
G01X223432D02*
Y1573058D01*
X225832D01*
X226632Y1572658D01*
X227232Y1571725D01*
X227432Y1570658D01*
X227232Y1569591D01*
X226732Y1568791D01*
X225832Y1568391D01*
X223432D01*
G01X231432Y1573058D02*
Y1565058D01*
X235432D01*
G01X243432D02*
X239432D01*
Y1573058D01*
X243432D01*
G01X241832Y1569191D02*
X239432D01*
G01X246832Y1565058D02*
Y1573058D01*
X249432Y1566391D01*
X252032Y1573058D01*
Y1565058D01*
G01X259432D02*
X255432D01*
Y1573058D01*
X259432D01*
G01X257832Y1569191D02*
X255432D01*
G01X263132Y1565058D02*
Y1573058D01*
X267732Y1565058D01*
Y1573058D01*
G01X273432D02*
Y1565058D01*
G01X271132Y1573058D02*
X275732D01*
G01X278932Y1565058D02*
X281432Y1573058D01*
X283932Y1565058D01*
G01X283032Y1567858D02*
X279832D01*
G01X289432Y1573058D02*
Y1565058D01*
G01X287132Y1573058D02*
X291732D01*
G01X296232D02*
X298632D01*
G01X297432D02*
Y1565058D01*
G01X296232D02*
X298632D01*
G01X305432D02*
X304632Y1565191D01*
X303932Y1565725D01*
X303332Y1566525D01*
X302932Y1567458D01*
X302732Y1568525D01*
Y1569591D01*
X302932Y1570658D01*
X303332Y1571591D01*
X303932Y1572391D01*
X304632Y1572925D01*
X305432Y1573058D01*
X306232Y1572925D01*
X306932Y1572391D01*
X307532Y1571591D01*
X307932Y1570658D01*
X308132Y1569591D01*
Y1568525D01*
X307932Y1567458D01*
X307532Y1566525D01*
X306932Y1565725D01*
X306232Y1565191D01*
X305432Y1565058D01*
G01X311132D02*
Y1573058D01*
X315732Y1565058D01*
Y1573058D01*
G01X321432Y1564791D02*
X321232Y1564925D01*
Y1565191D01*
X321432Y1565325D01*
X321632Y1565191D01*
Y1564925D01*
X321432Y1564791D01*
G01X47332Y1581124D02*
X48132Y1580458D01*
X49032Y1580058D01*
X49832D01*
X50632Y1580458D01*
X51232Y1581124D01*
X51532Y1582058D01*
X51332Y1582991D01*
X50832Y1583791D01*
X49932Y1584325D01*
X48732Y1584591D01*
X48032Y1585125D01*
X47732Y1586058D01*
X47932Y1586991D01*
X48432Y1587658D01*
X49132Y1588058D01*
X49832D01*
X50532Y1587791D01*
X51132Y1587125D01*
G01X57432Y1588058D02*
Y1580058D01*
G01X55132Y1588058D02*
X59732D01*
G01X62932Y1580058D02*
X65432Y1588058D01*
X67932Y1580058D01*
G01X67032Y1582858D02*
X63832D01*
G01X75632Y1587391D02*
X75032Y1587791D01*
X74332Y1588058D01*
X73532D01*
X72632Y1587658D01*
X71932Y1586991D01*
X71432Y1586191D01*
X71032Y1584858D01*
X70932Y1583658D01*
X71132Y1582458D01*
X71432Y1581658D01*
X72032Y1580858D01*
X72732Y1580325D01*
X73432Y1580058D01*
X74132D01*
X74832Y1580325D01*
X75432Y1580725D01*
X75932Y1581258D01*
G01X79232Y1580058D02*
Y1588058D01*
G01X83032D02*
X79232Y1583124D01*
G01X83632Y1580058D02*
X80932Y1585391D01*
G01X88232Y1588058D02*
X90632D01*
G01X89432D02*
Y1580058D01*
G01X88232D02*
X90632D01*
G01X95132D02*
Y1588058D01*
X99732Y1580058D01*
Y1588058D01*
G01X106032Y1584058D02*
X108032D01*
Y1581658D01*
X107432Y1580858D01*
X106732Y1580325D01*
X105732Y1580058D01*
X104732Y1580325D01*
X104032Y1580858D01*
X103432Y1581658D01*
X103032Y1582591D01*
X102832Y1583658D01*
Y1584591D01*
X103032Y1585391D01*
X103432Y1586325D01*
X104032Y1587125D01*
X104632Y1587658D01*
X105432Y1588058D01*
X106132D01*
X106932Y1587791D01*
X107532Y1587258D01*
G01X118932Y1580058D02*
X121432Y1588058D01*
X123932Y1580058D01*
G01X123032Y1582858D02*
X119832D01*
G01X127132Y1580058D02*
Y1588058D01*
X131732Y1580058D01*
Y1588058D01*
G01X135232Y1580058D02*
Y1588058D01*
X137232D01*
X138032Y1587658D01*
X138632Y1587125D01*
X139132Y1586325D01*
X139532Y1585391D01*
X139632Y1584058D01*
X139532Y1582725D01*
X139132Y1581791D01*
X138632Y1580991D01*
X138032Y1580458D01*
X137232Y1580058D01*
X135232D01*
G01X153432D02*
X152632Y1580191D01*
X151932Y1580725D01*
X151332Y1581525D01*
X150932Y1582458D01*
X150732Y1583525D01*
Y1584591D01*
X150932Y1585658D01*
X151332Y1586591D01*
X151932Y1587391D01*
X152632Y1587925D01*
X153432Y1588058D01*
X154232Y1587925D01*
X154932Y1587391D01*
X155532Y1586591D01*
X155932Y1585658D01*
X156132Y1584591D01*
Y1583525D01*
X155932Y1582458D01*
X155532Y1581525D01*
X154932Y1580725D01*
X154232Y1580191D01*
X153432Y1580058D01*
G01X161432Y1588058D02*
Y1580058D01*
G01X159132Y1588058D02*
X163732D01*
G01X167332Y1580058D02*
Y1588058D01*
G01X171532D02*
Y1580058D01*
G01Y1584058D02*
X167332D01*
G01X179432Y1580058D02*
X175432D01*
Y1588058D01*
X179432D01*
G01X177832Y1584191D02*
X175432D01*
G01X183432Y1580058D02*
Y1588058D01*
X185932D01*
X186732Y1587658D01*
X187232Y1587125D01*
X187432Y1586058D01*
X187232Y1584991D01*
X186632Y1584325D01*
X185932Y1583925D01*
X183432D01*
G01X185932D02*
X187432Y1580058D01*
G01X199332Y1581124D02*
X200132Y1580458D01*
X201032Y1580058D01*
X201832D01*
X202632Y1580458D01*
X203232Y1581124D01*
X203532Y1582058D01*
X203332Y1582991D01*
X202832Y1583791D01*
X201932Y1584325D01*
X200732Y1584591D01*
X200032Y1585125D01*
X199732Y1586058D01*
X199932Y1586991D01*
X200432Y1587658D01*
X201132Y1588058D01*
X201832D01*
X202532Y1587791D01*
X203132Y1587125D01*
G01X207232Y1588058D02*
Y1582325D01*
X207632Y1581124D01*
X208432Y1580325D01*
X209432Y1580058D01*
X210432Y1580325D01*
X211232Y1581124D01*
X211632Y1582325D01*
Y1588058D01*
G01X218232Y1584325D02*
X218632Y1584725D01*
X218932Y1585391D01*
X219132Y1586325D01*
X218932Y1587125D01*
X218532Y1587658D01*
X217832Y1588058D01*
X215132D01*
Y1580058D01*
X218432D01*
X219132Y1580591D01*
X219532Y1581391D01*
X219732Y1582325D01*
X219532Y1583258D01*
X218932Y1584058D01*
X218232Y1584325D01*
X215132D01*
G01X223332Y1581124D02*
X224132Y1580458D01*
X225032Y1580058D01*
X225832D01*
X226632Y1580458D01*
X227232Y1581124D01*
X227532Y1582058D01*
X227332Y1582991D01*
X226832Y1583791D01*
X225932Y1584325D01*
X224732Y1584591D01*
X224032Y1585125D01*
X223732Y1586058D01*
X223932Y1586991D01*
X224432Y1587658D01*
X225132Y1588058D01*
X225832D01*
X226532Y1587791D01*
X227132Y1587125D01*
G01X235432Y1580058D02*
X231432D01*
Y1588058D01*
X235432D01*
G01X233832Y1584191D02*
X231432D01*
G01X241432Y1580058D02*
X240632Y1580191D01*
X239932Y1580725D01*
X239332Y1581525D01*
X238932Y1582458D01*
X238732Y1583525D01*
Y1584591D01*
X238932Y1585658D01*
X239332Y1586591D01*
X239932Y1587391D01*
X240632Y1587925D01*
X241432Y1588058D01*
X242232Y1587925D01*
X242932Y1587391D01*
X243532Y1586591D01*
X243932Y1585658D01*
X244132Y1584591D01*
Y1583525D01*
X243932Y1582458D01*
X243532Y1581525D01*
X242932Y1580725D01*
X242232Y1580191D01*
X241432Y1580058D01*
G01X242232Y1582191D02*
X243432Y1580058D01*
G01X247232Y1588058D02*
Y1582325D01*
X247632Y1581124D01*
X248432Y1580325D01*
X249432Y1580058D01*
X250432Y1580325D01*
X251232Y1581124D01*
X251632Y1582325D01*
Y1588058D01*
G01X259432Y1580058D02*
X255432D01*
Y1588058D01*
X259432D01*
G01X257832Y1584191D02*
X255432D01*
G01X263132Y1580058D02*
Y1588058D01*
X267732Y1580058D01*
Y1588058D01*
G01X273432D02*
Y1580058D01*
G01X271132Y1588058D02*
X275732D01*
G01X291632Y1587391D02*
X291032Y1587791D01*
X290332Y1588058D01*
X289532D01*
X288632Y1587658D01*
X287932Y1586991D01*
X287432Y1586191D01*
X287032Y1584858D01*
X286932Y1583658D01*
X287132Y1582458D01*
X287432Y1581658D01*
X288032Y1580858D01*
X288732Y1580325D01*
X289432Y1580058D01*
X290132D01*
X290832Y1580325D01*
X291432Y1580725D01*
X291932Y1581258D01*
G01X295332Y1580058D02*
Y1588058D01*
G01X299532D02*
Y1580058D01*
G01Y1584058D02*
X295332D01*
G01X302932Y1580058D02*
X305432Y1588058D01*
X307932Y1580058D01*
G01X307032Y1582858D02*
X303832D01*
G01X311132Y1580058D02*
Y1588058D01*
X315732Y1580058D01*
Y1588058D01*
G01X322032Y1584058D02*
X324032D01*
Y1581658D01*
X323432Y1580858D01*
X322732Y1580325D01*
X321732Y1580058D01*
X320732Y1580325D01*
X320032Y1580858D01*
X319432Y1581658D01*
X319032Y1582591D01*
X318832Y1583658D01*
Y1584591D01*
X319032Y1585391D01*
X319432Y1586325D01*
X320032Y1587125D01*
X320632Y1587658D01*
X321432Y1588058D01*
X322132D01*
X322932Y1587791D01*
X323532Y1587258D01*
G01X331432Y1580058D02*
X327432D01*
Y1588058D01*
X331432D01*
G01X329832Y1584191D02*
X327432D01*
G01X335332Y1581124D02*
X336132Y1580458D01*
X337032Y1580058D01*
X337832D01*
X338632Y1580458D01*
X339232Y1581124D01*
X339532Y1582058D01*
X339332Y1582991D01*
X338832Y1583791D01*
X337932Y1584325D01*
X336732Y1584591D01*
X336032Y1585125D01*
X335732Y1586058D01*
X335932Y1586991D01*
X336432Y1587658D01*
X337132Y1588058D01*
X337832D01*
X338532Y1587791D01*
X339132Y1587125D01*
G01X350832Y1580058D02*
Y1588058D01*
X353432Y1581391D01*
X356032Y1588058D01*
Y1580058D01*
G01X359232Y1588058D02*
Y1582325D01*
X359632Y1581124D01*
X360432Y1580325D01*
X361432Y1580058D01*
X362432Y1580325D01*
X363232Y1581124D01*
X363632Y1582325D01*
Y1588058D01*
G01X367332Y1581124D02*
X368132Y1580458D01*
X369032Y1580058D01*
X369832D01*
X370632Y1580458D01*
X371232Y1581124D01*
X371532Y1582058D01*
X371332Y1582991D01*
X370832Y1583791D01*
X369932Y1584325D01*
X368732Y1584591D01*
X368032Y1585125D01*
X367732Y1586058D01*
X367932Y1586991D01*
X368432Y1587658D01*
X369132Y1588058D01*
X369832D01*
X370532Y1587791D01*
X371132Y1587125D01*
G01X377432Y1588058D02*
Y1580058D01*
G01X375132Y1588058D02*
X379732D01*
G01X394232Y1584325D02*
X394632Y1584725D01*
X394932Y1585391D01*
X395132Y1586325D01*
X394932Y1587125D01*
X394532Y1587658D01*
X393832Y1588058D01*
X391132D01*
Y1580058D01*
X394432D01*
X395132Y1580591D01*
X395532Y1581391D01*
X395732Y1582325D01*
X395532Y1583258D01*
X394932Y1584058D01*
X394232Y1584325D01*
X391132D01*
G01X403432Y1580058D02*
X399432D01*
Y1588058D01*
X403432D01*
G01X401832Y1584191D02*
X399432D01*
G01X414932Y1580058D02*
X417432Y1588058D01*
X419932Y1580058D01*
G01X419032Y1582858D02*
X415832D01*
G01X423432Y1580058D02*
Y1588058D01*
X425832D01*
X426632Y1587658D01*
X427232Y1586725D01*
X427432Y1585658D01*
X427232Y1584591D01*
X426732Y1583791D01*
X425832Y1583391D01*
X423432D01*
G01X431432Y1580058D02*
Y1588058D01*
X433832D01*
X434632Y1587658D01*
X435232Y1586725D01*
X435432Y1585658D01*
X435232Y1584591D01*
X434732Y1583791D01*
X433832Y1583391D01*
X431432D01*
G01X439432Y1580058D02*
Y1588058D01*
X441932D01*
X442732Y1587658D01*
X443232Y1587125D01*
X443432Y1586058D01*
X443232Y1584991D01*
X442632Y1584325D01*
X441932Y1583925D01*
X439432D01*
G01X441932D02*
X443432Y1580058D01*
G01X449432D02*
X448632Y1580191D01*
X447932Y1580725D01*
X447332Y1581525D01*
X446932Y1582458D01*
X446732Y1583525D01*
Y1584591D01*
X446932Y1585658D01*
X447332Y1586591D01*
X447932Y1587391D01*
X448632Y1587925D01*
X449432Y1588058D01*
X450232Y1587925D01*
X450932Y1587391D01*
X451532Y1586591D01*
X451932Y1585658D01*
X452132Y1584591D01*
Y1583525D01*
X451932Y1582458D01*
X451532Y1581525D01*
X450932Y1580725D01*
X450232Y1580191D01*
X449432Y1580058D01*
G01X454932Y1588058D02*
X457432Y1580058D01*
X459932Y1588058D01*
G01X467432Y1580058D02*
X463432D01*
Y1588058D01*
X467432D01*
G01X465832Y1584191D02*
X463432D01*
G01X471232Y1580058D02*
Y1588058D01*
X473232D01*
X474032Y1587658D01*
X474632Y1587125D01*
X475132Y1586325D01*
X475532Y1585391D01*
X475632Y1584058D01*
X475532Y1582725D01*
X475132Y1581791D01*
X474632Y1580991D01*
X474032Y1580458D01*
X473232Y1580058D01*
X471232D01*
G01X490232Y1584325D02*
X490632Y1584725D01*
X490932Y1585391D01*
X491132Y1586325D01*
X490932Y1587125D01*
X490532Y1587658D01*
X489832Y1588058D01*
X487132D01*
Y1580058D01*
X490432D01*
X491132Y1580591D01*
X491532Y1581391D01*
X491732Y1582325D01*
X491532Y1583258D01*
X490932Y1584058D01*
X490232Y1584325D01*
X487132D01*
G01X497432Y1580058D02*
Y1583658D01*
X495432Y1588058D01*
G01X499432D02*
X497432Y1583658D01*
G01X48232Y1603058D02*
X50632D01*
G01X49432D02*
Y1595058D01*
G01X48232D02*
X50632D01*
G01X54832D02*
Y1603058D01*
X57432Y1596391D01*
X60032Y1603058D01*
Y1595058D01*
G01X63432D02*
Y1603058D01*
X65832D01*
X66632Y1602658D01*
X67232Y1601725D01*
X67432Y1600658D01*
X67232Y1599591D01*
X66732Y1598791D01*
X65832Y1598391D01*
X63432D01*
G01X75432Y1595058D02*
X71432D01*
Y1603058D01*
X75432D01*
G01X73832Y1599191D02*
X71432D01*
G01X79232Y1595058D02*
Y1603058D01*
X81232D01*
X82032Y1602658D01*
X82632Y1602125D01*
X83132Y1601325D01*
X83532Y1600391D01*
X83632Y1599058D01*
X83532Y1597725D01*
X83132Y1596791D01*
X82632Y1595991D01*
X82032Y1595458D01*
X81232Y1595058D01*
X79232D01*
G01X86932D02*
X89432Y1603058D01*
X91932Y1595058D01*
G01X91032Y1597858D02*
X87832D01*
G01X95132Y1595058D02*
Y1603058D01*
X99732Y1595058D01*
Y1603058D01*
G01X107632Y1602391D02*
X107032Y1602791D01*
X106332Y1603058D01*
X105532D01*
X104632Y1602658D01*
X103932Y1601991D01*
X103432Y1601191D01*
X103032Y1599858D01*
X102932Y1598658D01*
X103132Y1597458D01*
X103432Y1596658D01*
X104032Y1595858D01*
X104732Y1595325D01*
X105432Y1595058D01*
X106132D01*
X106832Y1595325D01*
X107432Y1595725D01*
X107932Y1596258D01*
G01X115432Y1595058D02*
X111432D01*
Y1603058D01*
X115432D01*
G01X113832Y1599191D02*
X111432D01*
G01X119332Y1596124D02*
X120132Y1595458D01*
X121032Y1595058D01*
X121832D01*
X122632Y1595458D01*
X123232Y1596124D01*
X123532Y1597058D01*
X123332Y1597991D01*
X122832Y1598791D01*
X121932Y1599325D01*
X120732Y1599591D01*
X120032Y1600125D01*
X119732Y1601058D01*
X119932Y1601991D01*
X120432Y1602658D01*
X121132Y1603058D01*
X121832D01*
X122532Y1602791D01*
X123132Y1602125D01*
G01X134932Y1595058D02*
X137432Y1603058D01*
X139932Y1595058D01*
G01X139032Y1597858D02*
X135832D01*
G01X143132Y1595058D02*
Y1603058D01*
X147732Y1595058D01*
Y1603058D01*
G01X151232Y1595058D02*
Y1603058D01*
X153232D01*
X154032Y1602658D01*
X154632Y1602125D01*
X155132Y1601325D01*
X155532Y1600391D01*
X155632Y1599058D01*
X155532Y1597725D01*
X155132Y1596791D01*
X154632Y1595991D01*
X154032Y1595458D01*
X153232Y1595058D01*
X151232D01*
G01X170232Y1599325D02*
X170632Y1599725D01*
X170932Y1600391D01*
X171132Y1601325D01*
X170932Y1602125D01*
X170532Y1602658D01*
X169832Y1603058D01*
X167132D01*
Y1595058D01*
X170432D01*
X171132Y1595591D01*
X171532Y1596391D01*
X171732Y1597325D01*
X171532Y1598258D01*
X170932Y1599058D01*
X170232Y1599325D01*
X167132D01*
G01X177432Y1595058D02*
X176632Y1595191D01*
X175932Y1595725D01*
X175332Y1596525D01*
X174932Y1597458D01*
X174732Y1598525D01*
Y1599591D01*
X174932Y1600658D01*
X175332Y1601591D01*
X175932Y1602391D01*
X176632Y1602925D01*
X177432Y1603058D01*
X178232Y1602925D01*
X178932Y1602391D01*
X179532Y1601591D01*
X179932Y1600658D01*
X180132Y1599591D01*
Y1598525D01*
X179932Y1597458D01*
X179532Y1596525D01*
X178932Y1595725D01*
X178232Y1595191D01*
X177432Y1595058D01*
G01X182932D02*
X185432Y1603058D01*
X187932Y1595058D01*
G01X187032Y1597858D02*
X183832D01*
G01X191432Y1595058D02*
Y1603058D01*
X193932D01*
X194732Y1602658D01*
X195232Y1602125D01*
X195432Y1601058D01*
X195232Y1599991D01*
X194632Y1599325D01*
X193932Y1598925D01*
X191432D01*
G01X193932D02*
X195432Y1595058D01*
G01X199232D02*
Y1603058D01*
X201232D01*
X202032Y1602658D01*
X202632Y1602125D01*
X203132Y1601325D01*
X203532Y1600391D01*
X203632Y1599058D01*
X203532Y1597725D01*
X203132Y1596791D01*
X202632Y1595991D01*
X202032Y1595458D01*
X201232Y1595058D01*
X199232D01*
G01X217432Y1603058D02*
Y1595058D01*
G01X215132Y1603058D02*
X219732D01*
G01X223332Y1595058D02*
Y1603058D01*
G01X227532D02*
Y1595058D01*
G01Y1599058D02*
X223332D01*
G01X232232Y1603058D02*
X234632D01*
G01X233432D02*
Y1595058D01*
G01X232232D02*
X234632D01*
G01X243632Y1602391D02*
X243032Y1602791D01*
X242332Y1603058D01*
X241532D01*
X240632Y1602658D01*
X239932Y1601991D01*
X239432Y1601191D01*
X239032Y1599858D01*
X238932Y1598658D01*
X239132Y1597458D01*
X239432Y1596658D01*
X240032Y1595858D01*
X240732Y1595325D01*
X241432Y1595058D01*
X242132D01*
X242832Y1595325D01*
X243432Y1595725D01*
X243932Y1596258D01*
G01X247232Y1595058D02*
Y1603058D01*
G01X251032D02*
X247232Y1598124D01*
G01X251632Y1595058D02*
X248932Y1600391D01*
G01X255132Y1595058D02*
Y1603058D01*
X259732Y1595058D01*
Y1603058D01*
G01X267432Y1595058D02*
X263432D01*
Y1603058D01*
X267432D01*
G01X265832Y1599191D02*
X263432D01*
G01X271332Y1596124D02*
X272132Y1595458D01*
X273032Y1595058D01*
X273832D01*
X274632Y1595458D01*
X275232Y1596124D01*
X275532Y1597058D01*
X275332Y1597991D01*
X274832Y1598791D01*
X273932Y1599325D01*
X272732Y1599591D01*
X272032Y1600125D01*
X271732Y1601058D01*
X271932Y1601991D01*
X272432Y1602658D01*
X273132Y1603058D01*
X273832D01*
X274532Y1602791D01*
X275132Y1602125D01*
G01X279332Y1596124D02*
X280132Y1595458D01*
X281032Y1595058D01*
X281832D01*
X282632Y1595458D01*
X283232Y1596124D01*
X283532Y1597058D01*
X283332Y1597991D01*
X282832Y1598791D01*
X281932Y1599325D01*
X280732Y1599591D01*
X280032Y1600125D01*
X279732Y1601058D01*
X279932Y1601991D01*
X280432Y1602658D01*
X281132Y1603058D01*
X281832D01*
X282532Y1602791D01*
X283132Y1602125D01*
G01X289432Y1594791D02*
X289232Y1594925D01*
Y1595191D01*
X289432Y1595325D01*
X289632Y1595191D01*
Y1594925D01*
X289432Y1594791D01*
G01X312232Y1603058D02*
X314632D01*
G01X313432D02*
Y1595058D01*
G01X312232D02*
X314632D01*
G01X319132D02*
Y1603058D01*
X323732Y1595058D01*
Y1603058D01*
G01X328232D02*
X330632D01*
G01X329432D02*
Y1595058D01*
G01X328232D02*
X330632D01*
G01X337432Y1603058D02*
Y1595058D01*
G01X335132Y1603058D02*
X339732D01*
G01X344232D02*
X346632D01*
G01X345432D02*
Y1595058D01*
G01X344232D02*
X346632D01*
G01X350932D02*
X353432Y1603058D01*
X355932Y1595058D01*
G01X355032Y1597858D02*
X351832D01*
G01X359432Y1603058D02*
Y1595058D01*
X363432D01*
G01X375232D02*
Y1603058D01*
X377232D01*
X378032Y1602658D01*
X378632Y1602125D01*
X379132Y1601325D01*
X379532Y1600391D01*
X379632Y1599058D01*
X379532Y1597725D01*
X379132Y1596791D01*
X378632Y1595991D01*
X378032Y1595458D01*
X377232Y1595058D01*
X375232D01*
G01X387432D02*
X383432D01*
Y1603058D01*
X387432D01*
G01X385832Y1599191D02*
X383432D01*
G01X393432Y1603058D02*
Y1595058D01*
G01X391132Y1603058D02*
X395732D01*
G01X398932Y1595058D02*
X401432Y1603058D01*
X403932Y1595058D01*
G01X403032Y1597858D02*
X399832D01*
G01X408232Y1603058D02*
X410632D01*
G01X409432D02*
Y1595058D01*
G01X408232D02*
X410632D01*
G01X415432Y1603058D02*
Y1595058D01*
X419432D01*
G01X431432Y1603058D02*
Y1595058D01*
X435432D01*
G01X438932D02*
X441432Y1603058D01*
X443932Y1595058D01*
G01X443032Y1597858D02*
X439832D01*
G01X449432Y1595058D02*
Y1598658D01*
X447432Y1603058D01*
G01X451432D02*
X449432Y1598658D01*
G01X459432Y1595058D02*
X455432D01*
Y1603058D01*
X459432D01*
G01X457832Y1599191D02*
X455432D01*
G01X463432Y1595058D02*
Y1603058D01*
X465932D01*
X466732Y1602658D01*
X467232Y1602125D01*
X467432Y1601058D01*
X467232Y1599991D01*
X466632Y1599325D01*
X465932Y1598925D01*
X463432D01*
G01X465932D02*
X467432Y1595058D01*
G01X47332Y1611124D02*
X48132Y1610458D01*
X49032Y1610058D01*
X49832D01*
X50632Y1610458D01*
X51232Y1611124D01*
X51532Y1612058D01*
X51332Y1612991D01*
X50832Y1613791D01*
X49932Y1614325D01*
X48732Y1614591D01*
X48032Y1615125D01*
X47732Y1616058D01*
X47932Y1616991D01*
X48432Y1617658D01*
X49132Y1618058D01*
X49832D01*
X50532Y1617791D01*
X51132Y1617125D01*
G01X55432Y1610058D02*
Y1618058D01*
X57832D01*
X58632Y1617658D01*
X59232Y1616725D01*
X59432Y1615658D01*
X59232Y1614591D01*
X58732Y1613791D01*
X57832Y1613391D01*
X55432D01*
G01X62932Y1610058D02*
X65432Y1618058D01*
X67932Y1610058D01*
G01X67032Y1612858D02*
X63832D01*
G01X75632Y1617391D02*
X75032Y1617791D01*
X74332Y1618058D01*
X73532D01*
X72632Y1617658D01*
X71932Y1616991D01*
X71432Y1616191D01*
X71032Y1614858D01*
X70932Y1613658D01*
X71132Y1612458D01*
X71432Y1611658D01*
X72032Y1610858D01*
X72732Y1610325D01*
X73432Y1610058D01*
X74132D01*
X74832Y1610325D01*
X75432Y1610725D01*
X75932Y1611258D01*
G01X80232Y1618058D02*
X82632D01*
G01X81432D02*
Y1610058D01*
G01X80232D02*
X82632D01*
G01X87132D02*
Y1618058D01*
X91732Y1610058D01*
Y1618058D01*
G01X98032Y1614058D02*
X100032D01*
Y1611658D01*
X99432Y1610858D01*
X98732Y1610325D01*
X97732Y1610058D01*
X96732Y1610325D01*
X96032Y1610858D01*
X95432Y1611658D01*
X95032Y1612591D01*
X94832Y1613658D01*
Y1614591D01*
X95032Y1615391D01*
X95432Y1616325D01*
X96032Y1617125D01*
X96632Y1617658D01*
X97432Y1618058D01*
X98132D01*
X98932Y1617791D01*
X99532Y1617258D01*
G01X110932Y1610058D02*
X113432Y1618058D01*
X115932Y1610058D01*
G01X115032Y1612858D02*
X111832D01*
G01X119132Y1610058D02*
Y1618058D01*
X123732Y1610058D01*
Y1618058D01*
G01X127232Y1610058D02*
Y1618058D01*
X129232D01*
X130032Y1617658D01*
X130632Y1617125D01*
X131132Y1616325D01*
X131532Y1615391D01*
X131632Y1614058D01*
X131532Y1612725D01*
X131132Y1611791D01*
X130632Y1610991D01*
X130032Y1610458D01*
X129232Y1610058D01*
X127232D01*
G01X142832D02*
Y1618058D01*
X145432Y1611391D01*
X148032Y1618058D01*
Y1610058D01*
G01X150932D02*
X153432Y1618058D01*
X155932Y1610058D01*
G01X155032Y1612858D02*
X151832D01*
G01X161432Y1618058D02*
Y1610058D01*
G01X159132Y1618058D02*
X163732D01*
G01X171432Y1610058D02*
X167432D01*
Y1618058D01*
X171432D01*
G01X169832Y1614191D02*
X167432D01*
G01X175432Y1610058D02*
Y1618058D01*
X177932D01*
X178732Y1617658D01*
X179232Y1617125D01*
X179432Y1616058D01*
X179232Y1614991D01*
X178632Y1614325D01*
X177932Y1613925D01*
X175432D01*
G01X177932D02*
X179432Y1610058D01*
G01X184232Y1618058D02*
X186632D01*
G01X185432D02*
Y1610058D01*
G01X184232D02*
X186632D01*
G01X190932D02*
X193432Y1618058D01*
X195932Y1610058D01*
G01X195032Y1612858D02*
X191832D01*
G01X199432Y1618058D02*
Y1610058D01*
X203432D01*
G01X215232D02*
Y1618058D01*
X217232D01*
X218032Y1617658D01*
X218632Y1617125D01*
X219132Y1616325D01*
X219532Y1615391D01*
X219632Y1614058D01*
X219532Y1612725D01*
X219132Y1611791D01*
X218632Y1610991D01*
X218032Y1610458D01*
X217232Y1610058D01*
X215232D01*
G01X224232Y1618058D02*
X226632D01*
G01X225432D02*
Y1610058D01*
G01X224232D02*
X226632D01*
G01X235432D02*
X231432D01*
Y1618058D01*
X235432D01*
G01X233832Y1614191D02*
X231432D01*
G01X239432Y1618058D02*
Y1610058D01*
X243432D01*
G01X251432D02*
X247432D01*
Y1618058D01*
X251432D01*
G01X249832Y1614191D02*
X247432D01*
G01X259632Y1617391D02*
X259032Y1617791D01*
X258332Y1618058D01*
X257532D01*
X256632Y1617658D01*
X255932Y1616991D01*
X255432Y1616191D01*
X255032Y1614858D01*
X254932Y1613658D01*
X255132Y1612458D01*
X255432Y1611658D01*
X256032Y1610858D01*
X256732Y1610325D01*
X257432Y1610058D01*
X258132D01*
X258832Y1610325D01*
X259432Y1610725D01*
X259932Y1611258D01*
G01X265432Y1618058D02*
Y1610058D01*
G01X263132Y1618058D02*
X267732D01*
G01X271432Y1610058D02*
Y1618058D01*
X273932D01*
X274732Y1617658D01*
X275232Y1617125D01*
X275432Y1616058D01*
X275232Y1614991D01*
X274632Y1614325D01*
X273932Y1613925D01*
X271432D01*
G01X273932D02*
X275432Y1610058D01*
G01X280232Y1618058D02*
X282632D01*
G01X281432D02*
Y1610058D01*
G01X280232D02*
X282632D01*
G01X291632Y1617391D02*
X291032Y1617791D01*
X290332Y1618058D01*
X289532D01*
X288632Y1617658D01*
X287932Y1616991D01*
X287432Y1616191D01*
X287032Y1614858D01*
X286932Y1613658D01*
X287132Y1612458D01*
X287432Y1611658D01*
X288032Y1610858D01*
X288732Y1610325D01*
X289432Y1610058D01*
X290132D01*
X290832Y1610325D01*
X291432Y1610725D01*
X291932Y1611258D01*
G01X307632Y1617391D02*
X307032Y1617791D01*
X306332Y1618058D01*
X305532D01*
X304632Y1617658D01*
X303932Y1616991D01*
X303432Y1616191D01*
X303032Y1614858D01*
X302932Y1613658D01*
X303132Y1612458D01*
X303432Y1611658D01*
X304032Y1610858D01*
X304732Y1610325D01*
X305432Y1610058D01*
X306132D01*
X306832Y1610325D01*
X307432Y1610725D01*
X307932Y1611258D01*
G01X313432Y1610058D02*
X312632Y1610191D01*
X311932Y1610725D01*
X311332Y1611525D01*
X310932Y1612458D01*
X310732Y1613525D01*
Y1614591D01*
X310932Y1615658D01*
X311332Y1616591D01*
X311932Y1617391D01*
X312632Y1617925D01*
X313432Y1618058D01*
X314232Y1617925D01*
X314932Y1617391D01*
X315532Y1616591D01*
X315932Y1615658D01*
X316132Y1614591D01*
Y1613525D01*
X315932Y1612458D01*
X315532Y1611525D01*
X314932Y1610725D01*
X314232Y1610191D01*
X313432Y1610058D01*
G01X319132D02*
Y1618058D01*
X323732Y1610058D01*
Y1618058D01*
G01X327332Y1611124D02*
X328132Y1610458D01*
X329032Y1610058D01*
X329832D01*
X330632Y1610458D01*
X331232Y1611124D01*
X331532Y1612058D01*
X331332Y1612991D01*
X330832Y1613791D01*
X329932Y1614325D01*
X328732Y1614591D01*
X328032Y1615125D01*
X327732Y1616058D01*
X327932Y1616991D01*
X328432Y1617658D01*
X329132Y1618058D01*
X329832D01*
X330532Y1617791D01*
X331132Y1617125D01*
G01X337432Y1618058D02*
Y1610058D01*
G01X335132Y1618058D02*
X339732D01*
G01X342932Y1610058D02*
X345432Y1618058D01*
X347932Y1610058D01*
G01X347032Y1612858D02*
X343832D01*
G01X351132Y1610058D02*
Y1618058D01*
X355732Y1610058D01*
Y1618058D01*
G01X361432D02*
Y1610058D01*
G01X359132Y1618058D02*
X363732D01*
G01X377432D02*
Y1610058D01*
G01X375132Y1618058D02*
X379732D01*
G01X385432Y1610058D02*
X384632Y1610191D01*
X383932Y1610725D01*
X383332Y1611525D01*
X382932Y1612458D01*
X382732Y1613525D01*
Y1614591D01*
X382932Y1615658D01*
X383332Y1616591D01*
X383932Y1617391D01*
X384632Y1617925D01*
X385432Y1618058D01*
X386232Y1617925D01*
X386932Y1617391D01*
X387532Y1616591D01*
X387932Y1615658D01*
X388132Y1614591D01*
Y1613525D01*
X387932Y1612458D01*
X387532Y1611525D01*
X386932Y1610725D01*
X386232Y1610191D01*
X385432Y1610058D01*
G01X398932D02*
X401432Y1618058D01*
X403932Y1610058D01*
G01X403032Y1612858D02*
X399832D01*
G01X411632Y1617391D02*
X411032Y1617791D01*
X410332Y1618058D01*
X409532D01*
X408632Y1617658D01*
X407932Y1616991D01*
X407432Y1616191D01*
X407032Y1614858D01*
X406932Y1613658D01*
X407132Y1612458D01*
X407432Y1611658D01*
X408032Y1610858D01*
X408732Y1610325D01*
X409432Y1610058D01*
X410132D01*
X410832Y1610325D01*
X411432Y1610725D01*
X411932Y1611258D01*
G01X415332Y1610058D02*
Y1618058D01*
G01X419532D02*
Y1610058D01*
G01Y1614058D02*
X415332D01*
G01X424232Y1618058D02*
X426632D01*
G01X425432D02*
Y1610058D01*
G01X424232D02*
X426632D01*
G01X435432D02*
X431432D01*
Y1618058D01*
X435432D01*
G01X433832Y1614191D02*
X431432D01*
G01X438932Y1618058D02*
X441432Y1610058D01*
X443932Y1618058D01*
G01X451432Y1610058D02*
X447432D01*
Y1618058D01*
X451432D01*
G01X449832Y1614191D02*
X447432D01*
G01X463432Y1610058D02*
Y1618058D01*
X465932D01*
X466732Y1617658D01*
X467232Y1617125D01*
X467432Y1616058D01*
X467232Y1614991D01*
X466632Y1614325D01*
X465932Y1613925D01*
X463432D01*
G01X465932D02*
X467432Y1610058D01*
G01X475432D02*
X471432D01*
Y1618058D01*
X475432D01*
G01X473832Y1614191D02*
X471432D01*
G01X481432Y1610058D02*
X480632Y1610191D01*
X479932Y1610725D01*
X479332Y1611525D01*
X478932Y1612458D01*
X478732Y1613525D01*
Y1614591D01*
X478932Y1615658D01*
X479332Y1616591D01*
X479932Y1617391D01*
X480632Y1617925D01*
X481432Y1618058D01*
X482232Y1617925D01*
X482932Y1617391D01*
X483532Y1616591D01*
X483932Y1615658D01*
X484132Y1614591D01*
Y1613525D01*
X483932Y1612458D01*
X483532Y1611525D01*
X482932Y1610725D01*
X482232Y1610191D01*
X481432Y1610058D01*
G01X482232Y1612191D02*
X483432Y1610058D01*
G01X487232Y1618058D02*
Y1612325D01*
X487632Y1611124D01*
X488432Y1610325D01*
X489432Y1610058D01*
X490432Y1610325D01*
X491232Y1611124D01*
X491632Y1612325D01*
Y1618058D01*
G01X496232D02*
X498632D01*
G01X497432D02*
Y1610058D01*
G01X496232D02*
X498632D01*
G01X503432D02*
Y1618058D01*
X505932D01*
X506732Y1617658D01*
X507232Y1617125D01*
X507432Y1616058D01*
X507232Y1614991D01*
X506632Y1614325D01*
X505932Y1613925D01*
X503432D01*
G01X505932D02*
X507432Y1610058D01*
G01X515432D02*
X511432D01*
Y1618058D01*
X515432D01*
G01X513832Y1614191D02*
X511432D01*
G01X519232Y1610058D02*
Y1618058D01*
X521232D01*
X522032Y1617658D01*
X522632Y1617125D01*
X523132Y1616325D01*
X523532Y1615391D01*
X523632Y1614058D01*
X523532Y1612725D01*
X523132Y1611791D01*
X522632Y1610991D01*
X522032Y1610458D01*
X521232Y1610058D01*
X519232D01*
G01X51632Y1632391D02*
X51032Y1632791D01*
X50332Y1633058D01*
X49532D01*
X48632Y1632658D01*
X47932Y1631991D01*
X47432Y1631191D01*
X47032Y1629858D01*
X46932Y1628658D01*
X47132Y1627458D01*
X47432Y1626658D01*
X48032Y1625858D01*
X48732Y1625325D01*
X49432Y1625058D01*
X50132D01*
X50832Y1625325D01*
X51432Y1625725D01*
X51932Y1626258D01*
G01X55332Y1625058D02*
Y1633058D01*
G01X59532D02*
Y1625058D01*
G01Y1629058D02*
X55332D01*
G01X62932Y1625058D02*
X65432Y1633058D01*
X67932Y1625058D01*
G01X67032Y1627858D02*
X63832D01*
G01X71432Y1625058D02*
Y1633058D01*
X73932D01*
X74732Y1632658D01*
X75232Y1632125D01*
X75432Y1631058D01*
X75232Y1629991D01*
X74632Y1629325D01*
X73932Y1628925D01*
X71432D01*
G01X73932D02*
X75432Y1625058D01*
G01X81432Y1633058D02*
Y1625058D01*
G01X79132Y1633058D02*
X83732D01*
G01X89432Y1624791D02*
X89232Y1624925D01*
Y1625191D01*
X89432Y1625325D01*
X89632Y1625191D01*
Y1624925D01*
X89432Y1624791D01*
G01X102832Y1625058D02*
Y1633058D01*
X105432Y1626391D01*
X108032Y1633058D01*
Y1625058D01*
G01X110932D02*
X113432Y1633058D01*
X115932Y1625058D01*
G01X115032Y1627858D02*
X111832D01*
G01X119132Y1625058D02*
Y1633058D01*
X123732Y1625058D01*
Y1633058D01*
G01X127232D02*
Y1627325D01*
X127632Y1626124D01*
X128432Y1625325D01*
X129432Y1625058D01*
X130432Y1625325D01*
X131232Y1626124D01*
X131632Y1627325D01*
Y1633058D01*
G01X135532Y1625058D02*
Y1633058D01*
X139332D01*
G01X137932Y1629191D02*
X135532D01*
G01X142932Y1625058D02*
X145432Y1633058D01*
X147932Y1625058D01*
G01X147032Y1627858D02*
X143832D01*
G01X155632Y1632391D02*
X155032Y1632791D01*
X154332Y1633058D01*
X153532D01*
X152632Y1632658D01*
X151932Y1631991D01*
X151432Y1631191D01*
X151032Y1629858D01*
X150932Y1628658D01*
X151132Y1627458D01*
X151432Y1626658D01*
X152032Y1625858D01*
X152732Y1625325D01*
X153432Y1625058D01*
X154132D01*
X154832Y1625325D01*
X155432Y1625725D01*
X155932Y1626258D01*
G01X161432Y1633058D02*
Y1625058D01*
G01X159132Y1633058D02*
X163732D01*
G01X167232D02*
Y1627325D01*
X167632Y1626124D01*
X168432Y1625325D01*
X169432Y1625058D01*
X170432Y1625325D01*
X171232Y1626124D01*
X171632Y1627325D01*
Y1633058D01*
G01X175432Y1625058D02*
Y1633058D01*
X177932D01*
X178732Y1632658D01*
X179232Y1632125D01*
X179432Y1631058D01*
X179232Y1629991D01*
X178632Y1629325D01*
X177932Y1628925D01*
X175432D01*
G01X177932D02*
X179432Y1625058D01*
G01X187432D02*
X183432D01*
Y1633058D01*
X187432D01*
G01X185832Y1629191D02*
X183432D01*
G01X191432Y1625058D02*
Y1633058D01*
X193932D01*
X194732Y1632658D01*
X195232Y1632125D01*
X195432Y1631058D01*
X195232Y1629991D01*
X194632Y1629325D01*
X193932Y1628925D01*
X191432D01*
G01X193932D02*
X195432Y1625058D01*
G01X208232Y1633058D02*
X210632D01*
G01X209432D02*
Y1625058D01*
G01X208232D02*
X210632D01*
G01X215332Y1626124D02*
X216132Y1625458D01*
X217032Y1625058D01*
X217832D01*
X218632Y1625458D01*
X219232Y1626124D01*
X219532Y1627058D01*
X219332Y1627991D01*
X218832Y1628791D01*
X217932Y1629325D01*
X216732Y1629591D01*
X216032Y1630125D01*
X215732Y1631058D01*
X215932Y1631991D01*
X216432Y1632658D01*
X217132Y1633058D01*
X217832D01*
X218532Y1632791D01*
X219132Y1632125D01*
G01X231532Y1625058D02*
Y1633058D01*
X235332D01*
G01X233932Y1629191D02*
X231532D01*
G01X239432Y1625058D02*
Y1633058D01*
X241932D01*
X242732Y1632658D01*
X243232Y1632125D01*
X243432Y1631058D01*
X243232Y1629991D01*
X242632Y1629325D01*
X241932Y1628925D01*
X239432D01*
G01X241932D02*
X243432Y1625058D01*
G01X251432D02*
X247432D01*
Y1633058D01*
X251432D01*
G01X249832Y1629191D02*
X247432D01*
G01X259432Y1625058D02*
X255432D01*
Y1633058D01*
X259432D01*
G01X257832Y1629191D02*
X255432D01*
G01X273432Y1633058D02*
Y1625058D01*
G01X271132Y1633058D02*
X275732D01*
G01X281432Y1625058D02*
X280632Y1625191D01*
X279932Y1625725D01*
X279332Y1626525D01*
X278932Y1627458D01*
X278732Y1628525D01*
Y1629591D01*
X278932Y1630658D01*
X279332Y1631591D01*
X279932Y1632391D01*
X280632Y1632925D01*
X281432Y1633058D01*
X282232Y1632925D01*
X282932Y1632391D01*
X283532Y1631591D01*
X283932Y1630658D01*
X284132Y1629591D01*
Y1628525D01*
X283932Y1627458D01*
X283532Y1626525D01*
X282932Y1625725D01*
X282232Y1625191D01*
X281432Y1625058D01*
G01X294932D02*
X297432Y1633058D01*
X299932Y1625058D01*
G01X299032Y1627858D02*
X295832D01*
G01X303232Y1625058D02*
Y1633058D01*
X305232D01*
X306032Y1632658D01*
X306632Y1632125D01*
X307132Y1631325D01*
X307532Y1630391D01*
X307632Y1629058D01*
X307532Y1627725D01*
X307132Y1626791D01*
X306632Y1625991D01*
X306032Y1625458D01*
X305232Y1625058D01*
X303232D01*
G01X311432Y1626658D02*
X311932Y1625858D01*
X312532Y1625325D01*
X313232Y1625058D01*
X314032Y1625325D01*
X314632Y1625858D01*
X315232Y1626658D01*
X315432Y1627725D01*
Y1633058D01*
G01X319232D02*
Y1627325D01*
X319632Y1626124D01*
X320432Y1625325D01*
X321432Y1625058D01*
X322432Y1625325D01*
X323232Y1626124D01*
X323632Y1627325D01*
Y1633058D01*
G01X327332Y1626124D02*
X328132Y1625458D01*
X329032Y1625058D01*
X329832D01*
X330632Y1625458D01*
X331232Y1626124D01*
X331532Y1627058D01*
X331332Y1627991D01*
X330832Y1628791D01*
X329932Y1629325D01*
X328732Y1629591D01*
X328032Y1630125D01*
X327732Y1631058D01*
X327932Y1631991D01*
X328432Y1632658D01*
X329132Y1633058D01*
X329832D01*
X330532Y1632791D01*
X331132Y1632125D01*
G01X337432Y1633058D02*
Y1625058D01*
G01X335132Y1633058D02*
X339732D01*
G01X353432D02*
Y1625058D01*
G01X351132Y1633058D02*
X355732D01*
G01X359432Y1625058D02*
Y1633058D01*
X361932D01*
X362732Y1632658D01*
X363232Y1632125D01*
X363432Y1631058D01*
X363232Y1629991D01*
X362632Y1629325D01*
X361932Y1628925D01*
X359432D01*
G01X361932D02*
X363432Y1625058D01*
G01X366932D02*
X369432Y1633058D01*
X371932Y1625058D01*
G01X371032Y1627858D02*
X367832D01*
G01X379632Y1632391D02*
X379032Y1632791D01*
X378332Y1633058D01*
X377532D01*
X376632Y1632658D01*
X375932Y1631991D01*
X375432Y1631191D01*
X375032Y1629858D01*
X374932Y1628658D01*
X375132Y1627458D01*
X375432Y1626658D01*
X376032Y1625858D01*
X376732Y1625325D01*
X377432Y1625058D01*
X378132D01*
X378832Y1625325D01*
X379432Y1625725D01*
X379932Y1626258D01*
G01X387432Y1625058D02*
X383432D01*
Y1633058D01*
X387432D01*
G01X385832Y1629191D02*
X383432D01*
G01X398432Y1633058D02*
X399832Y1625058D01*
X401432Y1633058D01*
X403032Y1625058D01*
X404432Y1633058D01*
G01X408232D02*
X410632D01*
G01X409432D02*
Y1625058D01*
G01X408232D02*
X410632D01*
G01X415232D02*
Y1633058D01*
X417232D01*
X418032Y1632658D01*
X418632Y1632125D01*
X419132Y1631325D01*
X419532Y1630391D01*
X419632Y1629058D01*
X419532Y1627725D01*
X419132Y1626791D01*
X418632Y1625991D01*
X418032Y1625458D01*
X417232Y1625058D01*
X415232D01*
G01X425432Y1633058D02*
Y1625058D01*
G01X423132Y1633058D02*
X427732D01*
G01X431332Y1625058D02*
Y1633058D01*
G01X435532D02*
Y1625058D01*
G01Y1629058D02*
X431332D01*
G01X439332Y1626124D02*
X440132Y1625458D01*
X441032Y1625058D01*
X441832D01*
X442632Y1625458D01*
X443232Y1626124D01*
X443532Y1627058D01*
X443332Y1627991D01*
X442832Y1628791D01*
X441932Y1629325D01*
X440732Y1629591D01*
X440032Y1630125D01*
X439732Y1631058D01*
X439932Y1631991D01*
X440432Y1632658D01*
X441132Y1633058D01*
X441832D01*
X442532Y1632791D01*
X443132Y1632125D01*
G01X449232Y1623591D02*
X449632Y1625325D01*
G01X471232Y1625058D02*
Y1633058D01*
X473232D01*
X474032Y1632658D01*
X474632Y1632125D01*
X475132Y1631325D01*
X475532Y1630391D01*
X475632Y1629058D01*
X475532Y1627725D01*
X475132Y1626791D01*
X474632Y1625991D01*
X474032Y1625458D01*
X473232Y1625058D01*
X471232D01*
G01X480232Y1633058D02*
X482632D01*
G01X481432D02*
Y1625058D01*
G01X480232D02*
X482632D01*
G01X491432D02*
X487432D01*
Y1633058D01*
X491432D01*
G01X489832Y1629191D02*
X487432D01*
G01X495432Y1633058D02*
Y1625058D01*
X499432D01*
G01X507432D02*
X503432D01*
Y1633058D01*
X507432D01*
G01X505832Y1629191D02*
X503432D01*
G01X515632Y1632391D02*
X515032Y1632791D01*
X514332Y1633058D01*
X513532D01*
X512632Y1632658D01*
X511932Y1631991D01*
X511432Y1631191D01*
X511032Y1629858D01*
X510932Y1628658D01*
X511132Y1627458D01*
X511432Y1626658D01*
X512032Y1625858D01*
X512732Y1625325D01*
X513432Y1625058D01*
X514132D01*
X514832Y1625325D01*
X515432Y1625725D01*
X515932Y1626258D01*
G01X521432Y1633058D02*
Y1625058D01*
G01X519132Y1633058D02*
X523732D01*
G01X527432Y1625058D02*
Y1633058D01*
X529932D01*
X530732Y1632658D01*
X531232Y1632125D01*
X531432Y1631058D01*
X531232Y1629991D01*
X530632Y1629325D01*
X529932Y1628925D01*
X527432D01*
G01X529932D02*
X531432Y1625058D01*
G01X536232Y1633058D02*
X538632D01*
G01X537432D02*
Y1625058D01*
G01X536232D02*
X538632D01*
G01X547632Y1632391D02*
X547032Y1632791D01*
X546332Y1633058D01*
X545532D01*
X544632Y1632658D01*
X543932Y1631991D01*
X543432Y1631191D01*
X543032Y1629858D01*
X542932Y1628658D01*
X543132Y1627458D01*
X543432Y1626658D01*
X544032Y1625858D01*
X544732Y1625325D01*
X545432Y1625058D01*
X546132D01*
X546832Y1625325D01*
X547432Y1625725D01*
X547932Y1626258D01*
G01X50532Y1670058D02*
Y1678058D01*
X54332D01*
G01X52932Y1674191D02*
X50532D01*
G01X60432Y1669791D02*
X60232Y1669925D01*
Y1670191D01*
X60432Y1670325D01*
X60632Y1670191D01*
Y1669925D01*
X60432Y1669791D01*
G01X66132Y1670058D02*
Y1678058D01*
X70732Y1670058D01*
Y1678058D01*
G01X78432Y1670058D02*
X74432D01*
Y1678058D01*
X78432D01*
G01X76832Y1674191D02*
X74432D01*
G01X86432Y1670058D02*
X82432D01*
Y1678058D01*
X86432D01*
G01X84832Y1674191D02*
X82432D01*
G01X90232Y1670058D02*
Y1678058D01*
X92232D01*
X93032Y1677658D01*
X93632Y1677125D01*
X94132Y1676325D01*
X94532Y1675391D01*
X94632Y1674058D01*
X94532Y1672725D01*
X94132Y1671791D01*
X93632Y1670991D01*
X93032Y1670458D01*
X92232Y1670058D01*
X90232D01*
G01X106432D02*
Y1678058D01*
X108832D01*
X109632Y1677658D01*
X110232Y1676725D01*
X110432Y1675658D01*
X110232Y1674591D01*
X109732Y1673791D01*
X108832Y1673391D01*
X106432D01*
G01X118632Y1677391D02*
X118032Y1677791D01*
X117332Y1678058D01*
X116532D01*
X115632Y1677658D01*
X114932Y1676991D01*
X114432Y1676191D01*
X114032Y1674858D01*
X113932Y1673658D01*
X114132Y1672458D01*
X114432Y1671658D01*
X115032Y1670858D01*
X115732Y1670325D01*
X116432Y1670058D01*
X117132D01*
X117832Y1670325D01*
X118432Y1670725D01*
X118932Y1671258D01*
G01X125232Y1674325D02*
X125632Y1674725D01*
X125932Y1675391D01*
X126132Y1676325D01*
X125932Y1677125D01*
X125532Y1677658D01*
X124832Y1678058D01*
X122132D01*
Y1670058D01*
X125432D01*
X126132Y1670591D01*
X126532Y1671391D01*
X126732Y1672325D01*
X126532Y1673258D01*
X125932Y1674058D01*
X125232Y1674325D01*
X122132D01*
G01X137832Y1670058D02*
Y1678058D01*
X140432Y1671391D01*
X143032Y1678058D01*
Y1670058D01*
G01X145932D02*
X148432Y1678058D01*
X150932Y1670058D01*
G01X150032Y1672858D02*
X146832D01*
G01X154232Y1670058D02*
Y1678058D01*
G01X158032D02*
X154232Y1673124D01*
G01X158632Y1670058D02*
X155932Y1675391D01*
G01X166432Y1670058D02*
X162432D01*
Y1678058D01*
X166432D01*
G01X164832Y1674191D02*
X162432D01*
G01X170432Y1670058D02*
Y1678058D01*
X172932D01*
X173732Y1677658D01*
X174232Y1677125D01*
X174432Y1676058D01*
X174232Y1674991D01*
X173632Y1674325D01*
X172932Y1673925D01*
X170432D01*
G01X172932D02*
X174432Y1670058D01*
G01X178332Y1671124D02*
X179132Y1670458D01*
X180032Y1670058D01*
X180832D01*
X181632Y1670458D01*
X182232Y1671124D01*
X182532Y1672058D01*
X182332Y1672991D01*
X181832Y1673791D01*
X180932Y1674325D01*
X179732Y1674591D01*
X179032Y1675125D01*
X178732Y1676058D01*
X178932Y1676991D01*
X179432Y1677658D01*
X180132Y1678058D01*
X180832D01*
X181532Y1677791D01*
X182132Y1677125D01*
G01X195932Y1667391D02*
X194932Y1668725D01*
X194432Y1670058D01*
Y1675391D01*
X194932Y1676725D01*
X195932Y1678058D01*
G01X202332Y1671124D02*
X203132Y1670458D01*
X204032Y1670058D01*
X204832D01*
X205632Y1670458D01*
X206232Y1671124D01*
X206532Y1672058D01*
X206332Y1672991D01*
X205832Y1673791D01*
X204932Y1674325D01*
X203732Y1674591D01*
X203032Y1675125D01*
X202732Y1676058D01*
X202932Y1676991D01*
X203432Y1677658D01*
X204132Y1678058D01*
X204832D01*
X205532Y1677791D01*
X206132Y1677125D01*
G01X211232Y1678058D02*
X213632D01*
G01X212432D02*
Y1670058D01*
G01X211232D02*
X213632D01*
G01X218432Y1678058D02*
Y1670058D01*
X222432D01*
G01X226232D02*
Y1678058D01*
G01X230032D02*
X226232Y1673124D01*
G01X230632Y1670058D02*
X227932Y1675391D01*
G01X234332Y1671124D02*
X235132Y1670458D01*
X236032Y1670058D01*
X236832D01*
X237632Y1670458D01*
X238232Y1671124D01*
X238532Y1672058D01*
X238332Y1672991D01*
X237832Y1673791D01*
X236932Y1674325D01*
X235732Y1674591D01*
X235032Y1675125D01*
X234732Y1676058D01*
X234932Y1676991D01*
X235432Y1677658D01*
X236132Y1678058D01*
X236832D01*
X237532Y1677791D01*
X238132Y1677125D01*
G01X246632Y1677391D02*
X246032Y1677791D01*
X245332Y1678058D01*
X244532D01*
X243632Y1677658D01*
X242932Y1676991D01*
X242432Y1676191D01*
X242032Y1674858D01*
X241932Y1673658D01*
X242132Y1672458D01*
X242432Y1671658D01*
X243032Y1670858D01*
X243732Y1670325D01*
X244432Y1670058D01*
X245132D01*
X245832Y1670325D01*
X246432Y1670725D01*
X246932Y1671258D01*
G01X250432Y1670058D02*
Y1678058D01*
X252932D01*
X253732Y1677658D01*
X254232Y1677125D01*
X254432Y1676058D01*
X254232Y1674991D01*
X253632Y1674325D01*
X252932Y1673925D01*
X250432D01*
G01X252932D02*
X254432Y1670058D01*
G01X262432D02*
X258432D01*
Y1678058D01*
X262432D01*
G01X260832Y1674191D02*
X258432D01*
G01X270432Y1670058D02*
X266432D01*
Y1678058D01*
X270432D01*
G01X268832Y1674191D02*
X266432D01*
G01X274132Y1670058D02*
Y1678058D01*
X278732Y1670058D01*
Y1678058D01*
G01X284432Y1669791D02*
X284232Y1669925D01*
Y1670191D01*
X284432Y1670325D01*
X284632Y1670191D01*
Y1669925D01*
X284432Y1669791D01*
G01X292432Y1678058D02*
Y1670058D01*
G01X290132Y1678058D02*
X294732D01*
G01X300432Y1670058D02*
X299632Y1670191D01*
X298932Y1670725D01*
X298332Y1671525D01*
X297932Y1672458D01*
X297732Y1673525D01*
Y1674591D01*
X297932Y1675658D01*
X298332Y1676591D01*
X298932Y1677391D01*
X299632Y1677925D01*
X300432Y1678058D01*
X301232Y1677925D01*
X301932Y1677391D01*
X302532Y1676591D01*
X302932Y1675658D01*
X303132Y1674591D01*
Y1673525D01*
X302932Y1672458D01*
X302532Y1671525D01*
X301932Y1670725D01*
X301232Y1670191D01*
X300432Y1670058D01*
G01X306432D02*
Y1678058D01*
X308832D01*
X309632Y1677658D01*
X310232Y1676725D01*
X310432Y1675658D01*
X310232Y1674591D01*
X309732Y1673791D01*
X308832Y1673391D01*
X306432D01*
G01X322332Y1671124D02*
X323132Y1670458D01*
X324032Y1670058D01*
X324832D01*
X325632Y1670458D01*
X326232Y1671124D01*
X326532Y1672058D01*
X326332Y1672991D01*
X325832Y1673791D01*
X324932Y1674325D01*
X323732Y1674591D01*
X323032Y1675125D01*
X322732Y1676058D01*
X322932Y1676991D01*
X323432Y1677658D01*
X324132Y1678058D01*
X324832D01*
X325532Y1677791D01*
X326132Y1677125D01*
G01X331232Y1678058D02*
X333632D01*
G01X332432D02*
Y1670058D01*
G01X331232D02*
X333632D01*
G01X338232D02*
Y1678058D01*
X340232D01*
X341032Y1677658D01*
X341632Y1677125D01*
X342132Y1676325D01*
X342532Y1675391D01*
X342632Y1674058D01*
X342532Y1672725D01*
X342132Y1671791D01*
X341632Y1670991D01*
X341032Y1670458D01*
X340232Y1670058D01*
X338232D01*
G01X350432D02*
X346432D01*
Y1678058D01*
X350432D01*
G01X348832Y1674191D02*
X346432D01*
G01X356932Y1667391D02*
X357932Y1668725D01*
X358432Y1670058D01*
Y1675391D01*
X357932Y1676725D01*
X356932Y1678058D01*
G01X53032Y1659058D02*
X55032D01*
Y1656658D01*
X54432Y1655858D01*
X53732Y1655325D01*
X52732Y1655058D01*
X51732Y1655325D01*
X51032Y1655858D01*
X50432Y1656658D01*
X50032Y1657591D01*
X49832Y1658658D01*
Y1659591D01*
X50032Y1660391D01*
X50432Y1661325D01*
X51032Y1662125D01*
X51632Y1662658D01*
X52432Y1663058D01*
X53132D01*
X53932Y1662791D01*
X54532Y1662258D01*
G01X60432Y1654791D02*
X60232Y1654925D01*
Y1655191D01*
X60432Y1655325D01*
X60632Y1655191D01*
Y1654925D01*
X60432Y1654791D01*
G01X66132Y1655058D02*
Y1663058D01*
X70732Y1655058D01*
Y1663058D01*
G01X78432Y1655058D02*
X74432D01*
Y1663058D01*
X78432D01*
G01X76832Y1659191D02*
X74432D01*
G01X86432Y1655058D02*
X82432D01*
Y1663058D01*
X86432D01*
G01X84832Y1659191D02*
X82432D01*
G01X90232Y1655058D02*
Y1663058D01*
X92232D01*
X93032Y1662658D01*
X93632Y1662125D01*
X94132Y1661325D01*
X94532Y1660391D01*
X94632Y1659058D01*
X94532Y1657725D01*
X94132Y1656791D01*
X93632Y1655991D01*
X93032Y1655458D01*
X92232Y1655058D01*
X90232D01*
G01X106232Y1663058D02*
Y1657325D01*
X106632Y1656124D01*
X107432Y1655325D01*
X108432Y1655058D01*
X109432Y1655325D01*
X110232Y1656124D01*
X110632Y1657325D01*
Y1663058D01*
G01X114432D02*
Y1655058D01*
X118432D01*
G01X129832D02*
Y1663058D01*
X132432Y1656391D01*
X135032Y1663058D01*
Y1655058D01*
G01X137932D02*
X140432Y1663058D01*
X142932Y1655058D01*
G01X142032Y1657858D02*
X138832D01*
G01X146432Y1655058D02*
Y1663058D01*
X148932D01*
X149732Y1662658D01*
X150232Y1662125D01*
X150432Y1661058D01*
X150232Y1659991D01*
X149632Y1659325D01*
X148932Y1658925D01*
X146432D01*
G01X148932D02*
X150432Y1655058D01*
G01X154232D02*
Y1663058D01*
G01X158032D02*
X154232Y1658124D01*
G01X158632Y1655058D02*
X155932Y1660391D01*
G01X169932Y1655058D02*
X172432Y1663058D01*
X174932Y1655058D01*
G01X174032Y1657858D02*
X170832D01*
G01X178132Y1655058D02*
Y1663058D01*
X182732Y1655058D01*
Y1663058D01*
G01X186232Y1655058D02*
Y1663058D01*
X188232D01*
X189032Y1662658D01*
X189632Y1662125D01*
X190132Y1661325D01*
X190532Y1660391D01*
X190632Y1659058D01*
X190532Y1657725D01*
X190132Y1656791D01*
X189632Y1655991D01*
X189032Y1655458D01*
X188232Y1655058D01*
X186232D01*
G01X202232D02*
Y1663058D01*
X204232D01*
X205032Y1662658D01*
X205632Y1662125D01*
X206132Y1661325D01*
X206532Y1660391D01*
X206632Y1659058D01*
X206532Y1657725D01*
X206132Y1656791D01*
X205632Y1655991D01*
X205032Y1655458D01*
X204232Y1655058D01*
X202232D01*
G01X209932D02*
X212432Y1663058D01*
X214932Y1655058D01*
G01X214032Y1657858D02*
X210832D01*
G01X220432Y1663058D02*
Y1655058D01*
G01X218132Y1663058D02*
X222732D01*
G01X230432Y1655058D02*
X226432D01*
Y1663058D01*
X230432D01*
G01X228832Y1659191D02*
X226432D01*
G01X246632Y1662391D02*
X246032Y1662791D01*
X245332Y1663058D01*
X244532D01*
X243632Y1662658D01*
X242932Y1661991D01*
X242432Y1661191D01*
X242032Y1659858D01*
X241932Y1658658D01*
X242132Y1657458D01*
X242432Y1656658D01*
X243032Y1655858D01*
X243732Y1655325D01*
X244432Y1655058D01*
X245132D01*
X245832Y1655325D01*
X246432Y1655725D01*
X246932Y1656258D01*
G01X252432Y1655058D02*
X251632Y1655191D01*
X250932Y1655725D01*
X250332Y1656525D01*
X249932Y1657458D01*
X249732Y1658525D01*
Y1659591D01*
X249932Y1660658D01*
X250332Y1661591D01*
X250932Y1662391D01*
X251632Y1662925D01*
X252432Y1663058D01*
X253232Y1662925D01*
X253932Y1662391D01*
X254532Y1661591D01*
X254932Y1660658D01*
X255132Y1659591D01*
Y1658525D01*
X254932Y1657458D01*
X254532Y1656525D01*
X253932Y1655725D01*
X253232Y1655191D01*
X252432Y1655058D01*
G01X258232D02*
Y1663058D01*
X260232D01*
X261032Y1662658D01*
X261632Y1662125D01*
X262132Y1661325D01*
X262532Y1660391D01*
X262632Y1659058D01*
X262532Y1657725D01*
X262132Y1656791D01*
X261632Y1655991D01*
X261032Y1655458D01*
X260232Y1655058D01*
X258232D01*
G01X270432D02*
X266432D01*
Y1663058D01*
X270432D01*
G01X268832Y1659191D02*
X266432D01*
G01X283932Y1652391D02*
X282932Y1653725D01*
X282432Y1655058D01*
Y1660391D01*
X282932Y1661725D01*
X283932Y1663058D01*
G01X290332Y1656124D02*
X291132Y1655458D01*
X292032Y1655058D01*
X292832D01*
X293632Y1655458D01*
X294232Y1656124D01*
X294532Y1657058D01*
X294332Y1657991D01*
X293832Y1658791D01*
X292932Y1659325D01*
X291732Y1659591D01*
X291032Y1660125D01*
X290732Y1661058D01*
X290932Y1661991D01*
X291432Y1662658D01*
X292132Y1663058D01*
X292832D01*
X293532Y1662791D01*
X294132Y1662125D01*
G01X299232Y1663058D02*
X301632D01*
G01X300432D02*
Y1655058D01*
G01X299232D02*
X301632D01*
G01X306432Y1663058D02*
Y1655058D01*
X310432D01*
G01X314232D02*
Y1663058D01*
G01X318032D02*
X314232Y1658124D01*
G01X318632Y1655058D02*
X315932Y1660391D01*
G01X322332Y1656124D02*
X323132Y1655458D01*
X324032Y1655058D01*
X324832D01*
X325632Y1655458D01*
X326232Y1656124D01*
X326532Y1657058D01*
X326332Y1657991D01*
X325832Y1658791D01*
X324932Y1659325D01*
X323732Y1659591D01*
X323032Y1660125D01*
X322732Y1661058D01*
X322932Y1661991D01*
X323432Y1662658D01*
X324132Y1663058D01*
X324832D01*
X325532Y1662791D01*
X326132Y1662125D01*
G01X334632Y1662391D02*
X334032Y1662791D01*
X333332Y1663058D01*
X332532D01*
X331632Y1662658D01*
X330932Y1661991D01*
X330432Y1661191D01*
X330032Y1659858D01*
X329932Y1658658D01*
X330132Y1657458D01*
X330432Y1656658D01*
X331032Y1655858D01*
X331732Y1655325D01*
X332432Y1655058D01*
X333132D01*
X333832Y1655325D01*
X334432Y1655725D01*
X334932Y1656258D01*
G01X338432Y1655058D02*
Y1663058D01*
X340932D01*
X341732Y1662658D01*
X342232Y1662125D01*
X342432Y1661058D01*
X342232Y1659991D01*
X341632Y1659325D01*
X340932Y1658925D01*
X338432D01*
G01X340932D02*
X342432Y1655058D01*
G01X350432D02*
X346432D01*
Y1663058D01*
X350432D01*
G01X348832Y1659191D02*
X346432D01*
G01X358432Y1655058D02*
X354432D01*
Y1663058D01*
X358432D01*
G01X356832Y1659191D02*
X354432D01*
G01X362132Y1655058D02*
Y1663058D01*
X366732Y1655058D01*
Y1663058D01*
G01X372232Y1653591D02*
X372632Y1655325D01*
G01X380432Y1663058D02*
Y1655058D01*
G01X378132Y1663058D02*
X382732D01*
G01X388432Y1655058D02*
X387632Y1655191D01*
X386932Y1655725D01*
X386332Y1656525D01*
X385932Y1657458D01*
X385732Y1658525D01*
Y1659591D01*
X385932Y1660658D01*
X386332Y1661591D01*
X386932Y1662391D01*
X387632Y1662925D01*
X388432Y1663058D01*
X389232Y1662925D01*
X389932Y1662391D01*
X390532Y1661591D01*
X390932Y1660658D01*
X391132Y1659591D01*
Y1658525D01*
X390932Y1657458D01*
X390532Y1656525D01*
X389932Y1655725D01*
X389232Y1655191D01*
X388432Y1655058D01*
G01X394432D02*
Y1663058D01*
X396832D01*
X397632Y1662658D01*
X398232Y1661725D01*
X398432Y1660658D01*
X398232Y1659591D01*
X397732Y1658791D01*
X396832Y1658391D01*
X394432D01*
G01X410332Y1656124D02*
X411132Y1655458D01*
X412032Y1655058D01*
X412832D01*
X413632Y1655458D01*
X414232Y1656124D01*
X414532Y1657058D01*
X414332Y1657991D01*
X413832Y1658791D01*
X412932Y1659325D01*
X411732Y1659591D01*
X411032Y1660125D01*
X410732Y1661058D01*
X410932Y1661991D01*
X411432Y1662658D01*
X412132Y1663058D01*
X412832D01*
X413532Y1662791D01*
X414132Y1662125D01*
G01X419232Y1663058D02*
X421632D01*
G01X420432D02*
Y1655058D01*
G01X419232D02*
X421632D01*
G01X426232D02*
Y1663058D01*
X428232D01*
X429032Y1662658D01*
X429632Y1662125D01*
X430132Y1661325D01*
X430532Y1660391D01*
X430632Y1659058D01*
X430532Y1657725D01*
X430132Y1656791D01*
X429632Y1655991D01*
X429032Y1655458D01*
X428232Y1655058D01*
X426232D01*
G01X438432D02*
X434432D01*
Y1663058D01*
X438432D01*
G01X436832Y1659191D02*
X434432D01*
G01X444232Y1653591D02*
X444632Y1655325D01*
G01X457432Y1663058D02*
X458832Y1655058D01*
X460432Y1663058D01*
X462032Y1655058D01*
X463432Y1663058D01*
G01X465432D02*
X466832Y1655058D01*
X468432Y1663058D01*
X470032Y1655058D01*
X471432Y1663058D01*
G01X476432Y1655058D02*
Y1658658D01*
X474432Y1663058D01*
G01X478432D02*
X476432Y1658658D01*
G01X484432Y1655058D02*
Y1658658D01*
X482432Y1663058D01*
G01X486432D02*
X484432Y1658658D01*
G01X492932Y1652391D02*
X493932Y1653725D01*
X494432Y1655058D01*
Y1660391D01*
X493932Y1661725D01*
X492932Y1663058D01*
G01X54432Y1685058D02*
X50432D01*
Y1693058D01*
X54432D01*
G01X52832Y1689191D02*
X50432D01*
G01X60432Y1684791D02*
X60232Y1684925D01*
Y1685191D01*
X60432Y1685325D01*
X60632Y1685191D01*
Y1684925D01*
X60432Y1684791D01*
G01X66432Y1685058D02*
Y1693058D01*
X68832D01*
X69632Y1692658D01*
X70232Y1691725D01*
X70432Y1690658D01*
X70232Y1689591D01*
X69732Y1688791D01*
X68832Y1688391D01*
X66432D01*
G01X74432Y1685058D02*
Y1693058D01*
X76932D01*
X77732Y1692658D01*
X78232Y1692125D01*
X78432Y1691058D01*
X78232Y1689991D01*
X77632Y1689325D01*
X76932Y1688925D01*
X74432D01*
G01X76932D02*
X78432Y1685058D01*
G01X84432D02*
X83632Y1685191D01*
X82932Y1685725D01*
X82332Y1686525D01*
X81932Y1687458D01*
X81732Y1688525D01*
Y1689591D01*
X81932Y1690658D01*
X82332Y1691591D01*
X82932Y1692391D01*
X83632Y1692925D01*
X84432Y1693058D01*
X85232Y1692925D01*
X85932Y1692391D01*
X86532Y1691591D01*
X86932Y1690658D01*
X87132Y1689591D01*
Y1688525D01*
X86932Y1687458D01*
X86532Y1686525D01*
X85932Y1685725D01*
X85232Y1685191D01*
X84432Y1685058D01*
G01X89932Y1693058D02*
X92432Y1685058D01*
X94932Y1693058D01*
G01X99232D02*
X101632D01*
G01X100432D02*
Y1685058D01*
G01X99232D02*
X101632D01*
G01X106232D02*
Y1693058D01*
X108232D01*
X109032Y1692658D01*
X109632Y1692125D01*
X110132Y1691325D01*
X110532Y1690391D01*
X110632Y1689058D01*
X110532Y1687725D01*
X110132Y1686791D01*
X109632Y1685991D01*
X109032Y1685458D01*
X108232Y1685058D01*
X106232D01*
G01X118432D02*
X114432D01*
Y1693058D01*
X118432D01*
G01X116832Y1689191D02*
X114432D01*
G01X130432Y1685058D02*
Y1693058D01*
X132832D01*
X133632Y1692658D01*
X134232Y1691725D01*
X134432Y1690658D01*
X134232Y1689591D01*
X133732Y1688791D01*
X132832Y1688391D01*
X130432D01*
G01X142632Y1692391D02*
X142032Y1692791D01*
X141332Y1693058D01*
X140532D01*
X139632Y1692658D01*
X138932Y1691991D01*
X138432Y1691191D01*
X138032Y1689858D01*
X137932Y1688658D01*
X138132Y1687458D01*
X138432Y1686658D01*
X139032Y1685858D01*
X139732Y1685325D01*
X140432Y1685058D01*
X141132D01*
X141832Y1685325D01*
X142432Y1685725D01*
X142932Y1686258D01*
G01X149232Y1689325D02*
X149632Y1689725D01*
X149932Y1690391D01*
X150132Y1691325D01*
X149932Y1692125D01*
X149532Y1692658D01*
X148832Y1693058D01*
X146132D01*
Y1685058D01*
X149432D01*
X150132Y1685591D01*
X150532Y1686391D01*
X150732Y1687325D01*
X150532Y1688258D01*
X149932Y1689058D01*
X149232Y1689325D01*
X146132D01*
G01X162532Y1685058D02*
Y1693058D01*
X166332D01*
G01X164932Y1689191D02*
X162532D01*
G01X171232Y1693058D02*
X173632D01*
G01X172432D02*
Y1685058D01*
G01X171232D02*
X173632D01*
G01X178432Y1693058D02*
Y1685058D01*
X182432D01*
G01X185832D02*
Y1693058D01*
X188432Y1686391D01*
X191032Y1693058D01*
Y1685058D01*
G01X50232Y1700058D02*
Y1708058D01*
X52232D01*
X53032Y1707658D01*
X53632Y1707125D01*
X54132Y1706325D01*
X54532Y1705391D01*
X54632Y1704058D01*
X54532Y1702725D01*
X54132Y1701791D01*
X53632Y1700991D01*
X53032Y1700458D01*
X52232Y1700058D01*
X50232D01*
G01X60432Y1699791D02*
X60232Y1699925D01*
Y1700191D01*
X60432Y1700325D01*
X60632Y1700191D01*
Y1699925D01*
X60432Y1699791D01*
G01X66432Y1700058D02*
Y1708058D01*
X68832D01*
X69632Y1707658D01*
X70232Y1706725D01*
X70432Y1705658D01*
X70232Y1704591D01*
X69732Y1703791D01*
X68832Y1703391D01*
X66432D01*
G01X74432Y1700058D02*
Y1708058D01*
X76932D01*
X77732Y1707658D01*
X78232Y1707125D01*
X78432Y1706058D01*
X78232Y1704991D01*
X77632Y1704325D01*
X76932Y1703925D01*
X74432D01*
G01X76932D02*
X78432Y1700058D01*
G01X84432D02*
X83632Y1700191D01*
X82932Y1700725D01*
X82332Y1701525D01*
X81932Y1702458D01*
X81732Y1703525D01*
Y1704591D01*
X81932Y1705658D01*
X82332Y1706591D01*
X82932Y1707391D01*
X83632Y1707925D01*
X84432Y1708058D01*
X85232Y1707925D01*
X85932Y1707391D01*
X86532Y1706591D01*
X86932Y1705658D01*
X87132Y1704591D01*
Y1703525D01*
X86932Y1702458D01*
X86532Y1701525D01*
X85932Y1700725D01*
X85232Y1700191D01*
X84432Y1700058D01*
G01X89932Y1708058D02*
X92432Y1700058D01*
X94932Y1708058D01*
G01X99232D02*
X101632D01*
G01X100432D02*
Y1700058D01*
G01X99232D02*
X101632D01*
G01X106232D02*
Y1708058D01*
X108232D01*
X109032Y1707658D01*
X109632Y1707125D01*
X110132Y1706325D01*
X110532Y1705391D01*
X110632Y1704058D01*
X110532Y1702725D01*
X110132Y1701791D01*
X109632Y1700991D01*
X109032Y1700458D01*
X108232Y1700058D01*
X106232D01*
G01X118432D02*
X114432D01*
Y1708058D01*
X118432D01*
G01X116832Y1704191D02*
X114432D01*
G01X131232Y1708058D02*
X133632D01*
G01X132432D02*
Y1700058D01*
G01X131232D02*
X133632D01*
G01X137832D02*
Y1708058D01*
X140432Y1701391D01*
X143032Y1708058D01*
Y1700058D01*
G01X146432D02*
Y1708058D01*
X148832D01*
X149632Y1707658D01*
X150232Y1706725D01*
X150432Y1705658D01*
X150232Y1704591D01*
X149732Y1703791D01*
X148832Y1703391D01*
X146432D01*
G01X158432Y1700058D02*
X154432D01*
Y1708058D01*
X158432D01*
G01X156832Y1704191D02*
X154432D01*
G01X162232Y1700058D02*
Y1708058D01*
X164232D01*
X165032Y1707658D01*
X165632Y1707125D01*
X166132Y1706325D01*
X166532Y1705391D01*
X166632Y1704058D01*
X166532Y1702725D01*
X166132Y1701791D01*
X165632Y1700991D01*
X165032Y1700458D01*
X164232Y1700058D01*
X162232D01*
G01X169932D02*
X172432Y1708058D01*
X174932Y1700058D01*
G01X174032Y1702858D02*
X170832D01*
G01X178132Y1700058D02*
Y1708058D01*
X182732Y1700058D01*
Y1708058D01*
G01X190632Y1707391D02*
X190032Y1707791D01*
X189332Y1708058D01*
X188532D01*
X187632Y1707658D01*
X186932Y1706991D01*
X186432Y1706191D01*
X186032Y1704858D01*
X185932Y1703658D01*
X186132Y1702458D01*
X186432Y1701658D01*
X187032Y1700858D01*
X187732Y1700325D01*
X188432Y1700058D01*
X189132D01*
X189832Y1700325D01*
X190432Y1700725D01*
X190932Y1701258D01*
G01X198432Y1700058D02*
X194432D01*
Y1708058D01*
X198432D01*
G01X196832Y1704191D02*
X194432D01*
G01X214632Y1707391D02*
X214032Y1707791D01*
X213332Y1708058D01*
X212532D01*
X211632Y1707658D01*
X210932Y1706991D01*
X210432Y1706191D01*
X210032Y1704858D01*
X209932Y1703658D01*
X210132Y1702458D01*
X210432Y1701658D01*
X211032Y1700858D01*
X211732Y1700325D01*
X212432Y1700058D01*
X213132D01*
X213832Y1700325D01*
X214432Y1700725D01*
X214932Y1701258D01*
G01X220432Y1700058D02*
X219632Y1700191D01*
X218932Y1700725D01*
X218332Y1701525D01*
X217932Y1702458D01*
X217732Y1703525D01*
Y1704591D01*
X217932Y1705658D01*
X218332Y1706591D01*
X218932Y1707391D01*
X219632Y1707925D01*
X220432Y1708058D01*
X221232Y1707925D01*
X221932Y1707391D01*
X222532Y1706591D01*
X222932Y1705658D01*
X223132Y1704591D01*
Y1703525D01*
X222932Y1702458D01*
X222532Y1701525D01*
X221932Y1700725D01*
X221232Y1700191D01*
X220432Y1700058D01*
G01X226232Y1708058D02*
Y1702325D01*
X226632Y1701124D01*
X227432Y1700325D01*
X228432Y1700058D01*
X229432Y1700325D01*
X230232Y1701124D01*
X230632Y1702325D01*
Y1708058D01*
G01X234432Y1700058D02*
Y1708058D01*
X236832D01*
X237632Y1707658D01*
X238232Y1706725D01*
X238432Y1705658D01*
X238232Y1704591D01*
X237732Y1703791D01*
X236832Y1703391D01*
X234432D01*
G01X244432Y1700058D02*
X243632Y1700191D01*
X242932Y1700725D01*
X242332Y1701525D01*
X241932Y1702458D01*
X241732Y1703525D01*
Y1704591D01*
X241932Y1705658D01*
X242332Y1706591D01*
X242932Y1707391D01*
X243632Y1707925D01*
X244432Y1708058D01*
X245232Y1707925D01*
X245932Y1707391D01*
X246532Y1706591D01*
X246932Y1705658D01*
X247132Y1704591D01*
Y1703525D01*
X246932Y1702458D01*
X246532Y1701525D01*
X245932Y1700725D01*
X245232Y1700191D01*
X244432Y1700058D01*
G01X250132D02*
Y1708058D01*
X254732Y1700058D01*
Y1708058D01*
G01X265932Y1700058D02*
X268432Y1708058D01*
X270932Y1700058D01*
G01X270032Y1702858D02*
X266832D01*
G01X274132Y1700058D02*
Y1708058D01*
X278732Y1700058D01*
Y1708058D01*
G01X282232Y1700058D02*
Y1708058D01*
X284232D01*
X285032Y1707658D01*
X285632Y1707125D01*
X286132Y1706325D01*
X286532Y1705391D01*
X286632Y1704058D01*
X286532Y1702725D01*
X286132Y1701791D01*
X285632Y1700991D01*
X285032Y1700458D01*
X284232Y1700058D01*
X282232D01*
G01X297832D02*
Y1708058D01*
X300432Y1701391D01*
X303032Y1708058D01*
Y1700058D01*
G01X310432D02*
X306432D01*
Y1708058D01*
X310432D01*
G01X308832Y1704191D02*
X306432D01*
G01X313932Y1700058D02*
X316432Y1708058D01*
X318932Y1700058D01*
G01X318032Y1702858D02*
X314832D01*
G01X322332Y1701124D02*
X323132Y1700458D01*
X324032Y1700058D01*
X324832D01*
X325632Y1700458D01*
X326232Y1701124D01*
X326532Y1702058D01*
X326332Y1702991D01*
X325832Y1703791D01*
X324932Y1704325D01*
X323732Y1704591D01*
X323032Y1705125D01*
X322732Y1706058D01*
X322932Y1706991D01*
X323432Y1707658D01*
X324132Y1708058D01*
X324832D01*
X325532Y1707791D01*
X326132Y1707125D01*
G01X330232Y1708058D02*
Y1702325D01*
X330632Y1701124D01*
X331432Y1700325D01*
X332432Y1700058D01*
X333432Y1700325D01*
X334232Y1701124D01*
X334632Y1702325D01*
Y1708058D01*
G01X338432Y1700058D02*
Y1708058D01*
X340932D01*
X341732Y1707658D01*
X342232Y1707125D01*
X342432Y1706058D01*
X342232Y1704991D01*
X341632Y1704325D01*
X340932Y1703925D01*
X338432D01*
G01X340932D02*
X342432Y1700058D01*
G01X350432D02*
X346432D01*
Y1708058D01*
X350432D01*
G01X348832Y1704191D02*
X346432D01*
G01X353832Y1700058D02*
Y1708058D01*
X356432Y1701391D01*
X359032Y1708058D01*
Y1700058D01*
G01X366432D02*
X362432D01*
Y1708058D01*
X366432D01*
G01X364832Y1704191D02*
X362432D01*
G01X370132Y1700058D02*
Y1708058D01*
X374732Y1700058D01*
Y1708058D01*
G01X380432D02*
Y1700058D01*
G01X378132Y1708058D02*
X382732D01*
G01X394432Y1700058D02*
Y1708058D01*
X396932D01*
X397732Y1707658D01*
X398232Y1707125D01*
X398432Y1706058D01*
X398232Y1704991D01*
X397632Y1704325D01*
X396932Y1703925D01*
X394432D01*
G01X396932D02*
X398432Y1700058D01*
G01X406432D02*
X402432D01*
Y1708058D01*
X406432D01*
G01X404832Y1704191D02*
X402432D01*
G01X410432Y1700058D02*
Y1708058D01*
X412832D01*
X413632Y1707658D01*
X414232Y1706725D01*
X414432Y1705658D01*
X414232Y1704591D01*
X413732Y1703791D01*
X412832Y1703391D01*
X410432D01*
G01X420432Y1700058D02*
X419632Y1700191D01*
X418932Y1700725D01*
X418332Y1701525D01*
X417932Y1702458D01*
X417732Y1703525D01*
Y1704591D01*
X417932Y1705658D01*
X418332Y1706591D01*
X418932Y1707391D01*
X419632Y1707925D01*
X420432Y1708058D01*
X421232Y1707925D01*
X421932Y1707391D01*
X422532Y1706591D01*
X422932Y1705658D01*
X423132Y1704591D01*
Y1703525D01*
X422932Y1702458D01*
X422532Y1701525D01*
X421932Y1700725D01*
X421232Y1700191D01*
X420432Y1700058D01*
G01X426432D02*
Y1708058D01*
X428932D01*
X429732Y1707658D01*
X430232Y1707125D01*
X430432Y1706058D01*
X430232Y1704991D01*
X429632Y1704325D01*
X428932Y1703925D01*
X426432D01*
G01X428932D02*
X430432Y1700058D01*
G01X436432Y1708058D02*
Y1700058D01*
G01X434132Y1708058D02*
X438732D01*
G01X54632Y1722391D02*
X54032Y1722791D01*
X53332Y1723058D01*
X52532D01*
X51632Y1722658D01*
X50932Y1721991D01*
X50432Y1721191D01*
X50032Y1719858D01*
X49932Y1718658D01*
X50132Y1717458D01*
X50432Y1716658D01*
X51032Y1715858D01*
X51732Y1715325D01*
X52432Y1715058D01*
X53132D01*
X53832Y1715325D01*
X54432Y1715725D01*
X54932Y1716258D01*
G01X60432Y1714791D02*
X60232Y1714925D01*
Y1715191D01*
X60432Y1715325D01*
X60632Y1715191D01*
Y1714925D01*
X60432Y1714791D01*
G01X66132Y1715058D02*
Y1723058D01*
X70732Y1715058D01*
Y1723058D01*
G01X76432Y1715058D02*
X75632Y1715191D01*
X74932Y1715725D01*
X74332Y1716525D01*
X73932Y1717458D01*
X73732Y1718525D01*
Y1719591D01*
X73932Y1720658D01*
X74332Y1721591D01*
X74932Y1722391D01*
X75632Y1722925D01*
X76432Y1723058D01*
X77232Y1722925D01*
X77932Y1722391D01*
X78532Y1721591D01*
X78932Y1720658D01*
X79132Y1719591D01*
Y1718525D01*
X78932Y1717458D01*
X78532Y1716525D01*
X77932Y1715725D01*
X77232Y1715191D01*
X76432Y1715058D01*
G01X90132D02*
Y1723058D01*
X94732Y1715058D01*
Y1723058D01*
G01X102432Y1715058D02*
X98432D01*
Y1723058D01*
X102432D01*
G01X100832Y1719191D02*
X98432D01*
G01X110432Y1715058D02*
X106432D01*
Y1723058D01*
X110432D01*
G01X108832Y1719191D02*
X106432D01*
G01X114232Y1715058D02*
Y1723058D01*
X116232D01*
X117032Y1722658D01*
X117632Y1722125D01*
X118132Y1721325D01*
X118532Y1720391D01*
X118632Y1719058D01*
X118532Y1717725D01*
X118132Y1716791D01*
X117632Y1715991D01*
X117032Y1715458D01*
X116232Y1715058D01*
X114232D01*
G01X132432Y1723058D02*
Y1715058D01*
G01X130132Y1723058D02*
X134732D01*
G01X140432Y1715058D02*
X139632Y1715191D01*
X138932Y1715725D01*
X138332Y1716525D01*
X137932Y1717458D01*
X137732Y1718525D01*
Y1719591D01*
X137932Y1720658D01*
X138332Y1721591D01*
X138932Y1722391D01*
X139632Y1722925D01*
X140432Y1723058D01*
X141232Y1722925D01*
X141932Y1722391D01*
X142532Y1721591D01*
X142932Y1720658D01*
X143132Y1719591D01*
Y1718525D01*
X142932Y1717458D01*
X142532Y1716525D01*
X141932Y1715725D01*
X141232Y1715191D01*
X140432Y1715058D01*
G01X154432D02*
Y1723058D01*
X156832D01*
X157632Y1722658D01*
X158232Y1721725D01*
X158432Y1720658D01*
X158232Y1719591D01*
X157732Y1718791D01*
X156832Y1718391D01*
X154432D01*
G01X162432Y1723058D02*
Y1715058D01*
X166432D01*
G01X170232Y1723058D02*
Y1717325D01*
X170632Y1716124D01*
X171432Y1715325D01*
X172432Y1715058D01*
X173432Y1715325D01*
X174232Y1716124D01*
X174632Y1717325D01*
Y1723058D01*
G01X181032Y1719058D02*
X183032D01*
Y1716658D01*
X182432Y1715858D01*
X181732Y1715325D01*
X180732Y1715058D01*
X179732Y1715325D01*
X179032Y1715858D01*
X178432Y1716658D01*
X178032Y1717591D01*
X177832Y1718658D01*
Y1719591D01*
X178032Y1720391D01*
X178432Y1721325D01*
X179032Y1722125D01*
X179632Y1722658D01*
X180432Y1723058D01*
X181132D01*
X181932Y1722791D01*
X182532Y1722258D01*
G01X196432Y1715058D02*
X197132Y1715191D01*
X197932Y1715591D01*
X198432Y1716258D01*
X198632Y1717191D01*
X198432Y1718124D01*
X197832Y1718925D01*
X196932Y1719325D01*
X195932D01*
X195332Y1719591D01*
X194832Y1720258D01*
X194632Y1721191D01*
X194932Y1722125D01*
X195632Y1722791D01*
X196432Y1723058D01*
X197232Y1722791D01*
X197932Y1722125D01*
X198232Y1721191D01*
X198032Y1720258D01*
X197532Y1719591D01*
X196932Y1719325D01*
X195932D01*
X195032Y1718925D01*
X194432Y1718124D01*
X194232Y1717191D01*
X194432Y1716258D01*
X194932Y1715591D01*
X195732Y1715191D01*
X196432Y1715058D01*
G01X210332D02*
Y1723058D01*
G01X214532D02*
Y1715058D01*
G01Y1719058D02*
X210332D01*
G01X220432Y1715058D02*
X219632Y1715191D01*
X218932Y1715725D01*
X218332Y1716525D01*
X217932Y1717458D01*
X217732Y1718525D01*
Y1719591D01*
X217932Y1720658D01*
X218332Y1721591D01*
X218932Y1722391D01*
X219632Y1722925D01*
X220432Y1723058D01*
X221232Y1722925D01*
X221932Y1722391D01*
X222532Y1721591D01*
X222932Y1720658D01*
X223132Y1719591D01*
Y1718525D01*
X222932Y1717458D01*
X222532Y1716525D01*
X221932Y1715725D01*
X221232Y1715191D01*
X220432Y1715058D01*
G01X226432Y1723058D02*
Y1715058D01*
X230432D01*
G01X238432D02*
X234432D01*
Y1723058D01*
X238432D01*
G01X236832Y1719191D02*
X234432D01*
G01X242332Y1716124D02*
X243132Y1715458D01*
X244032Y1715058D01*
X244832D01*
X245632Y1715458D01*
X246232Y1716124D01*
X246532Y1717058D01*
X246332Y1717991D01*
X245832Y1718791D01*
X244932Y1719325D01*
X243732Y1719591D01*
X243032Y1720125D01*
X242732Y1721058D01*
X242932Y1721991D01*
X243432Y1722658D01*
X244132Y1723058D01*
X244832D01*
X245532Y1722791D01*
X246132Y1722125D01*
G01X258332Y1716124D02*
X259132Y1715458D01*
X260032Y1715058D01*
X260832D01*
X261632Y1715458D01*
X262232Y1716124D01*
X262532Y1717058D01*
X262332Y1717991D01*
X261832Y1718791D01*
X260932Y1719325D01*
X259732Y1719591D01*
X259032Y1720125D01*
X258732Y1721058D01*
X258932Y1721991D01*
X259432Y1722658D01*
X260132Y1723058D01*
X260832D01*
X261532Y1722791D01*
X262132Y1722125D01*
G01X266232Y1723058D02*
Y1717325D01*
X266632Y1716124D01*
X267432Y1715325D01*
X268432Y1715058D01*
X269432Y1715325D01*
X270232Y1716124D01*
X270632Y1717325D01*
Y1723058D01*
G01X274432Y1715058D02*
Y1723058D01*
X276932D01*
X277732Y1722658D01*
X278232Y1722125D01*
X278432Y1721058D01*
X278232Y1719991D01*
X277632Y1719325D01*
X276932Y1718925D01*
X274432D01*
G01X276932D02*
X278432Y1715058D01*
G01X282432D02*
Y1723058D01*
X284932D01*
X285732Y1722658D01*
X286232Y1722125D01*
X286432Y1721058D01*
X286232Y1719991D01*
X285632Y1719325D01*
X284932Y1718925D01*
X282432D01*
G01X284932D02*
X286432Y1715058D01*
G01X292432D02*
X291632Y1715191D01*
X290932Y1715725D01*
X290332Y1716525D01*
X289932Y1717458D01*
X289732Y1718525D01*
Y1719591D01*
X289932Y1720658D01*
X290332Y1721591D01*
X290932Y1722391D01*
X291632Y1722925D01*
X292432Y1723058D01*
X293232Y1722925D01*
X293932Y1722391D01*
X294532Y1721591D01*
X294932Y1720658D01*
X295132Y1719591D01*
Y1718525D01*
X294932Y1717458D01*
X294532Y1716525D01*
X293932Y1715725D01*
X293232Y1715191D01*
X292432Y1715058D01*
G01X298232Y1723058D02*
Y1717325D01*
X298632Y1716124D01*
X299432Y1715325D01*
X300432Y1715058D01*
X301432Y1715325D01*
X302232Y1716124D01*
X302632Y1717325D01*
Y1723058D01*
G01X306132Y1715058D02*
Y1723058D01*
X310732Y1715058D01*
Y1723058D01*
G01X314232Y1715058D02*
Y1723058D01*
X316232D01*
X317032Y1722658D01*
X317632Y1722125D01*
X318132Y1721325D01*
X318532Y1720391D01*
X318632Y1719058D01*
X318532Y1717725D01*
X318132Y1716791D01*
X317632Y1715991D01*
X317032Y1715458D01*
X316232Y1715058D01*
X314232D01*
G01X323232Y1723058D02*
X325632D01*
G01X324432D02*
Y1715058D01*
G01X323232D02*
X325632D01*
G01X330132D02*
Y1723058D01*
X334732Y1715058D01*
Y1723058D01*
G01X341032Y1719058D02*
X343032D01*
Y1716658D01*
X342432Y1715858D01*
X341732Y1715325D01*
X340732Y1715058D01*
X339732Y1715325D01*
X339032Y1715858D01*
X338432Y1716658D01*
X338032Y1717591D01*
X337832Y1718658D01*
Y1719591D01*
X338032Y1720391D01*
X338432Y1721325D01*
X339032Y1722125D01*
X339632Y1722658D01*
X340432Y1723058D01*
X341132D01*
X341932Y1722791D01*
X342532Y1722258D01*
G01X354332Y1716124D02*
X355132Y1715458D01*
X356032Y1715058D01*
X356832D01*
X357632Y1715458D01*
X358232Y1716124D01*
X358532Y1717058D01*
X358332Y1717991D01*
X357832Y1718791D01*
X356932Y1719325D01*
X355732Y1719591D01*
X355032Y1720125D01*
X354732Y1721058D01*
X354932Y1721991D01*
X355432Y1722658D01*
X356132Y1723058D01*
X356832D01*
X357532Y1722791D01*
X358132Y1722125D01*
G01X366632Y1722391D02*
X366032Y1722791D01*
X365332Y1723058D01*
X364532D01*
X363632Y1722658D01*
X362932Y1721991D01*
X362432Y1721191D01*
X362032Y1719858D01*
X361932Y1718658D01*
X362132Y1717458D01*
X362432Y1716658D01*
X363032Y1715858D01*
X363732Y1715325D01*
X364432Y1715058D01*
X365132D01*
X365832Y1715325D01*
X366432Y1715725D01*
X366932Y1716258D01*
G01X370432Y1715058D02*
Y1723058D01*
X372932D01*
X373732Y1722658D01*
X374232Y1722125D01*
X374432Y1721058D01*
X374232Y1719991D01*
X373632Y1719325D01*
X372932Y1718925D01*
X370432D01*
G01X372932D02*
X374432Y1715058D01*
G01X382432D02*
X378432D01*
Y1723058D01*
X382432D01*
G01X380832Y1719191D02*
X378432D01*
G01X385432Y1723058D02*
X386832Y1715058D01*
X388432Y1723058D01*
X390032Y1715058D01*
X391432Y1723058D01*
G01X396432Y1714791D02*
X396232Y1714925D01*
Y1715191D01*
X396432Y1715325D01*
X396632Y1715191D01*
Y1714925D01*
X396432Y1714791D01*
G01X403932Y1712391D02*
X402932Y1713725D01*
X402432Y1715058D01*
Y1720391D01*
X402932Y1721725D01*
X403932Y1723058D01*
G01X410432Y1715058D02*
Y1723058D01*
X412832D01*
X413632Y1722658D01*
X414232Y1721725D01*
X414432Y1720658D01*
X414232Y1719591D01*
X413732Y1718791D01*
X412832Y1718391D01*
X410432D01*
G01X418432Y1723058D02*
Y1715058D01*
X422432D01*
G01X430432D02*
X426432D01*
Y1723058D01*
X430432D01*
G01X428832Y1719191D02*
X426432D01*
G01X433932Y1715058D02*
X436432Y1723058D01*
X438932Y1715058D01*
G01X438032Y1717858D02*
X434832D01*
G01X442332Y1716124D02*
X443132Y1715458D01*
X444032Y1715058D01*
X444832D01*
X445632Y1715458D01*
X446232Y1716124D01*
X446532Y1717058D01*
X446332Y1717991D01*
X445832Y1718791D01*
X444932Y1719325D01*
X443732Y1719591D01*
X443032Y1720125D01*
X442732Y1721058D01*
X442932Y1721991D01*
X443432Y1722658D01*
X444132Y1723058D01*
X444832D01*
X445532Y1722791D01*
X446132Y1722125D01*
G01X454432Y1715058D02*
X450432D01*
Y1723058D01*
X454432D01*
G01X452832Y1719191D02*
X450432D01*
G01X467232Y1723058D02*
X469632D01*
G01X468432D02*
Y1715058D01*
G01X467232D02*
X469632D01*
G01X477032Y1719058D02*
X479032D01*
Y1716658D01*
X478432Y1715858D01*
X477732Y1715325D01*
X476732Y1715058D01*
X475732Y1715325D01*
X475032Y1715858D01*
X474432Y1716658D01*
X474032Y1717591D01*
X473832Y1718658D01*
Y1719591D01*
X474032Y1720391D01*
X474432Y1721325D01*
X475032Y1722125D01*
X475632Y1722658D01*
X476432Y1723058D01*
X477132D01*
X477932Y1722791D01*
X478532Y1722258D01*
G01X482132Y1715058D02*
Y1723058D01*
X486732Y1715058D01*
Y1723058D01*
G01X492432Y1715058D02*
X491632Y1715191D01*
X490932Y1715725D01*
X490332Y1716525D01*
X489932Y1717458D01*
X489732Y1718525D01*
Y1719591D01*
X489932Y1720658D01*
X490332Y1721591D01*
X490932Y1722391D01*
X491632Y1722925D01*
X492432Y1723058D01*
X493232Y1722925D01*
X493932Y1722391D01*
X494532Y1721591D01*
X494932Y1720658D01*
X495132Y1719591D01*
Y1718525D01*
X494932Y1717458D01*
X494532Y1716525D01*
X493932Y1715725D01*
X493232Y1715191D01*
X492432Y1715058D01*
G01X498432D02*
Y1723058D01*
X500932D01*
X501732Y1722658D01*
X502232Y1722125D01*
X502432Y1721058D01*
X502232Y1719991D01*
X501632Y1719325D01*
X500932Y1718925D01*
X498432D01*
G01X500932D02*
X502432Y1715058D01*
G01X510432D02*
X506432D01*
Y1723058D01*
X510432D01*
G01X508832Y1719191D02*
X506432D01*
G01X524432Y1723058D02*
Y1715058D01*
G01X522132Y1723058D02*
X526732D01*
G01X530332Y1715058D02*
Y1723058D01*
G01X534532D02*
Y1715058D01*
G01Y1719058D02*
X530332D01*
G01X539232Y1723058D02*
X541632D01*
G01X540432D02*
Y1715058D01*
G01X539232D02*
X541632D01*
G01X546332Y1716124D02*
X547132Y1715458D01*
X548032Y1715058D01*
X548832D01*
X549632Y1715458D01*
X550232Y1716124D01*
X550532Y1717058D01*
X550332Y1717991D01*
X549832Y1718791D01*
X548932Y1719325D01*
X547732Y1719591D01*
X547032Y1720125D01*
X546732Y1721058D01*
X546932Y1721991D01*
X547432Y1722658D01*
X548132Y1723058D01*
X548832D01*
X549532Y1722791D01*
X550132Y1722125D01*
G01X563232Y1723058D02*
X565632D01*
G01X564432D02*
Y1715058D01*
G01X563232D02*
X565632D01*
G01X570532D02*
Y1723058D01*
X574332D01*
G01X572932Y1719191D02*
X570532D01*
G01X586132Y1715058D02*
Y1723058D01*
X590732Y1715058D01*
Y1723058D01*
G01X596432Y1715058D02*
X595632Y1715191D01*
X594932Y1715725D01*
X594332Y1716525D01*
X593932Y1717458D01*
X593732Y1718525D01*
Y1719591D01*
X593932Y1720658D01*
X594332Y1721591D01*
X594932Y1722391D01*
X595632Y1722925D01*
X596432Y1723058D01*
X597232Y1722925D01*
X597932Y1722391D01*
X598532Y1721591D01*
X598932Y1720658D01*
X599132Y1719591D01*
Y1718525D01*
X598932Y1717458D01*
X598532Y1716525D01*
X597932Y1715725D01*
X597232Y1715191D01*
X596432Y1715058D01*
G01X612432Y1723058D02*
Y1715058D01*
G01X610132Y1723058D02*
X614732D01*
G01X618332Y1715058D02*
Y1723058D01*
G01X622532D02*
Y1715058D01*
G01Y1719058D02*
X618332D01*
G01X627232Y1723058D02*
X629632D01*
G01X628432D02*
Y1715058D01*
G01X627232D02*
X629632D01*
G01X634332Y1716124D02*
X635132Y1715458D01*
X636032Y1715058D01*
X636832D01*
X637632Y1715458D01*
X638232Y1716124D01*
X638532Y1717058D01*
X638332Y1717991D01*
X637832Y1718791D01*
X636932Y1719325D01*
X635732Y1719591D01*
X635032Y1720125D01*
X634732Y1721058D01*
X634932Y1721991D01*
X635432Y1722658D01*
X636132Y1723058D01*
X636832D01*
X637532Y1722791D01*
X638132Y1722125D01*
G01X651232Y1723058D02*
X653632D01*
G01X652432D02*
Y1715058D01*
G01X651232D02*
X653632D01*
G01X660432Y1723058D02*
Y1715058D01*
G01X658132Y1723058D02*
X662732D01*
G01X670432Y1715058D02*
X666432D01*
Y1723058D01*
X670432D01*
G01X668832Y1719191D02*
X666432D01*
G01X673832Y1715058D02*
Y1723058D01*
X676432Y1716391D01*
X679032Y1723058D01*
Y1715058D01*
G01X691232Y1723058D02*
X693632D01*
G01X692432D02*
Y1715058D01*
G01X691232D02*
X693632D01*
G01X698132D02*
Y1723058D01*
X702732Y1715058D01*
Y1723058D01*
G01X717232Y1719325D02*
X717632Y1719725D01*
X717932Y1720391D01*
X718132Y1721325D01*
X717932Y1722125D01*
X717532Y1722658D01*
X716832Y1723058D01*
X714132D01*
Y1715058D01*
X717432D01*
X718132Y1715591D01*
X718532Y1716391D01*
X718732Y1717325D01*
X718532Y1718258D01*
X717932Y1719058D01*
X717232Y1719325D01*
X714132D01*
G01X724432Y1715058D02*
X723632Y1715191D01*
X722932Y1715725D01*
X722332Y1716525D01*
X721932Y1717458D01*
X721732Y1718525D01*
Y1719591D01*
X721932Y1720658D01*
X722332Y1721591D01*
X722932Y1722391D01*
X723632Y1722925D01*
X724432Y1723058D01*
X725232Y1722925D01*
X725932Y1722391D01*
X726532Y1721591D01*
X726932Y1720658D01*
X727132Y1719591D01*
Y1718525D01*
X726932Y1717458D01*
X726532Y1716525D01*
X725932Y1715725D01*
X725232Y1715191D01*
X724432Y1715058D01*
G01X729932D02*
X732432Y1723058D01*
X734932Y1715058D01*
G01X734032Y1717858D02*
X730832D01*
G01X738432Y1715058D02*
Y1723058D01*
X740932D01*
X741732Y1722658D01*
X742232Y1722125D01*
X742432Y1721058D01*
X742232Y1719991D01*
X741632Y1719325D01*
X740932Y1718925D01*
X738432D01*
G01X740932D02*
X742432Y1715058D01*
G01X746232D02*
Y1723058D01*
X748232D01*
X749032Y1722658D01*
X749632Y1722125D01*
X750132Y1721325D01*
X750532Y1720391D01*
X750632Y1719058D01*
X750532Y1717725D01*
X750132Y1716791D01*
X749632Y1715991D01*
X749032Y1715458D01*
X748232Y1715058D01*
X746232D01*
G01X762532D02*
Y1723058D01*
X766332D01*
G01X764932Y1719191D02*
X762532D01*
G01X771232Y1723058D02*
X773632D01*
G01X772432D02*
Y1715058D01*
G01X771232D02*
X773632D01*
G01X778432Y1723058D02*
Y1715058D01*
X782432D01*
G01X790432D02*
X786432D01*
Y1723058D01*
X790432D01*
G01X788832Y1719191D02*
X786432D01*
G01X796932Y1712391D02*
X797932Y1713725D01*
X798432Y1715058D01*
Y1720391D01*
X797932Y1721725D01*
X796932Y1723058D01*
G01X53232Y1734325D02*
X53632Y1734725D01*
X53932Y1735391D01*
X54132Y1736325D01*
X53932Y1737125D01*
X53532Y1737658D01*
X52832Y1738058D01*
X50132D01*
Y1730058D01*
X53432D01*
X54132Y1730591D01*
X54532Y1731391D01*
X54732Y1732325D01*
X54532Y1733258D01*
X53932Y1734058D01*
X53232Y1734325D01*
X50132D01*
G01X60432Y1729791D02*
X60232Y1729925D01*
Y1730191D01*
X60432Y1730325D01*
X60632Y1730191D01*
Y1729925D01*
X60432Y1729791D01*
G01X65932Y1730058D02*
X68432Y1738058D01*
X70932Y1730058D01*
G01X70032Y1732858D02*
X66832D01*
G01X74432Y1738058D02*
Y1730058D01*
X78432D01*
G01X82432Y1738058D02*
Y1730058D01*
X86432D01*
G01X97932Y1738058D02*
X100432Y1730058D01*
X102932Y1738058D01*
G01X107232D02*
X109632D01*
G01X108432D02*
Y1730058D01*
G01X107232D02*
X109632D01*
G01X113932D02*
X116432Y1738058D01*
X118932Y1730058D01*
G01X118032Y1732858D02*
X114832D01*
G01X122332Y1731124D02*
X123132Y1730458D01*
X124032Y1730058D01*
X124832D01*
X125632Y1730458D01*
X126232Y1731124D01*
X126532Y1732058D01*
X126332Y1732991D01*
X125832Y1733791D01*
X124932Y1734325D01*
X123732Y1734591D01*
X123032Y1735125D01*
X122732Y1736058D01*
X122932Y1736991D01*
X123432Y1737658D01*
X124132Y1738058D01*
X124832D01*
X125532Y1737791D01*
X126132Y1737125D01*
G01X138432Y1730058D02*
Y1738058D01*
X140832D01*
X141632Y1737658D01*
X142232Y1736725D01*
X142432Y1735658D01*
X142232Y1734591D01*
X141732Y1733791D01*
X140832Y1733391D01*
X138432D01*
G01X146432Y1738058D02*
Y1730058D01*
X150432D01*
G01X154232Y1738058D02*
Y1732325D01*
X154632Y1731124D01*
X155432Y1730325D01*
X156432Y1730058D01*
X157432Y1730325D01*
X158232Y1731124D01*
X158632Y1732325D01*
Y1738058D01*
G01X165032Y1734058D02*
X167032D01*
Y1731658D01*
X166432Y1730858D01*
X165732Y1730325D01*
X164732Y1730058D01*
X163732Y1730325D01*
X163032Y1730858D01*
X162432Y1731658D01*
X162032Y1732591D01*
X161832Y1733658D01*
Y1734591D01*
X162032Y1735391D01*
X162432Y1736325D01*
X163032Y1737125D01*
X163632Y1737658D01*
X164432Y1738058D01*
X165132D01*
X165932Y1737791D01*
X166532Y1737258D01*
G01X173032Y1734058D02*
X175032D01*
Y1731658D01*
X174432Y1730858D01*
X173732Y1730325D01*
X172732Y1730058D01*
X171732Y1730325D01*
X171032Y1730858D01*
X170432Y1731658D01*
X170032Y1732591D01*
X169832Y1733658D01*
Y1734591D01*
X170032Y1735391D01*
X170432Y1736325D01*
X171032Y1737125D01*
X171632Y1737658D01*
X172432Y1738058D01*
X173132D01*
X173932Y1737791D01*
X174532Y1737258D01*
G01X182432Y1730058D02*
X178432D01*
Y1738058D01*
X182432D01*
G01X180832Y1734191D02*
X178432D01*
G01X186232Y1730058D02*
Y1738058D01*
X188232D01*
X189032Y1737658D01*
X189632Y1737125D01*
X190132Y1736325D01*
X190532Y1735391D01*
X190632Y1734058D01*
X190532Y1732725D01*
X190132Y1731791D01*
X189632Y1730991D01*
X189032Y1730458D01*
X188232Y1730058D01*
X186232D01*
G01X206432D02*
X202432D01*
Y1738058D01*
X206432D01*
G01X204832Y1734191D02*
X202432D01*
G01X210332Y1730058D02*
X214532Y1738058D01*
G01X210332D02*
X214532Y1730058D01*
G01X222632Y1737391D02*
X222032Y1737791D01*
X221332Y1738058D01*
X220532D01*
X219632Y1737658D01*
X218932Y1736991D01*
X218432Y1736191D01*
X218032Y1734858D01*
X217932Y1733658D01*
X218132Y1732458D01*
X218432Y1731658D01*
X219032Y1730858D01*
X219732Y1730325D01*
X220432Y1730058D01*
X221132D01*
X221832Y1730325D01*
X222432Y1730725D01*
X222932Y1731258D01*
G01X230432Y1730058D02*
X226432D01*
Y1738058D01*
X230432D01*
G01X228832Y1734191D02*
X226432D01*
G01X234432Y1730058D02*
Y1738058D01*
X236832D01*
X237632Y1737658D01*
X238232Y1736725D01*
X238432Y1735658D01*
X238232Y1734591D01*
X237732Y1733791D01*
X236832Y1733391D01*
X234432D01*
G01X244432Y1738058D02*
Y1730058D01*
G01X242132Y1738058D02*
X246732D01*
G01X258532Y1730058D02*
Y1738058D01*
X262332D01*
G01X260932Y1734191D02*
X258532D01*
G01X268432Y1730058D02*
X267632Y1730191D01*
X266932Y1730725D01*
X266332Y1731525D01*
X265932Y1732458D01*
X265732Y1733525D01*
Y1734591D01*
X265932Y1735658D01*
X266332Y1736591D01*
X266932Y1737391D01*
X267632Y1737925D01*
X268432Y1738058D01*
X269232Y1737925D01*
X269932Y1737391D01*
X270532Y1736591D01*
X270932Y1735658D01*
X271132Y1734591D01*
Y1733525D01*
X270932Y1732458D01*
X270532Y1731525D01*
X269932Y1730725D01*
X269232Y1730191D01*
X268432Y1730058D01*
G01X274432D02*
Y1738058D01*
X276932D01*
X277732Y1737658D01*
X278232Y1737125D01*
X278432Y1736058D01*
X278232Y1734991D01*
X277632Y1734325D01*
X276932Y1733925D01*
X274432D01*
G01X276932D02*
X278432Y1730058D01*
G01X49932Y1745058D02*
X52432Y1753058D01*
X54932Y1745058D01*
G01X54032Y1747858D02*
X50832D01*
G01X60432Y1744791D02*
X60232Y1744925D01*
Y1745191D01*
X60432Y1745325D01*
X60632Y1745191D01*
Y1744925D01*
X60432Y1744791D01*
G01X65932Y1753058D02*
X68432Y1745058D01*
X70932Y1753058D01*
G01X75232D02*
X77632D01*
G01X76432D02*
Y1745058D01*
G01X75232D02*
X77632D01*
G01X81932D02*
X84432Y1753058D01*
X86932Y1745058D01*
G01X86032Y1747858D02*
X82832D01*
G01X100432Y1753058D02*
Y1745058D01*
G01X98132Y1753058D02*
X102732D01*
G01X110432Y1745058D02*
X106432D01*
Y1753058D01*
X110432D01*
G01X108832Y1749191D02*
X106432D01*
G01X113932Y1745058D02*
X116432Y1753058D01*
X118932Y1745058D01*
G01X118032Y1747858D02*
X114832D01*
G01X122432Y1745058D02*
Y1753058D01*
X124932D01*
X125732Y1752658D01*
X126232Y1752125D01*
X126432Y1751058D01*
X126232Y1749991D01*
X125632Y1749325D01*
X124932Y1748925D01*
X122432D01*
G01X124932D02*
X126432Y1745058D01*
G01X138232D02*
Y1753058D01*
X140232D01*
X141032Y1752658D01*
X141632Y1752125D01*
X142132Y1751325D01*
X142532Y1750391D01*
X142632Y1749058D01*
X142532Y1747725D01*
X142132Y1746791D01*
X141632Y1745991D01*
X141032Y1745458D01*
X140232Y1745058D01*
X138232D01*
G01X146432D02*
Y1753058D01*
X148932D01*
X149732Y1752658D01*
X150232Y1752125D01*
X150432Y1751058D01*
X150232Y1749991D01*
X149632Y1749325D01*
X148932Y1748925D01*
X146432D01*
G01X148932D02*
X150432Y1745058D01*
G01X156432D02*
X155632Y1745191D01*
X154932Y1745725D01*
X154332Y1746525D01*
X153932Y1747458D01*
X153732Y1748525D01*
Y1749591D01*
X153932Y1750658D01*
X154332Y1751591D01*
X154932Y1752391D01*
X155632Y1752925D01*
X156432Y1753058D01*
X157232Y1752925D01*
X157932Y1752391D01*
X158532Y1751591D01*
X158932Y1750658D01*
X159132Y1749591D01*
Y1748525D01*
X158932Y1747458D01*
X158532Y1746525D01*
X157932Y1745725D01*
X157232Y1745191D01*
X156432Y1745058D01*
G01X162432D02*
Y1753058D01*
X164832D01*
X165632Y1752658D01*
X166232Y1751725D01*
X166432Y1750658D01*
X166232Y1749591D01*
X165732Y1748791D01*
X164832Y1748391D01*
X162432D01*
G01X179932Y1742391D02*
X178932Y1743725D01*
X178432Y1745058D01*
Y1750391D01*
X178932Y1751725D01*
X179932Y1753058D01*
G01X186532Y1745058D02*
Y1753058D01*
X190332D01*
G01X188932Y1749191D02*
X186532D01*
G01X196432Y1745058D02*
X195632Y1745191D01*
X194932Y1745725D01*
X194332Y1746525D01*
X193932Y1747458D01*
X193732Y1748525D01*
Y1749591D01*
X193932Y1750658D01*
X194332Y1751591D01*
X194932Y1752391D01*
X195632Y1752925D01*
X196432Y1753058D01*
X197232Y1752925D01*
X197932Y1752391D01*
X198532Y1751591D01*
X198932Y1750658D01*
X199132Y1749591D01*
Y1748525D01*
X198932Y1747458D01*
X198532Y1746525D01*
X197932Y1745725D01*
X197232Y1745191D01*
X196432Y1745058D01*
G01X202432D02*
Y1753058D01*
X204932D01*
X205732Y1752658D01*
X206232Y1752125D01*
X206432Y1751058D01*
X206232Y1749991D01*
X205632Y1749325D01*
X204932Y1748925D01*
X202432D01*
G01X204932D02*
X206432Y1745058D01*
G01X217932D02*
X220432Y1753058D01*
X222932Y1745058D01*
G01X222032Y1747858D02*
X218832D01*
G01X226432Y1753058D02*
Y1745058D01*
X230432D01*
G01X234432Y1753058D02*
Y1745058D01*
X238432D01*
G01X249932Y1753058D02*
X252432Y1745058D01*
X254932Y1753058D01*
G01X259232D02*
X261632D01*
G01X260432D02*
Y1745058D01*
G01X259232D02*
X261632D01*
G01X265932D02*
X268432Y1753058D01*
X270932Y1745058D01*
G01X270032Y1747858D02*
X266832D01*
G01X274332Y1746124D02*
X275132Y1745458D01*
X276032Y1745058D01*
X276832D01*
X277632Y1745458D01*
X278232Y1746124D01*
X278532Y1747058D01*
X278332Y1747991D01*
X277832Y1748791D01*
X276932Y1749325D01*
X275732Y1749591D01*
X275032Y1750125D01*
X274732Y1751058D01*
X274932Y1751991D01*
X275432Y1752658D01*
X276132Y1753058D01*
X276832D01*
X277532Y1752791D01*
X278132Y1752125D01*
G01X289932Y1745058D02*
X292432Y1753058D01*
X294932Y1745058D01*
G01X294032Y1747858D02*
X290832D01*
G01X298132Y1745058D02*
Y1753058D01*
X302732Y1745058D01*
Y1753058D01*
G01X306232Y1745058D02*
Y1753058D01*
X308232D01*
X309032Y1752658D01*
X309632Y1752125D01*
X310132Y1751325D01*
X310532Y1750391D01*
X310632Y1749058D01*
X310532Y1747725D01*
X310132Y1746791D01*
X309632Y1745991D01*
X309032Y1745458D01*
X308232Y1745058D01*
X306232D01*
G01X322432D02*
Y1753058D01*
X324832D01*
X325632Y1752658D01*
X326232Y1751725D01*
X326432Y1750658D01*
X326232Y1749591D01*
X325732Y1748791D01*
X324832Y1748391D01*
X322432D01*
G01X331232Y1753058D02*
X333632D01*
G01X332432D02*
Y1745058D01*
G01X331232D02*
X333632D01*
G01X338132D02*
Y1753058D01*
X342732Y1745058D01*
Y1753058D01*
G01X346332Y1746124D02*
X347132Y1745458D01*
X348032Y1745058D01*
X348832D01*
X349632Y1745458D01*
X350232Y1746124D01*
X350532Y1747058D01*
X350332Y1747991D01*
X349832Y1748791D01*
X348932Y1749325D01*
X347732Y1749591D01*
X347032Y1750125D01*
X346732Y1751058D01*
X346932Y1751991D01*
X347432Y1752658D01*
X348132Y1753058D01*
X348832D01*
X349532Y1752791D01*
X350132Y1752125D01*
G01X356932Y1742391D02*
X357932Y1743725D01*
X358432Y1745058D01*
Y1750391D01*
X357932Y1751725D01*
X356932Y1753058D01*
G01X364432Y1744791D02*
X364232Y1744925D01*
Y1745191D01*
X364432Y1745325D01*
X364632Y1745191D01*
Y1744925D01*
X364432Y1744791D01*
G01X101179Y-82212D02*
X101704Y-81663D01*
X101914Y-81037D01*
X101704Y-80410D01*
X101074Y-79862D01*
X100129Y-79470D01*
X99184Y-79313D01*
X98029D01*
X97084Y-79470D01*
X96244Y-79862D01*
X95824Y-80332D01*
X95614Y-80880D01*
X95824Y-81507D01*
X96244Y-81977D01*
X96874Y-82290D01*
X97714Y-82447D01*
X98449Y-82290D01*
X99184Y-81898D01*
X99604Y-81428D01*
X99709Y-80880D01*
X99499Y-80253D01*
X98974Y-79783D01*
X98029Y-79313D01*
G01X101914Y-74580D02*
X101809Y-74032D01*
X101494Y-73405D01*
X100969Y-73013D01*
X100234Y-72857D01*
X99499Y-73013D01*
X98869Y-73483D01*
X98554Y-74188D01*
Y-74972D01*
X98344Y-75442D01*
X97819Y-75833D01*
X97084Y-75990D01*
X96349Y-75755D01*
X95824Y-75207D01*
X95614Y-74580D01*
X95824Y-73953D01*
X96349Y-73405D01*
X97084Y-73170D01*
X97819Y-73327D01*
X98344Y-73718D01*
X98554Y-74188D01*
Y-74972D01*
X98869Y-75677D01*
X99499Y-76147D01*
X100234Y-76303D01*
X100969Y-76147D01*
X101494Y-75755D01*
X101809Y-75128D01*
X101914Y-74580D01*
G01Y-67340D02*
X95614D01*
X100129Y-70238D01*
Y-66322D01*
G01X102124Y-61980D02*
X102019Y-62137D01*
X101809D01*
X101704Y-61980D01*
X101809Y-61823D01*
X102019D01*
X102124Y-61980D01*
G01X96664Y-57168D02*
X96034Y-56698D01*
X95719Y-56150D01*
X95614Y-55523D01*
X95824Y-54740D01*
X96349Y-54192D01*
X96979Y-54035D01*
X97609Y-54113D01*
X98134Y-54427D01*
X99184Y-55993D01*
X99919Y-56698D01*
X100969Y-57168D01*
X101914Y-57325D01*
Y-54035D01*
G01X99289Y-50868D02*
X98554Y-50320D01*
X98134Y-49850D01*
X97924Y-49223D01*
X98134Y-48675D01*
X98554Y-48283D01*
X99184Y-47970D01*
X99919Y-47892D01*
X100549Y-47970D01*
X101179Y-48283D01*
X101704Y-48753D01*
X101914Y-49302D01*
X101704Y-49928D01*
X101074Y-50477D01*
X100129Y-50790D01*
X99079Y-50868D01*
X97714Y-50712D01*
X96979Y-50477D01*
X96244Y-50085D01*
X95719Y-49537D01*
X95614Y-48988D01*
X95824Y-48440D01*
X96349Y-48048D01*
G01X113117Y-81833D02*
X106817D01*
X108077Y-82773D01*
G01X113117D02*
Y-80893D01*
G01X106817Y-75533D02*
X107027Y-76160D01*
X107552Y-76630D01*
X108182Y-76943D01*
X109022Y-77178D01*
X109967Y-77256D01*
X110912Y-77178D01*
X111752Y-76943D01*
X112382Y-76630D01*
X112907Y-76160D01*
X113117Y-75533D01*
X112907Y-74906D01*
X112382Y-74436D01*
X111752Y-74123D01*
X110912Y-73888D01*
X109967Y-73810D01*
X109022Y-73888D01*
X108182Y-74123D01*
X107552Y-74436D01*
X107027Y-74906D01*
X106817Y-75533D01*
G01X107867Y-70721D02*
X107237Y-70251D01*
X106922Y-69703D01*
X106817Y-69076D01*
X107027Y-68293D01*
X107552Y-67745D01*
X108182Y-67588D01*
X108812Y-67666D01*
X109337Y-67980D01*
X110387Y-69546D01*
X111122Y-70251D01*
X112172Y-70721D01*
X113117Y-70878D01*
Y-67588D01*
G01X111857Y-64656D02*
X112592Y-64186D01*
X113012Y-63560D01*
X113117Y-62855D01*
X113012Y-62228D01*
X112487Y-61601D01*
X111857Y-61210D01*
X111227Y-61131D01*
X110492Y-61288D01*
X109967Y-61836D01*
X109757Y-62385D01*
Y-63090D01*
G01Y-62385D02*
X109442Y-61915D01*
X108917Y-61523D01*
X108287Y-61366D01*
X107657Y-61523D01*
X107132Y-61915D01*
X106817Y-62620D01*
X106922Y-63325D01*
X107342Y-64030D01*
G01X113327Y-56633D02*
X113222Y-56790D01*
X113012D01*
X112907Y-56633D01*
X113012Y-56476D01*
X113222D01*
X113327Y-56633D01*
G01X110492Y-51821D02*
X109757Y-51273D01*
X109337Y-50803D01*
X109127Y-50176D01*
X109337Y-49628D01*
X109757Y-49236D01*
X110387Y-48923D01*
X111122Y-48845D01*
X111752Y-48923D01*
X112382Y-49236D01*
X112907Y-49706D01*
X113117Y-50255D01*
X112907Y-50881D01*
X112277Y-51430D01*
X111332Y-51743D01*
X110282Y-51821D01*
X108917Y-51665D01*
X108182Y-51430D01*
X107447Y-51038D01*
X106922Y-50490D01*
X106817Y-49941D01*
X107027Y-49393D01*
X107552Y-49001D01*
G01X107867Y-45521D02*
X107237Y-45051D01*
X106922Y-44503D01*
X106817Y-43876D01*
X107027Y-43093D01*
X107552Y-42545D01*
X108182Y-42388D01*
X108812Y-42466D01*
X109337Y-42780D01*
X110387Y-44346D01*
X111122Y-45051D01*
X112172Y-45521D01*
X113117Y-45678D01*
Y-42388D01*
G01X232493Y-186364D02*
Y-194364D01*
X236493D01*
G01X244293D02*
Y-189031D01*
G01Y-189964D02*
X243893Y-189431D01*
X243293Y-189164D01*
X242593Y-189031D01*
X241893Y-189297D01*
X241293Y-189831D01*
X240893Y-190631D01*
X240693Y-191697D01*
X240893Y-192764D01*
X241293Y-193564D01*
X241893Y-194097D01*
X242593Y-194364D01*
X243293Y-194231D01*
X243893Y-193831D01*
X244293Y-193298D01*
G01X248393Y-196764D02*
X248993Y-197031D01*
X249793Y-196764D01*
X250293Y-196231D01*
X250693Y-195564D01*
X251293Y-193431D01*
X252593Y-189031D01*
G01X249393D02*
X251293Y-193431D01*
G01X256993Y-190764D02*
X260193D01*
X259893Y-189831D01*
X259393Y-189297D01*
X258693Y-189031D01*
X257993Y-189164D01*
X257393Y-189564D01*
X256993Y-190497D01*
X256793Y-191298D01*
Y-192097D01*
X256993Y-192897D01*
X257493Y-193697D01*
X258093Y-194231D01*
X258793Y-194364D01*
X259493Y-194097D01*
X260193Y-193298D01*
G01X265093Y-194364D02*
Y-189031D01*
G01Y-190097D02*
X265593Y-189564D01*
X266093Y-189164D01*
X266793Y-189031D01*
X267293Y-189164D01*
X267893Y-189564D01*
G01X254793Y-236364D02*
X257193D01*
G01X255993D02*
Y-244364D01*
G01X254793D02*
X257193D01*
G01X262593D02*
Y-239031D01*
G01Y-240097D02*
X263093Y-239564D01*
X263593Y-239164D01*
X264293Y-239031D01*
X264793Y-239164D01*
X265393Y-239564D01*
G01X270493Y-240764D02*
X273693D01*
X273393Y-239831D01*
X272893Y-239297D01*
X272193Y-239031D01*
X271493Y-239164D01*
X270893Y-239564D01*
X270493Y-240497D01*
X270293Y-241298D01*
Y-242097D01*
X270493Y-242897D01*
X270993Y-243697D01*
X271593Y-244231D01*
X272293Y-244364D01*
X272993Y-244097D01*
X273693Y-243298D01*
G01X278293Y-244364D02*
Y-239031D01*
G01Y-240364D02*
X278693Y-239697D01*
X279293Y-239164D01*
X280093Y-239031D01*
X280793Y-239164D01*
X281393Y-239697D01*
X281693Y-240631D01*
Y-244364D01*
G01X286493Y-240764D02*
X289693D01*
X289393Y-239831D01*
X288893Y-239297D01*
X288193Y-239031D01*
X287493Y-239164D01*
X286893Y-239564D01*
X286493Y-240497D01*
X286293Y-241298D01*
Y-242097D01*
X286493Y-242897D01*
X286993Y-243697D01*
X287593Y-244231D01*
X288293Y-244364D01*
X288993Y-244097D01*
X289693Y-243298D01*
G01X256593Y-219364D02*
Y-211364D01*
X260393D01*
G01X258993Y-215231D02*
X256593D01*
G01X263993Y-219364D02*
X266493Y-211364D01*
X268993Y-219364D01*
G01X268093Y-216564D02*
X264893D01*
G01X275293Y-215097D02*
X275693Y-214697D01*
X275993Y-214031D01*
X276193Y-213097D01*
X275993Y-212297D01*
X275593Y-211764D01*
X274893Y-211364D01*
X272193D01*
Y-219364D01*
X275493D01*
X276193Y-218831D01*
X276593Y-218031D01*
X276793Y-217097D01*
X276593Y-216164D01*
X275993Y-215364D01*
X275293Y-215097D01*
X272193D01*
G01X287332Y1731124D02*
X288132Y1730458D01*
X289032Y1730058D01*
X289832D01*
X290632Y1730458D01*
X291232Y1731124D01*
X291532Y1732058D01*
X291332Y1732991D01*
X290832Y1733791D01*
X289932Y1734325D01*
X288732Y1734591D01*
X288032Y1735125D01*
X287732Y1736058D01*
X287932Y1736991D01*
X288432Y1737658D01*
X289132Y1738058D01*
X289832D01*
X290532Y1737791D01*
X291132Y1737125D01*
G01X297432Y1730058D02*
X296632Y1730191D01*
X295932Y1730725D01*
X295332Y1731525D01*
X294932Y1732458D01*
X294732Y1733525D01*
Y1734591D01*
X294932Y1735658D01*
X295332Y1736591D01*
X295932Y1737391D01*
X296632Y1737925D01*
X297432Y1738058D01*
X298232Y1737925D01*
X298932Y1737391D01*
X299532Y1736591D01*
X299932Y1735658D01*
X300132Y1734591D01*
Y1733525D01*
X299932Y1732458D01*
X299532Y1731525D01*
X298932Y1730725D01*
X298232Y1730191D01*
X297432Y1730058D01*
G01X303432Y1738058D02*
Y1730058D01*
X307432D01*
G01X311232D02*
Y1738058D01*
X313232D01*
X314032Y1737658D01*
X314632Y1737125D01*
X315132Y1736325D01*
X315532Y1735391D01*
X315632Y1734058D01*
X315532Y1732725D01*
X315132Y1731791D01*
X314632Y1730991D01*
X314032Y1730458D01*
X313232Y1730058D01*
X311232D01*
G01X323432D02*
X319432D01*
Y1738058D01*
X323432D01*
G01X321832Y1734191D02*
X319432D01*
G01X327432Y1730058D02*
Y1738058D01*
X329932D01*
X330732Y1737658D01*
X331232Y1737125D01*
X331432Y1736058D01*
X331232Y1734991D01*
X330632Y1734325D01*
X329932Y1733925D01*
X327432D01*
G01X329932D02*
X331432Y1730058D01*
G01X334832D02*
Y1738058D01*
X337432Y1731391D01*
X340032Y1738058D01*
Y1730058D01*
G01X342932D02*
X345432Y1738058D01*
X347932Y1730058D01*
G01X347032Y1732858D02*
X343832D01*
G01X351332Y1731124D02*
X352132Y1730458D01*
X353032Y1730058D01*
X353832D01*
X354632Y1730458D01*
X355232Y1731124D01*
X355532Y1732058D01*
X355332Y1732991D01*
X354832Y1733791D01*
X353932Y1734325D01*
X352732Y1734591D01*
X352032Y1735125D01*
X351732Y1736058D01*
X351932Y1736991D01*
X352432Y1737658D01*
X353132Y1738058D01*
X353832D01*
X354532Y1737791D01*
X355132Y1737125D01*
G01X359232Y1730058D02*
Y1738058D01*
G01X363032D02*
X359232Y1733124D01*
G01X363632Y1730058D02*
X360932Y1735391D01*
G01X377432Y1730058D02*
X376632Y1730191D01*
X375932Y1730725D01*
X375332Y1731525D01*
X374932Y1732458D01*
X374732Y1733525D01*
Y1734591D01*
X374932Y1735658D01*
X375332Y1736591D01*
X375932Y1737391D01*
X376632Y1737925D01*
X377432Y1738058D01*
X378232Y1737925D01*
X378932Y1737391D01*
X379532Y1736591D01*
X379932Y1735658D01*
X380132Y1734591D01*
Y1733525D01*
X379932Y1732458D01*
X379532Y1731525D01*
X378932Y1730725D01*
X378232Y1730191D01*
X377432Y1730058D01*
G01X383432D02*
Y1738058D01*
X385832D01*
X386632Y1737658D01*
X387232Y1736725D01*
X387432Y1735658D01*
X387232Y1734591D01*
X386732Y1733791D01*
X385832Y1733391D01*
X383432D01*
G01X395432Y1730058D02*
X391432D01*
Y1738058D01*
X395432D01*
G01X393832Y1734191D02*
X391432D01*
G01X399132Y1730058D02*
Y1738058D01*
X403732Y1730058D01*
Y1738058D01*
G01X417432Y1730058D02*
X416632Y1730191D01*
X415932Y1730725D01*
X415332Y1731525D01*
X414932Y1732458D01*
X414732Y1733525D01*
Y1734591D01*
X414932Y1735658D01*
X415332Y1736591D01*
X415932Y1737391D01*
X416632Y1737925D01*
X417432Y1738058D01*
X418232Y1737925D01*
X418932Y1737391D01*
X419532Y1736591D01*
X419932Y1735658D01*
X420132Y1734591D01*
Y1733525D01*
X419932Y1732458D01*
X419532Y1731525D01*
X418932Y1730725D01*
X418232Y1730191D01*
X417432Y1730058D01*
G01X423132D02*
Y1738058D01*
X427732Y1730058D01*
Y1738058D01*
G01X442232Y1734325D02*
X442632Y1734725D01*
X442932Y1735391D01*
X443132Y1736325D01*
X442932Y1737125D01*
X442532Y1737658D01*
X441832Y1738058D01*
X439132D01*
Y1730058D01*
X442432D01*
X443132Y1730591D01*
X443532Y1731391D01*
X443732Y1732325D01*
X443532Y1733258D01*
X442932Y1734058D01*
X442232Y1734325D01*
X439132D01*
G01X449432Y1730058D02*
X448632Y1730191D01*
X447932Y1730725D01*
X447332Y1731525D01*
X446932Y1732458D01*
X446732Y1733525D01*
Y1734591D01*
X446932Y1735658D01*
X447332Y1736591D01*
X447932Y1737391D01*
X448632Y1737925D01*
X449432Y1738058D01*
X450232Y1737925D01*
X450932Y1737391D01*
X451532Y1736591D01*
X451932Y1735658D01*
X452132Y1734591D01*
Y1733525D01*
X451932Y1732458D01*
X451532Y1731525D01*
X450932Y1730725D01*
X450232Y1730191D01*
X449432Y1730058D01*
G01X457432Y1738058D02*
Y1730058D01*
G01X455132Y1738058D02*
X459732D01*
G01X463332Y1730058D02*
Y1738058D01*
G01X467532D02*
Y1730058D01*
G01Y1734058D02*
X463332D01*
G01X479332Y1731124D02*
X480132Y1730458D01*
X481032Y1730058D01*
X481832D01*
X482632Y1730458D01*
X483232Y1731124D01*
X483532Y1732058D01*
X483332Y1732991D01*
X482832Y1733791D01*
X481932Y1734325D01*
X480732Y1734591D01*
X480032Y1735125D01*
X479732Y1736058D01*
X479932Y1736991D01*
X480432Y1737658D01*
X481132Y1738058D01*
X481832D01*
X482532Y1737791D01*
X483132Y1737125D01*
G01X488232Y1738058D02*
X490632D01*
G01X489432D02*
Y1730058D01*
G01X488232D02*
X490632D01*
G01X495232D02*
Y1738058D01*
X497232D01*
X498032Y1737658D01*
X498632Y1737125D01*
X499132Y1736325D01*
X499532Y1735391D01*
X499632Y1734058D01*
X499532Y1732725D01*
X499132Y1731791D01*
X498632Y1730991D01*
X498032Y1730458D01*
X497232Y1730058D01*
X495232D01*
G01X507432D02*
X503432D01*
Y1738058D01*
X507432D01*
G01X505832Y1734191D02*
X503432D01*
G01X513432Y1729791D02*
X513232Y1729925D01*
Y1730191D01*
X513432Y1730325D01*
X513632Y1730191D01*
Y1729925D01*
X513432Y1729791D01*
G01X330860Y850805D02*
X331595Y851275D01*
X332015Y851901D01*
X332120Y852606D01*
X332015Y853233D01*
X331490Y853860D01*
X330860Y854251D01*
X330230Y854330D01*
X329495Y854173D01*
X328970Y853625D01*
X328760Y853076D01*
Y852371D01*
G01Y853076D02*
X328445Y853546D01*
X327920Y853938D01*
X327290Y854095D01*
X326660Y853938D01*
X326135Y853546D01*
X325820Y852841D01*
X325925Y852136D01*
X326345Y851431D01*
G01X326870Y857340D02*
X326240Y857810D01*
X325925Y858358D01*
X325820Y858985D01*
X326030Y859768D01*
X326555Y860316D01*
X327185Y860473D01*
X327815Y860395D01*
X328340Y860081D01*
X329390Y858515D01*
X330125Y857810D01*
X331175Y857340D01*
X332120Y857183D01*
Y860473D01*
G01Y865128D02*
X332015Y865676D01*
X331700Y866303D01*
X331175Y866695D01*
X330440Y866851D01*
X329705Y866695D01*
X329075Y866225D01*
X328760Y865520D01*
Y864736D01*
X328550Y864266D01*
X328025Y863875D01*
X327290Y863718D01*
X326555Y863953D01*
X326030Y864501D01*
X325820Y865128D01*
X326030Y865755D01*
X326555Y866303D01*
X327290Y866538D01*
X328025Y866381D01*
X328550Y865990D01*
X328760Y865520D01*
Y864736D01*
X329075Y864031D01*
X329705Y863561D01*
X330440Y863405D01*
X331175Y863561D01*
X331700Y863953D01*
X332015Y864580D01*
X332120Y865128D01*
G01X331385Y870096D02*
X331910Y870645D01*
X332120Y871271D01*
X331910Y871898D01*
X331280Y872446D01*
X330335Y872838D01*
X329390Y872995D01*
X328235D01*
X327290Y872838D01*
X326450Y872446D01*
X326030Y871976D01*
X325820Y871428D01*
X326030Y870801D01*
X326450Y870331D01*
X327080Y870018D01*
X327920Y869861D01*
X328655Y870018D01*
X329390Y870410D01*
X329810Y870880D01*
X329915Y871428D01*
X329705Y872055D01*
X329180Y872525D01*
X328235Y872995D01*
G01X332330Y877728D02*
X332225Y877571D01*
X332015D01*
X331910Y877728D01*
X332015Y877885D01*
X332225D01*
X332330Y877728D01*
G01X332120Y883871D02*
X330755Y884028D01*
X329600Y884263D01*
X328550Y884576D01*
X327395Y884968D01*
X325820Y885595D01*
Y882461D01*
G01Y890328D02*
X326030Y889701D01*
X326555Y889231D01*
X327185Y888918D01*
X328025Y888683D01*
X328970Y888605D01*
X329915Y888683D01*
X330755Y888918D01*
X331385Y889231D01*
X331910Y889701D01*
X332120Y890328D01*
X331910Y890955D01*
X331385Y891425D01*
X330755Y891738D01*
X329915Y891973D01*
X328970Y892051D01*
X328025Y891973D01*
X327185Y891738D01*
X326555Y891425D01*
X326030Y890955D01*
X325820Y890328D01*
G01X338321Y852299D02*
X339056Y852769D01*
X339476Y853395D01*
X339581Y854100D01*
X339476Y854727D01*
X338951Y855354D01*
X338321Y855745D01*
X337691Y855824D01*
X336956Y855667D01*
X336431Y855119D01*
X336221Y854570D01*
Y853865D01*
G01Y854570D02*
X335906Y855040D01*
X335381Y855432D01*
X334751Y855589D01*
X334121Y855432D01*
X333596Y855040D01*
X333281Y854335D01*
X333386Y853630D01*
X333806Y852925D01*
G01X338321Y858599D02*
X339056Y859069D01*
X339476Y859695D01*
X339581Y860400D01*
X339476Y861027D01*
X338951Y861654D01*
X338321Y862045D01*
X337691Y862124D01*
X336956Y861967D01*
X336431Y861419D01*
X336221Y860870D01*
Y860165D01*
G01Y860870D02*
X335906Y861340D01*
X335381Y861732D01*
X334751Y861889D01*
X334121Y861732D01*
X333596Y861340D01*
X333281Y860635D01*
X333386Y859930D01*
X333806Y859225D01*
G01X336956Y865134D02*
X336221Y865682D01*
X335801Y866152D01*
X335591Y866779D01*
X335801Y867327D01*
X336221Y867719D01*
X336851Y868032D01*
X337586Y868110D01*
X338216Y868032D01*
X338846Y867719D01*
X339371Y867249D01*
X339581Y866700D01*
X339371Y866074D01*
X338741Y865525D01*
X337796Y865212D01*
X336746Y865134D01*
X335381Y865290D01*
X334646Y865525D01*
X333911Y865917D01*
X333386Y866465D01*
X333281Y867014D01*
X333491Y867562D01*
X334016Y867954D01*
G01X339581Y873862D02*
X333281D01*
X337796Y870964D01*
Y874880D01*
G01X339791Y879222D02*
X339686Y879065D01*
X339476D01*
X339371Y879222D01*
X339476Y879379D01*
X339686D01*
X339791Y879222D01*
G01X338321Y883799D02*
X339056Y884269D01*
X339476Y884895D01*
X339581Y885600D01*
X339476Y886227D01*
X338951Y886854D01*
X338321Y887245D01*
X337691Y887324D01*
X336956Y887167D01*
X336431Y886619D01*
X336221Y886070D01*
Y885365D01*
G01Y886070D02*
X335906Y886540D01*
X335381Y886932D01*
X334751Y887089D01*
X334121Y886932D01*
X333596Y886540D01*
X333281Y885835D01*
X333386Y885130D01*
X333806Y884425D01*
G01X339581Y891822D02*
X333281D01*
X334541Y890882D01*
G01X339581D02*
Y892762D01*
G01X344507Y927967D02*
X344664Y929332D01*
X344899Y930487D01*
X345212Y931537D01*
X345604Y932692D01*
X346231Y934267D01*
X343097D01*
G01X350964Y927967D02*
X351512Y928072D01*
X352139Y928387D01*
X352531Y928912D01*
X352687Y929647D01*
X352531Y930382D01*
X352061Y931012D01*
X351356Y931327D01*
X350572D01*
X350102Y931537D01*
X349711Y932062D01*
X349554Y932797D01*
X349789Y933532D01*
X350337Y934057D01*
X350964Y934267D01*
X351591Y934057D01*
X352139Y933532D01*
X352374Y932797D01*
X352217Y932062D01*
X351826Y931537D01*
X351356Y931327D01*
X350572D01*
X349867Y931012D01*
X349397Y930382D01*
X349241Y929647D01*
X349397Y928912D01*
X349789Y928387D01*
X350416Y928072D01*
X350964Y927967D01*
G01X357107D02*
X357264Y929332D01*
X357499Y930487D01*
X357812Y931537D01*
X358204Y932692D01*
X358831Y934267D01*
X355697D01*
G01X364504Y927967D02*
Y934267D01*
X361606Y929752D01*
X365522D01*
G01X369864Y927757D02*
X369707Y927862D01*
Y928072D01*
X369864Y928177D01*
X370021Y928072D01*
Y927862D01*
X369864Y927757D01*
G01X376164Y934267D02*
X375537Y934057D01*
X375067Y933532D01*
X374754Y932902D01*
X374519Y932062D01*
X374441Y931117D01*
X374519Y930172D01*
X374754Y929332D01*
X375067Y928702D01*
X375537Y928177D01*
X376164Y927967D01*
X376791Y928177D01*
X377261Y928702D01*
X377574Y929332D01*
X377809Y930172D01*
X377887Y931117D01*
X377809Y932062D01*
X377574Y932902D01*
X377261Y933532D01*
X376791Y934057D01*
X376164Y934267D01*
G01X380976Y933217D02*
X381446Y933847D01*
X381994Y934162D01*
X382621Y934267D01*
X383404Y934057D01*
X383952Y933532D01*
X384109Y932902D01*
X384031Y932272D01*
X383717Y931747D01*
X382151Y930697D01*
X381446Y929962D01*
X380976Y928912D01*
X380819Y927967D01*
X384109D01*
G01X359093Y-237697D02*
X359693Y-236897D01*
X360393Y-236497D01*
X361193Y-236364D01*
X362193Y-236631D01*
X362893Y-237297D01*
X363093Y-238097D01*
X362993Y-238898D01*
X362593Y-239564D01*
X360593Y-240897D01*
X359693Y-241831D01*
X359093Y-243164D01*
X358893Y-244364D01*
X363093D01*
G01X368993Y-236364D02*
X368193Y-236631D01*
X367593Y-237297D01*
X367193Y-238097D01*
X366893Y-239164D01*
X366793Y-240364D01*
X366893Y-241564D01*
X367193Y-242631D01*
X367593Y-243431D01*
X368193Y-244097D01*
X368993Y-244364D01*
X369793Y-244097D01*
X370393Y-243431D01*
X370793Y-242631D01*
X371093Y-241564D01*
X371193Y-240364D01*
X371093Y-239164D01*
X370793Y-238097D01*
X370393Y-237297D01*
X369793Y-236631D01*
X368993Y-236364D01*
G01X376993Y-244364D02*
Y-236364D01*
X375793Y-237964D01*
G01Y-244364D02*
X378193D01*
G01X383093Y-237697D02*
X383693Y-236897D01*
X384393Y-236497D01*
X385193Y-236364D01*
X386193Y-236631D01*
X386893Y-237297D01*
X387093Y-238097D01*
X386993Y-238898D01*
X386593Y-239564D01*
X384593Y-240897D01*
X383693Y-241831D01*
X383093Y-243164D01*
X382893Y-244364D01*
X387093D01*
G01X391193Y-244631D02*
X394793Y-236364D01*
G01X400993Y-244364D02*
Y-236364D01*
X399793Y-237964D01*
G01Y-244364D02*
X402193D01*
G01X408993Y-236364D02*
X408193Y-236631D01*
X407593Y-237297D01*
X407193Y-238097D01*
X406893Y-239164D01*
X406793Y-240364D01*
X406893Y-241564D01*
X407193Y-242631D01*
X407593Y-243431D01*
X408193Y-244097D01*
X408993Y-244364D01*
X409793Y-244097D01*
X410393Y-243431D01*
X410793Y-242631D01*
X411093Y-241564D01*
X411193Y-240364D01*
X411093Y-239164D01*
X410793Y-238097D01*
X410393Y-237297D01*
X409793Y-236631D01*
X408993Y-236364D01*
G01X415193Y-244631D02*
X418793Y-236364D01*
G01X422793Y-242764D02*
X423393Y-243697D01*
X424193Y-244231D01*
X425093Y-244364D01*
X425893Y-244231D01*
X426693Y-243564D01*
X427193Y-242764D01*
X427293Y-241964D01*
X427093Y-241031D01*
X426393Y-240364D01*
X425693Y-240097D01*
X424793D01*
G01X425693D02*
X426293Y-239697D01*
X426793Y-239031D01*
X426993Y-238231D01*
X426793Y-237431D01*
X426293Y-236764D01*
X425393Y-236364D01*
X424493Y-236497D01*
X423593Y-237031D01*
G01X432993Y-244364D02*
Y-236364D01*
X431793Y-237964D01*
G01Y-244364D02*
X434193D01*
G01X358793Y-219364D02*
Y-211364D01*
X360793D01*
X361593Y-211764D01*
X362193Y-212297D01*
X362693Y-213097D01*
X363093Y-214031D01*
X363193Y-215364D01*
X363093Y-216697D01*
X362693Y-217631D01*
X362193Y-218431D01*
X361593Y-218964D01*
X360793Y-219364D01*
X358793D01*
G01X366493D02*
X368993Y-211364D01*
X371493Y-219364D01*
G01X370593Y-216564D02*
X367393D01*
G01X376993Y-211364D02*
Y-219364D01*
G01X374693Y-211364D02*
X379293D01*
G01X383093Y-216031D02*
X383793Y-215097D01*
X384393Y-214564D01*
X385193Y-214297D01*
X385893Y-214564D01*
X386393Y-215097D01*
X386793Y-215897D01*
X386893Y-216831D01*
X386793Y-217631D01*
X386393Y-218431D01*
X385793Y-219097D01*
X385093Y-219364D01*
X384293Y-219097D01*
X383593Y-218298D01*
X383193Y-217097D01*
X383093Y-215764D01*
X383293Y-214031D01*
X383593Y-213097D01*
X384093Y-212164D01*
X384793Y-211497D01*
X385493Y-211364D01*
X386193Y-211631D01*
X386693Y-212297D01*
G01X390393Y-219364D02*
Y-211364D01*
X392993Y-218031D01*
X395593Y-211364D01*
Y-219364D01*
G01X400993Y-211364D02*
Y-219364D01*
G01X398693Y-211364D02*
X403293D01*
G01X406893Y-219364D02*
Y-211364D01*
G01X411093D02*
Y-219364D01*
G01Y-215364D02*
X406893D01*
G01X414793Y-217764D02*
X415393Y-218697D01*
X416193Y-219231D01*
X417093Y-219364D01*
X417893Y-219231D01*
X418693Y-218564D01*
X419193Y-217764D01*
X419293Y-216964D01*
X419093Y-216031D01*
X418393Y-215364D01*
X417693Y-215097D01*
X416793D01*
G01X417693D02*
X418293Y-214697D01*
X418793Y-214031D01*
X418993Y-213231D01*
X418793Y-212431D01*
X418293Y-211764D01*
X417393Y-211364D01*
X416493Y-211497D01*
X415593Y-212031D01*
G01X422493Y-219364D02*
X424993Y-211364D01*
X427493Y-219364D01*
G01X426593Y-216564D02*
X423393D01*
G01X430793Y-219364D02*
Y-211364D01*
X432793D01*
X433593Y-211764D01*
X434193Y-212297D01*
X434693Y-213097D01*
X435093Y-214031D01*
X435193Y-215364D01*
X435093Y-216697D01*
X434693Y-217631D01*
X434193Y-218431D01*
X433593Y-218964D01*
X432793Y-219364D01*
X430793D01*
G01X440993Y-211364D02*
X440193Y-211631D01*
X439593Y-212297D01*
X439193Y-213097D01*
X438893Y-214164D01*
X438793Y-215364D01*
X438893Y-216564D01*
X439193Y-217631D01*
X439593Y-218431D01*
X440193Y-219097D01*
X440993Y-219364D01*
X441793Y-219097D01*
X442393Y-218431D01*
X442793Y-217631D01*
X443093Y-216564D01*
X443193Y-215364D01*
X443093Y-214164D01*
X442793Y-213097D01*
X442393Y-212297D01*
X441793Y-211631D01*
X440993Y-211364D01*
G01X380993Y-186364D02*
Y-194364D01*
G01X378693Y-186364D02*
X383293D01*
G01X387093Y-191031D02*
X387793Y-190097D01*
X388393Y-189564D01*
X389193Y-189297D01*
X389893Y-189564D01*
X390393Y-190097D01*
X390793Y-190897D01*
X390893Y-191831D01*
X390793Y-192631D01*
X390393Y-193431D01*
X389793Y-194097D01*
X389093Y-194364D01*
X388293Y-194097D01*
X387593Y-193298D01*
X387193Y-192097D01*
X387093Y-190764D01*
X387293Y-189031D01*
X387593Y-188097D01*
X388093Y-187164D01*
X388793Y-186497D01*
X389493Y-186364D01*
X390193Y-186631D01*
X390693Y-187297D01*
G01X394393Y-194364D02*
Y-186364D01*
X396993Y-193031D01*
X399593Y-186364D01*
Y-194364D01*
G01X401993Y-197031D02*
X407993D01*
G01X415193Y-187031D02*
X414593Y-186631D01*
X413893Y-186364D01*
X413093D01*
X412193Y-186764D01*
X411493Y-187431D01*
X410993Y-188231D01*
X410593Y-189564D01*
X410493Y-190764D01*
X410693Y-191964D01*
X410993Y-192764D01*
X411593Y-193564D01*
X412293Y-194097D01*
X412993Y-194364D01*
X413693D01*
X414393Y-194097D01*
X414993Y-193697D01*
X415493Y-193164D01*
G01X418393Y-194364D02*
Y-186364D01*
X420993Y-193031D01*
X423593Y-186364D01*
Y-194364D01*
G01X425993Y-197031D02*
X431993D01*
G01X434793Y-194364D02*
Y-186364D01*
X436793D01*
X437593Y-186764D01*
X438193Y-187297D01*
X438693Y-188097D01*
X439093Y-189031D01*
X439193Y-190364D01*
X439093Y-191697D01*
X438693Y-192631D01*
X438193Y-193431D01*
X437593Y-193964D01*
X436793Y-194364D01*
X434793D01*
G01X382430Y853332D02*
X383165Y853802D01*
X383585Y854428D01*
X383690Y855133D01*
X383585Y855760D01*
X383060Y856387D01*
X382430Y856778D01*
X381800Y856857D01*
X381065Y856700D01*
X380540Y856152D01*
X380330Y855603D01*
Y854898D01*
G01Y855603D02*
X380015Y856073D01*
X379490Y856465D01*
X378860Y856622D01*
X378230Y856465D01*
X377705Y856073D01*
X377390Y855368D01*
X377495Y854663D01*
X377915Y853958D01*
G01X383690Y861355D02*
X383585Y861903D01*
X383270Y862530D01*
X382745Y862922D01*
X382010Y863078D01*
X381275Y862922D01*
X380645Y862452D01*
X380330Y861747D01*
Y860963D01*
X380120Y860493D01*
X379595Y860102D01*
X378860Y859945D01*
X378125Y860180D01*
X377600Y860728D01*
X377390Y861355D01*
X377600Y861982D01*
X378125Y862530D01*
X378860Y862765D01*
X379595Y862608D01*
X380120Y862217D01*
X380330Y861747D01*
Y860963D01*
X380645Y860258D01*
X381275Y859788D01*
X382010Y859632D01*
X382745Y859788D01*
X383270Y860180D01*
X383585Y860807D01*
X383690Y861355D01*
G01X377390Y867655D02*
X377600Y867028D01*
X378125Y866558D01*
X378755Y866245D01*
X379595Y866010D01*
X380540Y865932D01*
X381485Y866010D01*
X382325Y866245D01*
X382955Y866558D01*
X383480Y867028D01*
X383690Y867655D01*
X383480Y868282D01*
X382955Y868752D01*
X382325Y869065D01*
X381485Y869300D01*
X380540Y869378D01*
X379595Y869300D01*
X378755Y869065D01*
X378125Y868752D01*
X377600Y868282D01*
X377390Y867655D01*
G01X382745Y872232D02*
X383270Y872702D01*
X383585Y873250D01*
X383690Y873955D01*
X383480Y874660D01*
X383060Y875208D01*
X382325Y875600D01*
X381485Y875678D01*
X380645Y875522D01*
X380120Y875130D01*
X379700Y874582D01*
X379595Y874033D01*
X379700Y873485D01*
X380120Y872780D01*
X377390Y873015D01*
Y875130D01*
G01X383900Y880255D02*
X383795Y880098D01*
X383585D01*
X383480Y880255D01*
X383585Y880412D01*
X383795D01*
X383900Y880255D01*
G01X383690Y887495D02*
X377390D01*
X381905Y884597D01*
Y888513D01*
G01X377390Y892855D02*
X377600Y892228D01*
X378125Y891758D01*
X378755Y891445D01*
X379595Y891210D01*
X380540Y891132D01*
X381485Y891210D01*
X382325Y891445D01*
X382955Y891758D01*
X383480Y892228D01*
X383690Y892855D01*
X383480Y893482D01*
X382955Y893952D01*
X382325Y894265D01*
X381485Y894500D01*
X380540Y894578D01*
X379595Y894500D01*
X378755Y894265D01*
X378125Y893952D01*
X377600Y893482D01*
X377390Y892855D01*
G01X395432Y1264858D02*
X397432D01*
Y1262458D01*
X396832Y1261658D01*
X396132Y1261125D01*
X395132Y1260858D01*
X394132Y1261125D01*
X393432Y1261658D01*
X392832Y1262458D01*
X392432Y1263391D01*
X392232Y1264458D01*
Y1265391D01*
X392432Y1266191D01*
X392832Y1267125D01*
X393432Y1267925D01*
X394032Y1268458D01*
X394832Y1268858D01*
X395532D01*
X396332Y1268591D01*
X396932Y1268058D01*
G01X400832Y1260858D02*
Y1268858D01*
X403332D01*
X404132Y1268458D01*
X404632Y1267925D01*
X404832Y1266858D01*
X404632Y1265791D01*
X404032Y1265125D01*
X403332Y1264725D01*
X400832D01*
G01X403332D02*
X404832Y1260858D01*
G01X410832D02*
X410032Y1260991D01*
X409332Y1261525D01*
X408732Y1262325D01*
X408332Y1263258D01*
X408132Y1264325D01*
Y1265391D01*
X408332Y1266458D01*
X408732Y1267391D01*
X409332Y1268191D01*
X410032Y1268725D01*
X410832Y1268858D01*
X411632Y1268725D01*
X412332Y1268191D01*
X412932Y1267391D01*
X413332Y1266458D01*
X413532Y1265391D01*
Y1264325D01*
X413332Y1263258D01*
X412932Y1262325D01*
X412332Y1261525D01*
X411632Y1260991D01*
X410832Y1260858D01*
G01X416632Y1268858D02*
Y1263125D01*
X417032Y1261924D01*
X417832Y1261125D01*
X418832Y1260858D01*
X419832Y1261125D01*
X420632Y1261924D01*
X421032Y1263125D01*
Y1268858D01*
G01X424832Y1260858D02*
Y1268858D01*
X427232D01*
X428032Y1268458D01*
X428632Y1267525D01*
X428832Y1266458D01*
X428632Y1265391D01*
X428132Y1264591D01*
X427232Y1264191D01*
X424832D01*
G01X432732Y1261924D02*
X433532Y1261258D01*
X434432Y1260858D01*
X435232D01*
X436032Y1261258D01*
X436632Y1261924D01*
X436932Y1262858D01*
X436732Y1263791D01*
X436232Y1264591D01*
X435332Y1265125D01*
X434132Y1265391D01*
X433432Y1265925D01*
X433132Y1266858D01*
X433332Y1267791D01*
X433832Y1268458D01*
X434532Y1268858D01*
X435232D01*
X435932Y1268591D01*
X436532Y1267925D01*
G01X451632Y1265125D02*
X452032Y1265525D01*
X452332Y1266191D01*
X452532Y1267125D01*
X452332Y1267925D01*
X451932Y1268458D01*
X451232Y1268858D01*
X448532D01*
Y1260858D01*
X451832D01*
X452532Y1261391D01*
X452932Y1262191D01*
X453132Y1263125D01*
X452932Y1264058D01*
X452332Y1264858D01*
X451632Y1265125D01*
X448532D01*
G01X416536Y-59598D02*
X410236D01*
X414751Y-62496D01*
Y-58580D01*
G01X416536Y-54238D02*
X410236D01*
X411496Y-55178D01*
G01X416536D02*
Y-53298D01*
G01X415276Y-49661D02*
X416011Y-49191D01*
X416431Y-48565D01*
X416536Y-47860D01*
X416431Y-47233D01*
X415906Y-46606D01*
X415276Y-46215D01*
X414646Y-46136D01*
X413911Y-46293D01*
X413386Y-46841D01*
X413176Y-47390D01*
Y-48095D01*
G01Y-47390D02*
X412861Y-46920D01*
X412336Y-46528D01*
X411706Y-46371D01*
X411076Y-46528D01*
X410551Y-46920D01*
X410236Y-47625D01*
X410341Y-48330D01*
X410761Y-49035D01*
G01X415276Y-43361D02*
X416011Y-42891D01*
X416431Y-42265D01*
X416536Y-41560D01*
X416431Y-40933D01*
X415906Y-40306D01*
X415276Y-39915D01*
X414646Y-39836D01*
X413911Y-39993D01*
X413386Y-40541D01*
X413176Y-41090D01*
Y-41795D01*
G01Y-41090D02*
X412861Y-40620D01*
X412336Y-40228D01*
X411706Y-40071D01*
X411076Y-40228D01*
X410551Y-40620D01*
X410236Y-41325D01*
X410341Y-42030D01*
X410761Y-42735D01*
G01X416746Y-35338D02*
X416641Y-35495D01*
X416431D01*
X416326Y-35338D01*
X416431Y-35181D01*
X416641D01*
X416746Y-35338D01*
G01X416536Y-29038D02*
X416431Y-28490D01*
X416116Y-27863D01*
X415591Y-27471D01*
X414856Y-27315D01*
X414121Y-27471D01*
X413491Y-27941D01*
X413176Y-28646D01*
Y-29430D01*
X412966Y-29900D01*
X412441Y-30291D01*
X411706Y-30448D01*
X410971Y-30213D01*
X410446Y-29665D01*
X410236Y-29038D01*
X410446Y-28411D01*
X410971Y-27863D01*
X411706Y-27628D01*
X412441Y-27785D01*
X412966Y-28176D01*
X413176Y-28646D01*
Y-29430D01*
X413491Y-30135D01*
X414121Y-30605D01*
X414856Y-30761D01*
X415591Y-30605D01*
X416116Y-30213D01*
X416431Y-29586D01*
X416536Y-29038D01*
G01X413911Y-24226D02*
X413176Y-23678D01*
X412756Y-23208D01*
X412546Y-22581D01*
X412756Y-22033D01*
X413176Y-21641D01*
X413806Y-21328D01*
X414541Y-21250D01*
X415171Y-21328D01*
X415801Y-21641D01*
X416326Y-22111D01*
X416536Y-22660D01*
X416326Y-23286D01*
X415696Y-23835D01*
X414751Y-24148D01*
X413701Y-24226D01*
X412336Y-24070D01*
X411601Y-23835D01*
X410866Y-23443D01*
X410341Y-22895D01*
X410236Y-22346D01*
X410446Y-21798D01*
X410971Y-21406D01*
G01X410079Y857287D02*
X403779D01*
X408294Y854389D01*
Y858305D01*
G01X403779Y862647D02*
X403989Y862020D01*
X404514Y861550D01*
X405144Y861237D01*
X405984Y861002D01*
X406929Y860924D01*
X407874Y861002D01*
X408714Y861237D01*
X409344Y861550D01*
X409869Y862020D01*
X410079Y862647D01*
X409869Y863274D01*
X409344Y863744D01*
X408714Y864057D01*
X407874Y864292D01*
X406929Y864370D01*
X405984Y864292D01*
X405144Y864057D01*
X404514Y863744D01*
X403989Y863274D01*
X403779Y862647D01*
G01X407454Y867459D02*
X406719Y868007D01*
X406299Y868477D01*
X406089Y869104D01*
X406299Y869652D01*
X406719Y870044D01*
X407349Y870357D01*
X408084Y870435D01*
X408714Y870357D01*
X409344Y870044D01*
X409869Y869574D01*
X410079Y869025D01*
X409869Y868399D01*
X409239Y867850D01*
X408294Y867537D01*
X407244Y867459D01*
X405879Y867615D01*
X405144Y867850D01*
X404409Y868242D01*
X403884Y868790D01*
X403779Y869339D01*
X403989Y869887D01*
X404514Y870279D01*
G01X409344Y873915D02*
X409869Y874464D01*
X410079Y875090D01*
X409869Y875717D01*
X409239Y876265D01*
X408294Y876657D01*
X407349Y876814D01*
X406194D01*
X405249Y876657D01*
X404409Y876265D01*
X403989Y875795D01*
X403779Y875247D01*
X403989Y874620D01*
X404409Y874150D01*
X405039Y873837D01*
X405879Y873680D01*
X406614Y873837D01*
X407349Y874229D01*
X407769Y874699D01*
X407874Y875247D01*
X407664Y875874D01*
X407139Y876344D01*
X406194Y876814D01*
G01X410289Y881547D02*
X410184Y881390D01*
X409974D01*
X409869Y881547D01*
X409974Y881704D01*
X410184D01*
X410289Y881547D01*
G01X404829Y886359D02*
X404199Y886829D01*
X403884Y887377D01*
X403779Y888004D01*
X403989Y888787D01*
X404514Y889335D01*
X405144Y889492D01*
X405774Y889414D01*
X406299Y889100D01*
X407349Y887534D01*
X408084Y886829D01*
X409134Y886359D01*
X410079Y886202D01*
Y889492D01*
G01X409344Y892815D02*
X409869Y893364D01*
X410079Y893990D01*
X409869Y894617D01*
X409239Y895165D01*
X408294Y895557D01*
X407349Y895714D01*
X406194D01*
X405249Y895557D01*
X404409Y895165D01*
X403989Y894695D01*
X403779Y894147D01*
X403989Y893520D01*
X404409Y893050D01*
X405039Y892737D01*
X405879Y892580D01*
X406614Y892737D01*
X407349Y893129D01*
X407769Y893599D01*
X407874Y894147D01*
X407664Y894774D01*
X407139Y895244D01*
X406194Y895714D01*
G01X473793Y-244364D02*
Y-236364D01*
X475793D01*
X476593Y-236764D01*
X477193Y-237297D01*
X477693Y-238097D01*
X478093Y-239031D01*
X478193Y-240364D01*
X478093Y-241697D01*
X477693Y-242631D01*
X477193Y-243431D01*
X476593Y-243964D01*
X475793Y-244364D01*
X473793D01*
G01X484252Y-79202D02*
X477952D01*
X482467Y-82100D01*
Y-78184D01*
G01X484252Y-73842D02*
X484147Y-73294D01*
X483832Y-72667D01*
X483307Y-72275D01*
X482572Y-72119D01*
X481837Y-72275D01*
X481207Y-72745D01*
X480892Y-73450D01*
Y-74234D01*
X480682Y-74704D01*
X480157Y-75095D01*
X479422Y-75252D01*
X478687Y-75017D01*
X478162Y-74469D01*
X477952Y-73842D01*
X478162Y-73215D01*
X478687Y-72667D01*
X479422Y-72432D01*
X480157Y-72589D01*
X480682Y-72980D01*
X480892Y-73450D01*
Y-74234D01*
X481207Y-74939D01*
X481837Y-75409D01*
X482572Y-75565D01*
X483307Y-75409D01*
X483832Y-75017D01*
X484147Y-74390D01*
X484252Y-73842D01*
G01Y-67542D02*
X477952D01*
X479212Y-68482D01*
G01X484252D02*
Y-66602D01*
G01Y-61242D02*
X477952D01*
X479212Y-62182D01*
G01X484252D02*
Y-60302D01*
G01X484462Y-54942D02*
X484357Y-55099D01*
X484147D01*
X484042Y-54942D01*
X484147Y-54785D01*
X484357D01*
X484462Y-54942D01*
G01X477952Y-48642D02*
X478162Y-49269D01*
X478687Y-49739D01*
X479317Y-50052D01*
X480157Y-50287D01*
X481102Y-50365D01*
X482047Y-50287D01*
X482887Y-50052D01*
X483517Y-49739D01*
X484042Y-49269D01*
X484252Y-48642D01*
X484042Y-48015D01*
X483517Y-47545D01*
X482887Y-47232D01*
X482047Y-46997D01*
X481102Y-46919D01*
X480157Y-46997D01*
X479317Y-47232D01*
X478687Y-47545D01*
X478162Y-48015D01*
X477952Y-48642D01*
G01X479002Y-43830D02*
X478372Y-43360D01*
X478057Y-42812D01*
X477952Y-42185D01*
X478162Y-41402D01*
X478687Y-40854D01*
X479317Y-40697D01*
X479947Y-40775D01*
X480472Y-41089D01*
X481522Y-42655D01*
X482257Y-43360D01*
X483307Y-43830D01*
X484252Y-43987D01*
Y-40697D01*
G01X503493Y-244364D02*
Y-236364D01*
X502293Y-237964D01*
G01Y-244364D02*
X504693D01*
G01X509593Y-241031D02*
X510293Y-240097D01*
X510893Y-239564D01*
X511693Y-239297D01*
X512393Y-239564D01*
X512893Y-240097D01*
X513293Y-240897D01*
X513393Y-241831D01*
X513293Y-242631D01*
X512893Y-243431D01*
X512293Y-244097D01*
X511593Y-244364D01*
X510793Y-244097D01*
X510093Y-243298D01*
X509693Y-242097D01*
X509593Y-240764D01*
X509793Y-239031D01*
X510093Y-238097D01*
X510593Y-237164D01*
X511293Y-236497D01*
X511993Y-236364D01*
X512693Y-236631D01*
X513193Y-237297D01*
G01X689502Y-70815D02*
X688767Y-70267D01*
X688347Y-69797D01*
X688137Y-69170D01*
X688347Y-68622D01*
X688767Y-68230D01*
X689397Y-67917D01*
X690132Y-67839D01*
X690762Y-67917D01*
X691392Y-68230D01*
X691917Y-68700D01*
X692127Y-69249D01*
X691917Y-69875D01*
X691287Y-70424D01*
X690342Y-70737D01*
X689292Y-70815D01*
X687927Y-70659D01*
X687192Y-70424D01*
X686457Y-70032D01*
X685932Y-69484D01*
X685827Y-68935D01*
X686037Y-68387D01*
X686562Y-67995D01*
G01X692127Y-63027D02*
X692022Y-62479D01*
X691707Y-61852D01*
X691182Y-61460D01*
X690447Y-61304D01*
X689712Y-61460D01*
X689082Y-61930D01*
X688767Y-62635D01*
Y-63419D01*
X688557Y-63889D01*
X688032Y-64280D01*
X687297Y-64437D01*
X686562Y-64202D01*
X686037Y-63654D01*
X685827Y-63027D01*
X686037Y-62400D01*
X686562Y-61852D01*
X687297Y-61617D01*
X688032Y-61774D01*
X688557Y-62165D01*
X688767Y-62635D01*
Y-63419D01*
X689082Y-64124D01*
X689712Y-64594D01*
X690447Y-64750D01*
X691182Y-64594D01*
X691707Y-64202D01*
X692022Y-63575D01*
X692127Y-63027D01*
G01Y-56727D02*
X692022Y-56179D01*
X691707Y-55552D01*
X691182Y-55160D01*
X690447Y-55004D01*
X689712Y-55160D01*
X689082Y-55630D01*
X688767Y-56335D01*
Y-57119D01*
X688557Y-57589D01*
X688032Y-57980D01*
X687297Y-58137D01*
X686562Y-57902D01*
X686037Y-57354D01*
X685827Y-56727D01*
X686037Y-56100D01*
X686562Y-55552D01*
X687297Y-55317D01*
X688032Y-55474D01*
X688557Y-55865D01*
X688767Y-56335D01*
Y-57119D01*
X689082Y-57824D01*
X689712Y-58294D01*
X690447Y-58450D01*
X691182Y-58294D01*
X691707Y-57902D01*
X692022Y-57275D01*
X692127Y-56727D01*
G01X691392Y-51759D02*
X691917Y-51210D01*
X692127Y-50584D01*
X691917Y-49957D01*
X691287Y-49409D01*
X690342Y-49017D01*
X689397Y-48860D01*
X688242D01*
X687297Y-49017D01*
X686457Y-49409D01*
X686037Y-49879D01*
X685827Y-50427D01*
X686037Y-51054D01*
X686457Y-51524D01*
X687087Y-51837D01*
X687927Y-51994D01*
X688662Y-51837D01*
X689397Y-51445D01*
X689817Y-50975D01*
X689922Y-50427D01*
X689712Y-49800D01*
X689187Y-49330D01*
X688242Y-48860D01*
G01X692337Y-44127D02*
X692232Y-44284D01*
X692022D01*
X691917Y-44127D01*
X692022Y-43970D01*
X692232D01*
X692337Y-44127D01*
G01X692127Y-37984D02*
X690762Y-37827D01*
X689607Y-37592D01*
X688557Y-37279D01*
X687402Y-36887D01*
X685827Y-36260D01*
Y-39394D01*
G01X692127Y-31684D02*
X690762Y-31527D01*
X689607Y-31292D01*
X688557Y-30979D01*
X687402Y-30587D01*
X685827Y-29960D01*
Y-33094D01*
G01X687769Y862321D02*
X687034Y862869D01*
X686614Y863339D01*
X686404Y863966D01*
X686614Y864514D01*
X687034Y864906D01*
X687664Y865219D01*
X688399Y865297D01*
X689029Y865219D01*
X689659Y864906D01*
X690184Y864436D01*
X690394Y863887D01*
X690184Y863261D01*
X689554Y862712D01*
X688609Y862399D01*
X687559Y862321D01*
X686194Y862477D01*
X685459Y862712D01*
X684724Y863104D01*
X684199Y863652D01*
X684094Y864201D01*
X684304Y864749D01*
X684829Y865141D01*
G01X690394Y870109D02*
X690289Y870657D01*
X689974Y871284D01*
X689449Y871676D01*
X688714Y871832D01*
X687979Y871676D01*
X687349Y871206D01*
X687034Y870501D01*
Y869717D01*
X686824Y869247D01*
X686299Y868856D01*
X685564Y868699D01*
X684829Y868934D01*
X684304Y869482D01*
X684094Y870109D01*
X684304Y870736D01*
X684829Y871284D01*
X685564Y871519D01*
X686299Y871362D01*
X686824Y870971D01*
X687034Y870501D01*
Y869717D01*
X687349Y869012D01*
X687979Y868542D01*
X688714Y868386D01*
X689449Y868542D01*
X689974Y868934D01*
X690289Y869561D01*
X690394Y870109D01*
G01Y876252D02*
X689029Y876409D01*
X687874Y876644D01*
X686824Y876957D01*
X685669Y877349D01*
X684094Y877976D01*
Y874842D01*
G01X685144Y881221D02*
X684514Y881691D01*
X684199Y882239D01*
X684094Y882866D01*
X684304Y883649D01*
X684829Y884197D01*
X685459Y884354D01*
X686089Y884276D01*
X686614Y883962D01*
X687664Y882396D01*
X688399Y881691D01*
X689449Y881221D01*
X690394Y881064D01*
Y884354D01*
G01X690604Y889009D02*
X690499Y888852D01*
X690289D01*
X690184Y889009D01*
X690289Y889166D01*
X690499D01*
X690604Y889009D01*
G01X690394Y896249D02*
X684094D01*
X688609Y893351D01*
Y897267D01*
G01X690394Y902549D02*
X684094D01*
X688609Y899651D01*
Y903567D01*
G01X695249Y861137D02*
X694514Y861685D01*
X694094Y862155D01*
X693884Y862782D01*
X694094Y863330D01*
X694514Y863722D01*
X695144Y864035D01*
X695879Y864113D01*
X696509Y864035D01*
X697139Y863722D01*
X697664Y863252D01*
X697874Y862703D01*
X697664Y862077D01*
X697034Y861528D01*
X696089Y861215D01*
X695039Y861137D01*
X693674Y861293D01*
X692939Y861528D01*
X692204Y861920D01*
X691679Y862468D01*
X691574Y863017D01*
X691784Y863565D01*
X692309Y863957D01*
G01X697139Y867593D02*
X697664Y868142D01*
X697874Y868768D01*
X697664Y869395D01*
X697034Y869943D01*
X696089Y870335D01*
X695144Y870492D01*
X693989D01*
X693044Y870335D01*
X692204Y869943D01*
X691784Y869473D01*
X691574Y868925D01*
X691784Y868298D01*
X692204Y867828D01*
X692834Y867515D01*
X693674Y867358D01*
X694409Y867515D01*
X695144Y867907D01*
X695564Y868377D01*
X695669Y868925D01*
X695459Y869552D01*
X694934Y870022D01*
X693989Y870492D01*
G01X697874Y876165D02*
X691574D01*
X696089Y873267D01*
Y877183D01*
G01X697874Y881368D02*
X696509Y881525D01*
X695354Y881760D01*
X694304Y882073D01*
X693149Y882465D01*
X691574Y883092D01*
Y879958D01*
G01X698084Y887825D02*
X697979Y887668D01*
X697769D01*
X697664Y887825D01*
X697769Y887982D01*
X697979D01*
X698084Y887825D01*
G01X692624Y892637D02*
X691994Y893107D01*
X691679Y893655D01*
X691574Y894282D01*
X691784Y895065D01*
X692309Y895613D01*
X692939Y895770D01*
X693569Y895692D01*
X694094Y895378D01*
X695144Y893812D01*
X695879Y893107D01*
X696929Y892637D01*
X697874Y892480D01*
Y895770D01*
G01Y901365D02*
X691574D01*
X696089Y898467D01*
Y902383D01*
G01X747532Y1334658D02*
X749532D01*
Y1332258D01*
X748932Y1331458D01*
X748232Y1330925D01*
X747232Y1330658D01*
X746232Y1330925D01*
X745532Y1331458D01*
X744932Y1332258D01*
X744532Y1333191D01*
X744332Y1334258D01*
Y1335191D01*
X744532Y1335991D01*
X744932Y1336925D01*
X745532Y1337725D01*
X746132Y1338258D01*
X746932Y1338658D01*
X747632D01*
X748432Y1338391D01*
X749032Y1337858D01*
G01X752932Y1330658D02*
Y1338658D01*
X755432D01*
X756232Y1338258D01*
X756732Y1337725D01*
X756932Y1336658D01*
X756732Y1335591D01*
X756132Y1334925D01*
X755432Y1334525D01*
X752932D01*
G01X755432D02*
X756932Y1330658D01*
G01X762932D02*
X762132Y1330791D01*
X761432Y1331325D01*
X760832Y1332125D01*
X760432Y1333058D01*
X760232Y1334125D01*
Y1335191D01*
X760432Y1336258D01*
X760832Y1337191D01*
X761432Y1337991D01*
X762132Y1338525D01*
X762932Y1338658D01*
X763732Y1338525D01*
X764432Y1337991D01*
X765032Y1337191D01*
X765432Y1336258D01*
X765632Y1335191D01*
Y1334125D01*
X765432Y1333058D01*
X765032Y1332125D01*
X764432Y1331325D01*
X763732Y1330791D01*
X762932Y1330658D01*
G01X768732Y1338658D02*
Y1332925D01*
X769132Y1331724D01*
X769932Y1330925D01*
X770932Y1330658D01*
X771932Y1330925D01*
X772732Y1331724D01*
X773132Y1332925D01*
Y1338658D01*
G01X776932Y1330658D02*
Y1338658D01*
X779332D01*
X780132Y1338258D01*
X780732Y1337325D01*
X780932Y1336258D01*
X780732Y1335191D01*
X780232Y1334391D01*
X779332Y1333991D01*
X776932D01*
G01X784832Y1331724D02*
X785632Y1331058D01*
X786532Y1330658D01*
X787332D01*
X788132Y1331058D01*
X788732Y1331724D01*
X789032Y1332658D01*
X788832Y1333591D01*
X788332Y1334391D01*
X787432Y1334925D01*
X786232Y1335191D01*
X785532Y1335725D01*
X785232Y1336658D01*
X785432Y1337591D01*
X785932Y1338258D01*
X786632Y1338658D01*
X787332D01*
X788032Y1338391D01*
X788632Y1337725D01*
G01X800432Y1330658D02*
X802932Y1338658D01*
X805432Y1330658D01*
G01X804532Y1333458D02*
X801332D01*
G01X802386Y32638D02*
X802856Y31903D01*
X803482Y31483D01*
X804187Y31378D01*
X804814Y31483D01*
X805441Y32008D01*
X805832Y32638D01*
X805911Y33268D01*
X805754Y34003D01*
X805206Y34528D01*
X804657Y34738D01*
X803952D01*
G01X804657D02*
X805127Y35053D01*
X805519Y35578D01*
X805676Y36208D01*
X805519Y36838D01*
X805127Y37363D01*
X804422Y37678D01*
X803717Y37573D01*
X803012Y37153D01*
G01X811349Y31378D02*
Y37678D01*
X808451Y33163D01*
X812367D01*
G01X814986Y32323D02*
X815456Y31798D01*
X816004Y31483D01*
X816709Y31378D01*
X817414Y31588D01*
X817962Y32008D01*
X818354Y32743D01*
X818432Y33583D01*
X818276Y34423D01*
X817884Y34948D01*
X817336Y35368D01*
X816787Y35473D01*
X816239Y35368D01*
X815534Y34948D01*
X815769Y37678D01*
X817884D01*
G01X823009Y31168D02*
X822852Y31273D01*
Y31483D01*
X823009Y31588D01*
X823166Y31483D01*
Y31273D01*
X823009Y31168D01*
G01X827821Y36628D02*
X828291Y37258D01*
X828839Y37573D01*
X829466Y37678D01*
X830249Y37468D01*
X830797Y36943D01*
X830954Y36313D01*
X830876Y35683D01*
X830562Y35158D01*
X828996Y34108D01*
X828291Y33373D01*
X827821Y32323D01*
X827664Y31378D01*
X830954D01*
G01X835609D02*
X836157Y31483D01*
X836784Y31798D01*
X837176Y32323D01*
X837332Y33058D01*
X837176Y33793D01*
X836706Y34423D01*
X836001Y34738D01*
X835217D01*
X834747Y34948D01*
X834356Y35473D01*
X834199Y36208D01*
X834434Y36943D01*
X834982Y37468D01*
X835609Y37678D01*
X836236Y37468D01*
X836784Y36943D01*
X837019Y36208D01*
X836862Y35473D01*
X836471Y34948D01*
X836001Y34738D01*
X835217D01*
X834512Y34423D01*
X834042Y33793D01*
X833886Y33058D01*
X834042Y32323D01*
X834434Y31798D01*
X835061Y31483D01*
X835609Y31378D01*
G01X818164Y347716D02*
X818634Y346981D01*
X819260Y346561D01*
X819965Y346456D01*
X820592Y346561D01*
X821219Y347086D01*
X821610Y347716D01*
X821689Y348346D01*
X821532Y349081D01*
X820984Y349606D01*
X820435Y349816D01*
X819730D01*
G01X820435D02*
X820905Y350131D01*
X821297Y350656D01*
X821454Y351286D01*
X821297Y351916D01*
X820905Y352441D01*
X820200Y352756D01*
X819495Y352651D01*
X818790Y352231D01*
G01X827127Y346456D02*
Y352756D01*
X824229Y348241D01*
X828145D01*
G01X831155Y347191D02*
X831704Y346666D01*
X832330Y346456D01*
X832957Y346666D01*
X833505Y347296D01*
X833897Y348241D01*
X834054Y349186D01*
Y350341D01*
X833897Y351286D01*
X833505Y352126D01*
X833035Y352546D01*
X832487Y352756D01*
X831860Y352546D01*
X831390Y352126D01*
X831077Y351496D01*
X830920Y350656D01*
X831077Y349921D01*
X831469Y349186D01*
X831939Y348766D01*
X832487Y348661D01*
X833114Y348871D01*
X833584Y349396D01*
X834054Y350341D01*
G01X837299Y349081D02*
X837847Y349816D01*
X838317Y350236D01*
X838944Y350446D01*
X839492Y350236D01*
X839884Y349816D01*
X840197Y349186D01*
X840275Y348451D01*
X840197Y347821D01*
X839884Y347191D01*
X839414Y346666D01*
X838865Y346456D01*
X838239Y346666D01*
X837690Y347296D01*
X837377Y348241D01*
X837299Y349291D01*
X837455Y350656D01*
X837690Y351391D01*
X838082Y352126D01*
X838630Y352651D01*
X839179Y352756D01*
X839727Y352546D01*
X840119Y352021D01*
G01X845087Y346246D02*
X844930Y346351D01*
Y346561D01*
X845087Y346666D01*
X845244Y346561D01*
Y346351D01*
X845087Y346246D01*
G01X851387Y352756D02*
X850760Y352546D01*
X850290Y352021D01*
X849977Y351391D01*
X849742Y350551D01*
X849664Y349606D01*
X849742Y348661D01*
X849977Y347821D01*
X850290Y347191D01*
X850760Y346666D01*
X851387Y346456D01*
X852014Y346666D01*
X852484Y347191D01*
X852797Y347821D01*
X853032Y348661D01*
X853110Y349606D01*
X853032Y350551D01*
X852797Y351391D01*
X852484Y352021D01*
X852014Y352546D01*
X851387Y352756D01*
G01X856199Y349081D02*
X856747Y349816D01*
X857217Y350236D01*
X857844Y350446D01*
X858392Y350236D01*
X858784Y349816D01*
X859097Y349186D01*
X859175Y348451D01*
X859097Y347821D01*
X858784Y347191D01*
X858314Y346666D01*
X857765Y346456D01*
X857139Y346666D01*
X856590Y347296D01*
X856277Y348241D01*
X856199Y349291D01*
X856355Y350656D01*
X856590Y351391D01*
X856982Y352126D01*
X857530Y352651D01*
X858079Y352756D01*
X858627Y352546D01*
X859019Y352021D01*
G01X822220Y375275D02*
X822690Y374540D01*
X823316Y374120D01*
X824021Y374015D01*
X824648Y374120D01*
X825275Y374645D01*
X825666Y375275D01*
X825745Y375905D01*
X825588Y376640D01*
X825040Y377165D01*
X824491Y377375D01*
X823786D01*
G01X824491D02*
X824961Y377690D01*
X825353Y378215D01*
X825510Y378845D01*
X825353Y379475D01*
X824961Y380000D01*
X824256Y380315D01*
X823551Y380210D01*
X822846Y379790D01*
G01X830086Y374015D02*
X830243Y375380D01*
X830478Y376535D01*
X830791Y377585D01*
X831183Y378740D01*
X831810Y380315D01*
X828676D01*
G01X836386Y374015D02*
X836543Y375380D01*
X836778Y376535D01*
X837091Y377585D01*
X837483Y378740D01*
X838110Y380315D01*
X834976D01*
G01X842843Y374015D02*
Y380315D01*
X841903Y379055D01*
G01Y374015D02*
X843783D01*
G01X849143Y373805D02*
X848986Y373910D01*
Y374120D01*
X849143Y374225D01*
X849300Y374120D01*
Y373910D01*
X849143Y373805D01*
G01X853955Y376640D02*
X854503Y377375D01*
X854973Y377795D01*
X855600Y378005D01*
X856148Y377795D01*
X856540Y377375D01*
X856853Y376745D01*
X856931Y376010D01*
X856853Y375380D01*
X856540Y374750D01*
X856070Y374225D01*
X855521Y374015D01*
X854895Y374225D01*
X854346Y374855D01*
X854033Y375800D01*
X853955Y376850D01*
X854111Y378215D01*
X854346Y378950D01*
X854738Y379685D01*
X855286Y380210D01*
X855835Y380315D01*
X856383Y380105D01*
X856775Y379580D01*
G01X860020Y374960D02*
X860490Y374435D01*
X861038Y374120D01*
X861743Y374015D01*
X862448Y374225D01*
X862996Y374645D01*
X863388Y375380D01*
X863466Y376220D01*
X863310Y377060D01*
X862918Y377585D01*
X862370Y378005D01*
X861821Y378110D01*
X861273Y378005D01*
X860568Y377585D01*
X860803Y380315D01*
X862918D01*
G01X845575Y102362D02*
Y108662D01*
X844635Y107402D01*
G01Y102362D02*
X846515D01*
G01X851875Y108662D02*
X851248Y108452D01*
X850778Y107927D01*
X850465Y107297D01*
X850230Y106457D01*
X850152Y105512D01*
X850230Y104567D01*
X850465Y103727D01*
X850778Y103097D01*
X851248Y102572D01*
X851875Y102362D01*
X852502Y102572D01*
X852972Y103097D01*
X853285Y103727D01*
X853520Y104567D01*
X853598Y105512D01*
X853520Y106457D01*
X853285Y107297D01*
X852972Y107927D01*
X852502Y108452D01*
X851875Y108662D01*
G01X856452Y103307D02*
X856922Y102782D01*
X857470Y102467D01*
X858175Y102362D01*
X858880Y102572D01*
X859428Y102992D01*
X859820Y103727D01*
X859898Y104567D01*
X859742Y105407D01*
X859350Y105932D01*
X858802Y106352D01*
X858253Y106457D01*
X857705Y106352D01*
X857000Y105932D01*
X857235Y108662D01*
X859350D01*
G01X862752Y103307D02*
X863222Y102782D01*
X863770Y102467D01*
X864475Y102362D01*
X865180Y102572D01*
X865728Y102992D01*
X866120Y103727D01*
X866198Y104567D01*
X866042Y105407D01*
X865650Y105932D01*
X865102Y106352D01*
X864553Y106457D01*
X864005Y106352D01*
X863300Y105932D01*
X863535Y108662D01*
X865650D01*
G01X870775Y102152D02*
X870618Y102257D01*
Y102467D01*
X870775Y102572D01*
X870932Y102467D01*
Y102257D01*
X870775Y102152D01*
G01X877075Y102362D02*
Y108662D01*
X876135Y107402D01*
G01Y102362D02*
X878015D01*
G01X881887Y107612D02*
X882357Y108242D01*
X882905Y108557D01*
X883532Y108662D01*
X884315Y108452D01*
X884863Y107927D01*
X885020Y107297D01*
X884942Y106667D01*
X884628Y106142D01*
X883062Y105092D01*
X882357Y104357D01*
X881887Y103307D01*
X881730Y102362D01*
X885020D01*
G01X872120Y716535D02*
X872277Y717900D01*
X872512Y719055D01*
X872825Y720105D01*
X873217Y721260D01*
X873844Y722835D01*
X870710D01*
G01X878577Y716535D02*
Y722835D01*
X877637Y721575D01*
G01Y716535D02*
X879517D01*
G01X883545Y717270D02*
X884094Y716745D01*
X884720Y716535D01*
X885347Y716745D01*
X885895Y717375D01*
X886287Y718320D01*
X886444Y719265D01*
Y720420D01*
X886287Y721365D01*
X885895Y722205D01*
X885425Y722625D01*
X884877Y722835D01*
X884250Y722625D01*
X883780Y722205D01*
X883467Y721575D01*
X883310Y720735D01*
X883467Y720000D01*
X883859Y719265D01*
X884329Y718845D01*
X884877Y718740D01*
X885504Y718950D01*
X885974Y719475D01*
X886444Y720420D01*
G01X889689Y719160D02*
X890237Y719895D01*
X890707Y720315D01*
X891334Y720525D01*
X891882Y720315D01*
X892274Y719895D01*
X892587Y719265D01*
X892665Y718530D01*
X892587Y717900D01*
X892274Y717270D01*
X891804Y716745D01*
X891255Y716535D01*
X890629Y716745D01*
X890080Y717375D01*
X889767Y718320D01*
X889689Y719370D01*
X889845Y720735D01*
X890080Y721470D01*
X890472Y722205D01*
X891020Y722730D01*
X891569Y722835D01*
X892117Y722625D01*
X892509Y722100D01*
G01X897477Y716325D02*
X897320Y716430D01*
Y716640D01*
X897477Y716745D01*
X897634Y716640D01*
Y716430D01*
X897477Y716325D01*
G01X903777Y716535D02*
X904325Y716640D01*
X904952Y716955D01*
X905344Y717480D01*
X905500Y718215D01*
X905344Y718950D01*
X904874Y719580D01*
X904169Y719895D01*
X903385D01*
X902915Y720105D01*
X902524Y720630D01*
X902367Y721365D01*
X902602Y722100D01*
X903150Y722625D01*
X903777Y722835D01*
X904404Y722625D01*
X904952Y722100D01*
X905187Y721365D01*
X905030Y720630D01*
X904639Y720105D01*
X904169Y719895D01*
X903385D01*
X902680Y719580D01*
X902210Y718950D01*
X902054Y718215D01*
X902210Y717480D01*
X902602Y716955D01*
X903229Y716640D01*
X903777Y716535D01*
G01X908354Y717480D02*
X908824Y716955D01*
X909372Y716640D01*
X910077Y716535D01*
X910782Y716745D01*
X911330Y717165D01*
X911722Y717900D01*
X911800Y718740D01*
X911644Y719580D01*
X911252Y720105D01*
X910704Y720525D01*
X910155Y720630D01*
X909607Y720525D01*
X908902Y720105D01*
X909137Y722835D01*
X911252D01*
G01X907510Y435642D02*
X907405Y436190D01*
X907090Y436817D01*
X906565Y437209D01*
X905830Y437365D01*
X905095Y437209D01*
X904465Y436739D01*
X904150Y436034D01*
Y435250D01*
X903940Y434780D01*
X903415Y434389D01*
X902680Y434232D01*
X901945Y434467D01*
X901420Y435015D01*
X901210Y435642D01*
X901420Y436269D01*
X901945Y436817D01*
X902680Y437052D01*
X903415Y436895D01*
X903940Y436504D01*
X904150Y436034D01*
Y435250D01*
X904465Y434545D01*
X905095Y434075D01*
X905830Y433919D01*
X906565Y434075D01*
X907090Y434467D01*
X907405Y435094D01*
X907510Y435642D01*
G01X902260Y440454D02*
X901630Y440924D01*
X901315Y441472D01*
X901210Y442099D01*
X901420Y442882D01*
X901945Y443430D01*
X902575Y443587D01*
X903205Y443509D01*
X903730Y443195D01*
X904780Y441629D01*
X905515Y440924D01*
X906565Y440454D01*
X907510Y440297D01*
Y443587D01*
G01Y448242D02*
X901210D01*
X902470Y447302D01*
G01X907510D02*
Y449182D01*
G01X904885Y453054D02*
X904150Y453602D01*
X903730Y454072D01*
X903520Y454699D01*
X903730Y455247D01*
X904150Y455639D01*
X904780Y455952D01*
X905515Y456030D01*
X906145Y455952D01*
X906775Y455639D01*
X907300Y455169D01*
X907510Y454620D01*
X907300Y453994D01*
X906670Y453445D01*
X905725Y453132D01*
X904675Y453054D01*
X903310Y453210D01*
X902575Y453445D01*
X901840Y453837D01*
X901315Y454385D01*
X901210Y454934D01*
X901420Y455482D01*
X901945Y455874D01*
G01X907720Y460842D02*
X907615Y460685D01*
X907405D01*
X907300Y460842D01*
X907405Y460999D01*
X907615D01*
X907720Y460842D01*
G01X906565Y465419D02*
X907090Y465889D01*
X907405Y466437D01*
X907510Y467142D01*
X907300Y467847D01*
X906880Y468395D01*
X906145Y468787D01*
X905305Y468865D01*
X904465Y468709D01*
X903940Y468317D01*
X903520Y467769D01*
X903415Y467220D01*
X903520Y466672D01*
X903940Y465967D01*
X901210Y466202D01*
Y468317D01*
G01X907510Y474382D02*
X901210D01*
X905725Y471484D01*
Y475400D01*
G01X1074518Y972870D02*
Y977870D01*
X1076924D01*
G01X1076038Y975453D02*
X1074518D01*
G01X1080061Y977870D02*
X1081581D01*
G01X1080821D02*
Y972870D01*
G01X1080061D02*
X1081581D01*
G01X1086301Y975370D02*
X1087568D01*
Y973870D01*
X1087188Y973370D01*
X1086744Y973037D01*
X1086111Y972870D01*
X1085478Y973037D01*
X1085034Y973370D01*
X1084654Y973870D01*
X1084401Y974453D01*
X1084274Y975120D01*
Y975703D01*
X1084401Y976203D01*
X1084654Y976787D01*
X1085034Y977287D01*
X1085414Y977620D01*
X1085921Y977870D01*
X1086364D01*
X1086871Y977703D01*
X1087251Y977370D01*
G01X1089628Y977870D02*
Y974287D01*
X1089881Y973537D01*
X1090388Y973037D01*
X1091021Y972870D01*
X1091654Y973037D01*
X1092161Y973537D01*
X1092414Y974287D01*
Y977870D01*
G01X1094854Y972870D02*
Y977870D01*
X1096438D01*
X1096944Y977620D01*
X1097261Y977287D01*
X1097388Y976620D01*
X1097261Y975953D01*
X1096881Y975537D01*
X1096438Y975287D01*
X1094854D01*
G01X1096438D02*
X1097388Y972870D01*
G01X1102488D02*
X1099954D01*
Y977870D01*
X1102488D01*
G01X1101474Y975453D02*
X1099954D01*
G01X1122921Y24045D02*
Y29045D01*
X1122161Y28045D01*
G01Y24045D02*
X1123681D01*
G01X1126818Y28212D02*
X1127198Y28712D01*
X1127641Y28962D01*
X1128148Y29045D01*
X1128781Y28878D01*
X1129224Y28462D01*
X1129351Y27962D01*
X1129288Y27462D01*
X1129034Y27045D01*
X1127768Y26212D01*
X1127198Y25628D01*
X1126818Y24795D01*
X1126691Y24045D01*
X1129351D01*
G01X1133881D02*
Y29045D01*
X1131538Y25462D01*
X1134704D01*
G01X1138221Y23878D02*
X1138094Y23962D01*
Y24128D01*
X1138221Y24212D01*
X1138348Y24128D01*
Y23962D01*
X1138221Y23878D01*
G01X1143321Y29045D02*
X1142814Y28878D01*
X1142434Y28462D01*
X1142181Y27962D01*
X1141991Y27295D01*
X1141928Y26545D01*
X1141991Y25795D01*
X1142181Y25128D01*
X1142434Y24628D01*
X1142814Y24212D01*
X1143321Y24045D01*
X1143828Y24212D01*
X1144208Y24628D01*
X1144461Y25128D01*
X1144651Y25795D01*
X1144714Y26545D01*
X1144651Y27295D01*
X1144461Y27962D01*
X1144208Y28462D01*
X1143828Y28878D01*
X1143321Y29045D01*
G01X1147471Y27378D02*
X1149371Y24045D01*
G01Y27378D02*
X1147471Y24045D01*
G01X1152318Y28212D02*
X1152698Y28712D01*
X1153141Y28962D01*
X1153648Y29045D01*
X1154281Y28878D01*
X1154724Y28462D01*
X1154851Y27962D01*
X1154788Y27462D01*
X1154534Y27045D01*
X1153268Y26212D01*
X1152698Y25628D01*
X1152318Y24795D01*
X1152191Y24045D01*
X1154851D01*
G01X1158621D02*
X1159064Y24128D01*
X1159571Y24378D01*
X1159888Y24795D01*
X1160014Y25378D01*
X1159888Y25962D01*
X1159508Y26462D01*
X1158938Y26712D01*
X1158304D01*
X1157924Y26878D01*
X1157608Y27295D01*
X1157481Y27878D01*
X1157671Y28462D01*
X1158114Y28878D01*
X1158621Y29045D01*
X1159128Y28878D01*
X1159571Y28462D01*
X1159761Y27878D01*
X1159634Y27295D01*
X1159318Y26878D01*
X1158938Y26712D01*
X1158304D01*
X1157734Y26462D01*
X1157354Y25962D01*
X1157228Y25378D01*
X1157354Y24795D01*
X1157671Y24378D01*
X1158178Y24128D01*
X1158621Y24045D01*
G01X1163721Y23878D02*
X1163594Y23962D01*
Y24128D01*
X1163721Y24212D01*
X1163848Y24128D01*
Y23962D01*
X1163721Y23878D01*
G01X1168821Y29045D02*
X1168314Y28878D01*
X1167934Y28462D01*
X1167681Y27962D01*
X1167491Y27295D01*
X1167428Y26545D01*
X1167491Y25795D01*
X1167681Y25128D01*
X1167934Y24628D01*
X1168314Y24212D01*
X1168821Y24045D01*
X1169328Y24212D01*
X1169708Y24628D01*
X1169961Y25128D01*
X1170151Y25795D01*
X1170214Y26545D01*
X1170151Y27295D01*
X1169961Y27962D01*
X1169708Y28462D01*
X1169328Y28878D01*
X1168821Y29045D01*
G01X1135671Y55995D02*
Y60995D01*
X1134911Y59995D01*
G01Y55995D02*
X1136431D01*
G01X1139378Y56745D02*
X1139758Y56328D01*
X1140201Y56078D01*
X1140771Y55995D01*
X1141341Y56162D01*
X1141784Y56495D01*
X1142101Y57078D01*
X1142164Y57745D01*
X1142038Y58412D01*
X1141721Y58828D01*
X1141278Y59162D01*
X1140834Y59245D01*
X1140391Y59162D01*
X1139821Y58828D01*
X1140011Y60995D01*
X1141721D01*
G01X1145871Y55995D02*
X1146314Y56078D01*
X1146821Y56328D01*
X1147138Y56745D01*
X1147264Y57328D01*
X1147138Y57912D01*
X1146758Y58412D01*
X1146188Y58662D01*
X1145554D01*
X1145174Y58828D01*
X1144858Y59245D01*
X1144731Y59828D01*
X1144921Y60412D01*
X1145364Y60828D01*
X1145871Y60995D01*
X1146378Y60828D01*
X1146821Y60412D01*
X1147011Y59828D01*
X1146884Y59245D01*
X1146568Y58828D01*
X1146188Y58662D01*
X1145554D01*
X1144984Y58412D01*
X1144604Y57912D01*
X1144478Y57328D01*
X1144604Y56745D01*
X1144921Y56328D01*
X1145428Y56078D01*
X1145871Y55995D01*
G01X1150971Y55828D02*
X1150844Y55912D01*
Y56078D01*
X1150971Y56162D01*
X1151098Y56078D01*
Y55912D01*
X1150971Y55828D01*
G01X1156071Y60995D02*
X1155564Y60828D01*
X1155184Y60412D01*
X1154931Y59912D01*
X1154741Y59245D01*
X1154678Y58495D01*
X1154741Y57745D01*
X1154931Y57078D01*
X1155184Y56578D01*
X1155564Y56162D01*
X1156071Y55995D01*
X1156578Y56162D01*
X1156958Y56578D01*
X1157211Y57078D01*
X1157401Y57745D01*
X1157464Y58495D01*
X1157401Y59245D01*
X1157211Y59912D01*
X1156958Y60412D01*
X1156578Y60828D01*
X1156071Y60995D01*
G01X1135671Y87945D02*
Y92945D01*
X1134911Y91945D01*
G01Y87945D02*
X1136431D01*
G01X1139378Y88695D02*
X1139758Y88278D01*
X1140201Y88028D01*
X1140771Y87945D01*
X1141341Y88112D01*
X1141784Y88445D01*
X1142101Y89028D01*
X1142164Y89695D01*
X1142038Y90362D01*
X1141721Y90778D01*
X1141278Y91112D01*
X1140834Y91195D01*
X1140391Y91112D01*
X1139821Y90778D01*
X1140011Y92945D01*
X1141721D01*
G01X1145871D02*
X1145364Y92778D01*
X1144984Y92362D01*
X1144731Y91862D01*
X1144541Y91195D01*
X1144478Y90445D01*
X1144541Y89695D01*
X1144731Y89028D01*
X1144984Y88528D01*
X1145364Y88112D01*
X1145871Y87945D01*
X1146378Y88112D01*
X1146758Y88528D01*
X1147011Y89028D01*
X1147201Y89695D01*
X1147264Y90445D01*
X1147201Y91195D01*
X1147011Y91862D01*
X1146758Y92362D01*
X1146378Y92778D01*
X1145871Y92945D01*
G01X1150971Y87778D02*
X1150844Y87862D01*
Y88028D01*
X1150971Y88112D01*
X1151098Y88028D01*
Y87862D01*
X1150971Y87778D01*
G01X1156071Y92945D02*
X1155564Y92778D01*
X1155184Y92362D01*
X1154931Y91862D01*
X1154741Y91195D01*
X1154678Y90445D01*
X1154741Y89695D01*
X1154931Y89028D01*
X1155184Y88528D01*
X1155564Y88112D01*
X1156071Y87945D01*
X1156578Y88112D01*
X1156958Y88528D01*
X1157211Y89028D01*
X1157401Y89695D01*
X1157464Y90445D01*
X1157401Y91195D01*
X1157211Y91862D01*
X1156958Y92362D01*
X1156578Y92778D01*
X1156071Y92945D01*
G01X1135671Y119895D02*
Y124895D01*
X1134911Y123895D01*
G01Y119895D02*
X1136431D01*
G01X1141531D02*
Y124895D01*
X1139188Y121312D01*
X1142354D01*
G01X1144668Y124062D02*
X1145048Y124562D01*
X1145491Y124812D01*
X1145998Y124895D01*
X1146631Y124728D01*
X1147074Y124312D01*
X1147201Y123812D01*
X1147138Y123312D01*
X1146884Y122895D01*
X1145618Y122062D01*
X1145048Y121478D01*
X1144668Y120645D01*
X1144541Y119895D01*
X1147201D01*
G01X1150971Y119728D02*
X1150844Y119812D01*
Y119978D01*
X1150971Y120062D01*
X1151098Y119978D01*
Y119812D01*
X1150971Y119728D01*
G01X1156071Y124895D02*
X1155564Y124728D01*
X1155184Y124312D01*
X1154931Y123812D01*
X1154741Y123145D01*
X1154678Y122395D01*
X1154741Y121645D01*
X1154931Y120978D01*
X1155184Y120478D01*
X1155564Y120062D01*
X1156071Y119895D01*
X1156578Y120062D01*
X1156958Y120478D01*
X1157211Y120978D01*
X1157401Y121645D01*
X1157464Y122395D01*
X1157401Y123145D01*
X1157211Y123812D01*
X1156958Y124312D01*
X1156578Y124728D01*
X1156071Y124895D01*
G01X1135671Y151845D02*
Y156845D01*
X1134911Y155845D01*
G01Y151845D02*
X1136431D01*
G01X1139568Y156012D02*
X1139948Y156512D01*
X1140391Y156762D01*
X1140898Y156845D01*
X1141531Y156678D01*
X1141974Y156262D01*
X1142101Y155762D01*
X1142038Y155262D01*
X1141784Y154845D01*
X1140518Y154012D01*
X1139948Y153428D01*
X1139568Y152595D01*
X1139441Y151845D01*
X1142101D01*
G01X1145871Y156845D02*
X1145364Y156678D01*
X1144984Y156262D01*
X1144731Y155762D01*
X1144541Y155095D01*
X1144478Y154345D01*
X1144541Y153595D01*
X1144731Y152928D01*
X1144984Y152428D01*
X1145364Y152012D01*
X1145871Y151845D01*
X1146378Y152012D01*
X1146758Y152428D01*
X1147011Y152928D01*
X1147201Y153595D01*
X1147264Y154345D01*
X1147201Y155095D01*
X1147011Y155762D01*
X1146758Y156262D01*
X1146378Y156678D01*
X1145871Y156845D01*
G01X1150971Y151678D02*
X1150844Y151762D01*
Y151928D01*
X1150971Y152012D01*
X1151098Y151928D01*
Y151762D01*
X1150971Y151678D01*
G01X1156071Y156845D02*
X1155564Y156678D01*
X1155184Y156262D01*
X1154931Y155762D01*
X1154741Y155095D01*
X1154678Y154345D01*
X1154741Y153595D01*
X1154931Y152928D01*
X1155184Y152428D01*
X1155564Y152012D01*
X1156071Y151845D01*
X1156578Y152012D01*
X1156958Y152428D01*
X1157211Y152928D01*
X1157401Y153595D01*
X1157464Y154345D01*
X1157401Y155095D01*
X1157211Y155762D01*
X1156958Y156262D01*
X1156578Y156678D01*
X1156071Y156845D01*
G01X1135671Y183795D02*
Y188795D01*
X1134911Y187795D01*
G01Y183795D02*
X1136431D01*
G01X1140771D02*
Y188795D01*
X1140011Y187795D01*
G01Y183795D02*
X1141531D01*
G01X1145871D02*
X1146314Y183878D01*
X1146821Y184128D01*
X1147138Y184545D01*
X1147264Y185128D01*
X1147138Y185712D01*
X1146758Y186212D01*
X1146188Y186462D01*
X1145554D01*
X1145174Y186628D01*
X1144858Y187045D01*
X1144731Y187628D01*
X1144921Y188212D01*
X1145364Y188628D01*
X1145871Y188795D01*
X1146378Y188628D01*
X1146821Y188212D01*
X1147011Y187628D01*
X1146884Y187045D01*
X1146568Y186628D01*
X1146188Y186462D01*
X1145554D01*
X1144984Y186212D01*
X1144604Y185712D01*
X1144478Y185128D01*
X1144604Y184545D01*
X1144921Y184128D01*
X1145428Y183878D01*
X1145871Y183795D01*
G01X1150971Y183628D02*
X1150844Y183712D01*
Y183878D01*
X1150971Y183962D01*
X1151098Y183878D01*
Y183712D01*
X1150971Y183628D01*
G01X1156071Y188795D02*
X1155564Y188628D01*
X1155184Y188212D01*
X1154931Y187712D01*
X1154741Y187045D01*
X1154678Y186295D01*
X1154741Y185545D01*
X1154931Y184878D01*
X1155184Y184378D01*
X1155564Y183962D01*
X1156071Y183795D01*
X1156578Y183962D01*
X1156958Y184378D01*
X1157211Y184878D01*
X1157401Y185545D01*
X1157464Y186295D01*
X1157401Y187045D01*
X1157211Y187712D01*
X1156958Y188212D01*
X1156578Y188628D01*
X1156071Y188795D01*
G01X1137018Y217828D02*
X1137461Y218412D01*
X1137841Y218745D01*
X1138348Y218912D01*
X1138791Y218745D01*
X1139108Y218412D01*
X1139361Y217912D01*
X1139424Y217328D01*
X1139361Y216828D01*
X1139108Y216328D01*
X1138728Y215912D01*
X1138284Y215745D01*
X1137778Y215912D01*
X1137334Y216412D01*
X1137081Y217162D01*
X1137018Y217995D01*
X1137144Y219078D01*
X1137334Y219662D01*
X1137651Y220245D01*
X1138094Y220662D01*
X1138538Y220745D01*
X1138981Y220578D01*
X1139298Y220162D01*
G01X1141928Y216495D02*
X1142308Y216078D01*
X1142751Y215828D01*
X1143321Y215745D01*
X1143891Y215912D01*
X1144334Y216245D01*
X1144651Y216828D01*
X1144714Y217495D01*
X1144588Y218162D01*
X1144271Y218578D01*
X1143828Y218912D01*
X1143384Y218995D01*
X1142941Y218912D01*
X1142371Y218578D01*
X1142561Y220745D01*
X1144271D01*
G01X1148421Y215578D02*
X1148294Y215662D01*
Y215828D01*
X1148421Y215912D01*
X1148548Y215828D01*
Y215662D01*
X1148421Y215578D01*
G01X1153521Y220745D02*
X1153014Y220578D01*
X1152634Y220162D01*
X1152381Y219662D01*
X1152191Y218995D01*
X1152128Y218245D01*
X1152191Y217495D01*
X1152381Y216828D01*
X1152634Y216328D01*
X1153014Y215912D01*
X1153521Y215745D01*
X1154028Y215912D01*
X1154408Y216328D01*
X1154661Y216828D01*
X1154851Y217495D01*
X1154914Y218245D01*
X1154851Y218995D01*
X1154661Y219662D01*
X1154408Y220162D01*
X1154028Y220578D01*
X1153521Y220745D01*
G01X1136828Y248445D02*
X1137208Y248028D01*
X1137651Y247778D01*
X1138221Y247695D01*
X1138791Y247862D01*
X1139234Y248195D01*
X1139551Y248778D01*
X1139614Y249445D01*
X1139488Y250112D01*
X1139171Y250528D01*
X1138728Y250862D01*
X1138284Y250945D01*
X1137841Y250862D01*
X1137271Y250528D01*
X1137461Y252695D01*
X1139171D01*
G01X1142244Y248278D02*
X1142688Y247862D01*
X1143194Y247695D01*
X1143701Y247862D01*
X1144144Y248362D01*
X1144461Y249112D01*
X1144588Y249862D01*
Y250778D01*
X1144461Y251528D01*
X1144144Y252195D01*
X1143764Y252528D01*
X1143321Y252695D01*
X1142814Y252528D01*
X1142434Y252195D01*
X1142181Y251695D01*
X1142054Y251028D01*
X1142181Y250445D01*
X1142498Y249862D01*
X1142878Y249528D01*
X1143321Y249445D01*
X1143828Y249612D01*
X1144208Y250028D01*
X1144588Y250778D01*
G01X1148421Y247528D02*
X1148294Y247612D01*
Y247778D01*
X1148421Y247862D01*
X1148548Y247778D01*
Y247612D01*
X1148421Y247528D01*
G01X1153521Y252695D02*
X1153014Y252528D01*
X1152634Y252112D01*
X1152381Y251612D01*
X1152191Y250945D01*
X1152128Y250195D01*
X1152191Y249445D01*
X1152381Y248778D01*
X1152634Y248278D01*
X1153014Y247862D01*
X1153521Y247695D01*
X1154028Y247862D01*
X1154408Y248278D01*
X1154661Y248778D01*
X1154851Y249445D01*
X1154914Y250195D01*
X1154851Y250945D01*
X1154661Y251612D01*
X1154408Y252112D01*
X1154028Y252528D01*
X1153521Y252695D01*
G01X1136828Y280395D02*
X1137208Y279978D01*
X1137651Y279728D01*
X1138221Y279645D01*
X1138791Y279812D01*
X1139234Y280145D01*
X1139551Y280728D01*
X1139614Y281395D01*
X1139488Y282062D01*
X1139171Y282478D01*
X1138728Y282812D01*
X1138284Y282895D01*
X1137841Y282812D01*
X1137271Y282478D01*
X1137461Y284645D01*
X1139171D01*
G01X1143321D02*
X1142814Y284478D01*
X1142434Y284062D01*
X1142181Y283562D01*
X1141991Y282895D01*
X1141928Y282145D01*
X1141991Y281395D01*
X1142181Y280728D01*
X1142434Y280228D01*
X1142814Y279812D01*
X1143321Y279645D01*
X1143828Y279812D01*
X1144208Y280228D01*
X1144461Y280728D01*
X1144651Y281395D01*
X1144714Y282145D01*
X1144651Y282895D01*
X1144461Y283562D01*
X1144208Y284062D01*
X1143828Y284478D01*
X1143321Y284645D01*
G01X1148421Y279478D02*
X1148294Y279562D01*
Y279728D01*
X1148421Y279812D01*
X1148548Y279728D01*
Y279562D01*
X1148421Y279478D01*
G01X1153521Y284645D02*
X1153014Y284478D01*
X1152634Y284062D01*
X1152381Y283562D01*
X1152191Y282895D01*
X1152128Y282145D01*
X1152191Y281395D01*
X1152381Y280728D01*
X1152634Y280228D01*
X1153014Y279812D01*
X1153521Y279645D01*
X1154028Y279812D01*
X1154408Y280228D01*
X1154661Y280728D01*
X1154851Y281395D01*
X1154914Y282145D01*
X1154851Y282895D01*
X1154661Y283562D01*
X1154408Y284062D01*
X1154028Y284478D01*
X1153521Y284645D01*
G01X1138981Y311595D02*
Y316595D01*
X1136638Y313012D01*
X1139804D01*
G01X1143194Y311595D02*
X1143321Y312678D01*
X1143511Y313595D01*
X1143764Y314428D01*
X1144081Y315345D01*
X1144588Y316595D01*
X1142054D01*
G01X1148421Y311428D02*
X1148294Y311512D01*
Y311678D01*
X1148421Y311762D01*
X1148548Y311678D01*
Y311512D01*
X1148421Y311428D01*
G01X1153521Y316595D02*
X1153014Y316428D01*
X1152634Y316012D01*
X1152381Y315512D01*
X1152191Y314845D01*
X1152128Y314095D01*
X1152191Y313345D01*
X1152381Y312678D01*
X1152634Y312178D01*
X1153014Y311762D01*
X1153521Y311595D01*
X1154028Y311762D01*
X1154408Y312178D01*
X1154661Y312678D01*
X1154851Y313345D01*
X1154914Y314095D01*
X1154851Y314845D01*
X1154661Y315512D01*
X1154408Y316012D01*
X1154028Y316428D01*
X1153521Y316595D01*
G01X1138981Y343545D02*
Y348545D01*
X1136638Y344962D01*
X1139804D01*
G01X1142118Y345628D02*
X1142561Y346212D01*
X1142941Y346545D01*
X1143448Y346712D01*
X1143891Y346545D01*
X1144208Y346212D01*
X1144461Y345712D01*
X1144524Y345128D01*
X1144461Y344628D01*
X1144208Y344128D01*
X1143828Y343712D01*
X1143384Y343545D01*
X1142878Y343712D01*
X1142434Y344212D01*
X1142181Y344962D01*
X1142118Y345795D01*
X1142244Y346878D01*
X1142434Y347462D01*
X1142751Y348045D01*
X1143194Y348462D01*
X1143638Y348545D01*
X1144081Y348378D01*
X1144398Y347962D01*
G01X1148421Y343378D02*
X1148294Y343462D01*
Y343628D01*
X1148421Y343712D01*
X1148548Y343628D01*
Y343462D01*
X1148421Y343378D01*
G01X1153521Y348545D02*
X1153014Y348378D01*
X1152634Y347962D01*
X1152381Y347462D01*
X1152191Y346795D01*
X1152128Y346045D01*
X1152191Y345295D01*
X1152381Y344628D01*
X1152634Y344128D01*
X1153014Y343712D01*
X1153521Y343545D01*
X1154028Y343712D01*
X1154408Y344128D01*
X1154661Y344628D01*
X1154851Y345295D01*
X1154914Y346045D01*
X1154851Y346795D01*
X1154661Y347462D01*
X1154408Y347962D01*
X1154028Y348378D01*
X1153521Y348545D01*
G01X1138981Y375495D02*
Y380495D01*
X1136638Y376912D01*
X1139804D01*
G01X1142118Y379662D02*
X1142498Y380162D01*
X1142941Y380412D01*
X1143448Y380495D01*
X1144081Y380328D01*
X1144524Y379912D01*
X1144651Y379412D01*
X1144588Y378912D01*
X1144334Y378495D01*
X1143068Y377662D01*
X1142498Y377078D01*
X1142118Y376245D01*
X1141991Y375495D01*
X1144651D01*
G01X1148421Y375328D02*
X1148294Y375412D01*
Y375578D01*
X1148421Y375662D01*
X1148548Y375578D01*
Y375412D01*
X1148421Y375328D01*
G01X1153521Y380495D02*
X1153014Y380328D01*
X1152634Y379912D01*
X1152381Y379412D01*
X1152191Y378745D01*
X1152128Y377995D01*
X1152191Y377245D01*
X1152381Y376578D01*
X1152634Y376078D01*
X1153014Y375662D01*
X1153521Y375495D01*
X1154028Y375662D01*
X1154408Y376078D01*
X1154661Y376578D01*
X1154851Y377245D01*
X1154914Y377995D01*
X1154851Y378745D01*
X1154661Y379412D01*
X1154408Y379912D01*
X1154028Y380328D01*
X1153521Y380495D01*
G01X1134468Y411612D02*
X1134848Y412112D01*
X1135291Y412362D01*
X1135798Y412445D01*
X1136431Y412278D01*
X1136874Y411862D01*
X1137001Y411362D01*
X1136938Y410862D01*
X1136684Y410445D01*
X1135418Y409612D01*
X1134848Y409028D01*
X1134468Y408195D01*
X1134341Y407445D01*
X1137001D01*
G01X1140771D02*
Y412445D01*
X1140011Y411445D01*
G01Y407445D02*
X1141531D01*
G01X1144478Y408445D02*
X1144858Y407862D01*
X1145364Y407528D01*
X1145934Y407445D01*
X1146441Y407528D01*
X1146948Y407945D01*
X1147264Y408445D01*
X1147328Y408945D01*
X1147201Y409528D01*
X1146758Y409945D01*
X1146314Y410112D01*
X1145744D01*
G01X1146314D02*
X1146694Y410362D01*
X1147011Y410778D01*
X1147138Y411278D01*
X1147011Y411778D01*
X1146694Y412195D01*
X1146124Y412445D01*
X1145554Y412362D01*
X1144984Y412028D01*
G01X1150971Y407278D02*
X1150844Y407362D01*
Y407528D01*
X1150971Y407612D01*
X1151098Y407528D01*
Y407362D01*
X1150971Y407278D01*
G01X1156071Y412445D02*
X1155564Y412278D01*
X1155184Y411862D01*
X1154931Y411362D01*
X1154741Y410695D01*
X1154678Y409945D01*
X1154741Y409195D01*
X1154931Y408528D01*
X1155184Y408028D01*
X1155564Y407612D01*
X1156071Y407445D01*
X1156578Y407612D01*
X1156958Y408028D01*
X1157211Y408528D01*
X1157401Y409195D01*
X1157464Y409945D01*
X1157401Y410695D01*
X1157211Y411362D01*
X1156958Y411862D01*
X1156578Y412278D01*
X1156071Y412445D01*
G01X1137144Y439978D02*
X1137588Y439562D01*
X1138094Y439395D01*
X1138601Y439562D01*
X1139044Y440062D01*
X1139361Y440812D01*
X1139488Y441562D01*
Y442478D01*
X1139361Y443228D01*
X1139044Y443895D01*
X1138664Y444228D01*
X1138221Y444395D01*
X1137714Y444228D01*
X1137334Y443895D01*
X1137081Y443395D01*
X1136954Y442728D01*
X1137081Y442145D01*
X1137398Y441562D01*
X1137778Y441228D01*
X1138221Y441145D01*
X1138728Y441312D01*
X1139108Y441728D01*
X1139488Y442478D01*
G01X1143321Y444395D02*
X1142814Y444228D01*
X1142434Y443812D01*
X1142181Y443312D01*
X1141991Y442645D01*
X1141928Y441895D01*
X1141991Y441145D01*
X1142181Y440478D01*
X1142434Y439978D01*
X1142814Y439562D01*
X1143321Y439395D01*
X1143828Y439562D01*
X1144208Y439978D01*
X1144461Y440478D01*
X1144651Y441145D01*
X1144714Y441895D01*
X1144651Y442645D01*
X1144461Y443312D01*
X1144208Y443812D01*
X1143828Y444228D01*
X1143321Y444395D01*
G01X1148421Y439228D02*
X1148294Y439312D01*
Y439478D01*
X1148421Y439562D01*
X1148548Y439478D01*
Y439312D01*
X1148421Y439228D01*
G01X1153521Y444395D02*
X1153014Y444228D01*
X1152634Y443812D01*
X1152381Y443312D01*
X1152191Y442645D01*
X1152128Y441895D01*
X1152191Y441145D01*
X1152381Y440478D01*
X1152634Y439978D01*
X1153014Y439562D01*
X1153521Y439395D01*
X1154028Y439562D01*
X1154408Y439978D01*
X1154661Y440478D01*
X1154851Y441145D01*
X1154914Y441895D01*
X1154851Y442645D01*
X1154661Y443312D01*
X1154408Y443812D01*
X1154028Y444228D01*
X1153521Y444395D01*
G01X1136828Y472095D02*
X1137208Y471678D01*
X1137651Y471428D01*
X1138221Y471345D01*
X1138791Y471512D01*
X1139234Y471845D01*
X1139551Y472428D01*
X1139614Y473095D01*
X1139488Y473762D01*
X1139171Y474178D01*
X1138728Y474512D01*
X1138284Y474595D01*
X1137841Y474512D01*
X1137271Y474178D01*
X1137461Y476345D01*
X1139171D01*
G01X1143194Y471345D02*
X1143321Y472428D01*
X1143511Y473345D01*
X1143764Y474178D01*
X1144081Y475095D01*
X1144588Y476345D01*
X1142054D01*
G01X1148421Y471178D02*
X1148294Y471262D01*
Y471428D01*
X1148421Y471512D01*
X1148548Y471428D01*
Y471262D01*
X1148421Y471178D01*
G01X1153521Y476345D02*
X1153014Y476178D01*
X1152634Y475762D01*
X1152381Y475262D01*
X1152191Y474595D01*
X1152128Y473845D01*
X1152191Y473095D01*
X1152381Y472428D01*
X1152634Y471928D01*
X1153014Y471512D01*
X1153521Y471345D01*
X1154028Y471512D01*
X1154408Y471928D01*
X1154661Y472428D01*
X1154851Y473095D01*
X1154914Y473845D01*
X1154851Y474595D01*
X1154661Y475262D01*
X1154408Y475762D01*
X1154028Y476178D01*
X1153521Y476345D01*
G01X1136828Y504045D02*
X1137208Y503628D01*
X1137651Y503378D01*
X1138221Y503295D01*
X1138791Y503462D01*
X1139234Y503795D01*
X1139551Y504378D01*
X1139614Y505045D01*
X1139488Y505712D01*
X1139171Y506128D01*
X1138728Y506462D01*
X1138284Y506545D01*
X1137841Y506462D01*
X1137271Y506128D01*
X1137461Y508295D01*
X1139171D01*
G01X1142118Y505378D02*
X1142561Y505962D01*
X1142941Y506295D01*
X1143448Y506462D01*
X1143891Y506295D01*
X1144208Y505962D01*
X1144461Y505462D01*
X1144524Y504878D01*
X1144461Y504378D01*
X1144208Y503878D01*
X1143828Y503462D01*
X1143384Y503295D01*
X1142878Y503462D01*
X1142434Y503962D01*
X1142181Y504712D01*
X1142118Y505545D01*
X1142244Y506628D01*
X1142434Y507212D01*
X1142751Y507795D01*
X1143194Y508212D01*
X1143638Y508295D01*
X1144081Y508128D01*
X1144398Y507712D01*
G01X1148421Y503128D02*
X1148294Y503212D01*
Y503378D01*
X1148421Y503462D01*
X1148548Y503378D01*
Y503212D01*
X1148421Y503128D01*
G01X1153521Y508295D02*
X1153014Y508128D01*
X1152634Y507712D01*
X1152381Y507212D01*
X1152191Y506545D01*
X1152128Y505795D01*
X1152191Y505045D01*
X1152381Y504378D01*
X1152634Y503878D01*
X1153014Y503462D01*
X1153521Y503295D01*
X1154028Y503462D01*
X1154408Y503878D01*
X1154661Y504378D01*
X1154851Y505045D01*
X1154914Y505795D01*
X1154851Y506545D01*
X1154661Y507212D01*
X1154408Y507712D01*
X1154028Y508128D01*
X1153521Y508295D01*
G01X1138981Y535245D02*
Y540245D01*
X1136638Y536662D01*
X1139804D01*
G01X1143321Y535245D02*
X1143764Y535328D01*
X1144271Y535578D01*
X1144588Y535995D01*
X1144714Y536578D01*
X1144588Y537162D01*
X1144208Y537662D01*
X1143638Y537912D01*
X1143004D01*
X1142624Y538078D01*
X1142308Y538495D01*
X1142181Y539078D01*
X1142371Y539662D01*
X1142814Y540078D01*
X1143321Y540245D01*
X1143828Y540078D01*
X1144271Y539662D01*
X1144461Y539078D01*
X1144334Y538495D01*
X1144018Y538078D01*
X1143638Y537912D01*
X1143004D01*
X1142434Y537662D01*
X1142054Y537162D01*
X1141928Y536578D01*
X1142054Y535995D01*
X1142371Y535578D01*
X1142878Y535328D01*
X1143321Y535245D01*
G01X1148421Y535078D02*
X1148294Y535162D01*
Y535328D01*
X1148421Y535412D01*
X1148548Y535328D01*
Y535162D01*
X1148421Y535078D01*
G01X1153521Y540245D02*
X1153014Y540078D01*
X1152634Y539662D01*
X1152381Y539162D01*
X1152191Y538495D01*
X1152128Y537745D01*
X1152191Y536995D01*
X1152381Y536328D01*
X1152634Y535828D01*
X1153014Y535412D01*
X1153521Y535245D01*
X1154028Y535412D01*
X1154408Y535828D01*
X1154661Y536328D01*
X1154851Y536995D01*
X1154914Y537745D01*
X1154851Y538495D01*
X1154661Y539162D01*
X1154408Y539662D01*
X1154028Y540078D01*
X1153521Y540245D01*
G01X1138981Y567195D02*
Y572195D01*
X1136638Y568612D01*
X1139804D01*
G01X1142118Y569278D02*
X1142561Y569862D01*
X1142941Y570195D01*
X1143448Y570362D01*
X1143891Y570195D01*
X1144208Y569862D01*
X1144461Y569362D01*
X1144524Y568778D01*
X1144461Y568278D01*
X1144208Y567778D01*
X1143828Y567362D01*
X1143384Y567195D01*
X1142878Y567362D01*
X1142434Y567862D01*
X1142181Y568612D01*
X1142118Y569445D01*
X1142244Y570528D01*
X1142434Y571112D01*
X1142751Y571695D01*
X1143194Y572112D01*
X1143638Y572195D01*
X1144081Y572028D01*
X1144398Y571612D01*
G01X1148421Y567028D02*
X1148294Y567112D01*
Y567278D01*
X1148421Y567362D01*
X1148548Y567278D01*
Y567112D01*
X1148421Y567028D01*
G01X1153521Y572195D02*
X1153014Y572028D01*
X1152634Y571612D01*
X1152381Y571112D01*
X1152191Y570445D01*
X1152128Y569695D01*
X1152191Y568945D01*
X1152381Y568278D01*
X1152634Y567778D01*
X1153014Y567362D01*
X1153521Y567195D01*
X1154028Y567362D01*
X1154408Y567778D01*
X1154661Y568278D01*
X1154851Y568945D01*
X1154914Y569695D01*
X1154851Y570445D01*
X1154661Y571112D01*
X1154408Y571612D01*
X1154028Y572028D01*
X1153521Y572195D01*
G01X1138981Y599145D02*
Y604145D01*
X1136638Y600562D01*
X1139804D01*
G01X1144081Y599145D02*
Y604145D01*
X1141738Y600562D01*
X1144904D01*
G01X1148421Y598978D02*
X1148294Y599062D01*
Y599228D01*
X1148421Y599312D01*
X1148548Y599228D01*
Y599062D01*
X1148421Y598978D01*
G01X1153521Y604145D02*
X1153014Y603978D01*
X1152634Y603562D01*
X1152381Y603062D01*
X1152191Y602395D01*
X1152128Y601645D01*
X1152191Y600895D01*
X1152381Y600228D01*
X1152634Y599728D01*
X1153014Y599312D01*
X1153521Y599145D01*
X1154028Y599312D01*
X1154408Y599728D01*
X1154661Y600228D01*
X1154851Y600895D01*
X1154914Y601645D01*
X1154851Y602395D01*
X1154661Y603062D01*
X1154408Y603562D01*
X1154028Y603978D01*
X1153521Y604145D01*
G01X1138981Y631095D02*
Y636095D01*
X1136638Y632512D01*
X1139804D01*
G01X1143321Y631095D02*
Y636095D01*
X1142561Y635095D01*
G01Y631095D02*
X1144081D01*
G01X1148421Y630928D02*
X1148294Y631012D01*
Y631178D01*
X1148421Y631262D01*
X1148548Y631178D01*
Y631012D01*
X1148421Y630928D01*
G01X1153521Y636095D02*
X1153014Y635928D01*
X1152634Y635512D01*
X1152381Y635012D01*
X1152191Y634345D01*
X1152128Y633595D01*
X1152191Y632845D01*
X1152381Y632178D01*
X1152634Y631678D01*
X1153014Y631262D01*
X1153521Y631095D01*
X1154028Y631262D01*
X1154408Y631678D01*
X1154661Y632178D01*
X1154851Y632845D01*
X1154914Y633595D01*
X1154851Y634345D01*
X1154661Y635012D01*
X1154408Y635512D01*
X1154028Y635928D01*
X1153521Y636095D01*
G01X1138981Y663045D02*
Y668045D01*
X1136638Y664462D01*
X1139804D01*
G01X1143321Y668045D02*
X1142814Y667878D01*
X1142434Y667462D01*
X1142181Y666962D01*
X1141991Y666295D01*
X1141928Y665545D01*
X1141991Y664795D01*
X1142181Y664128D01*
X1142434Y663628D01*
X1142814Y663212D01*
X1143321Y663045D01*
X1143828Y663212D01*
X1144208Y663628D01*
X1144461Y664128D01*
X1144651Y664795D01*
X1144714Y665545D01*
X1144651Y666295D01*
X1144461Y666962D01*
X1144208Y667462D01*
X1143828Y667878D01*
X1143321Y668045D01*
G01X1148421Y662878D02*
X1148294Y662962D01*
Y663128D01*
X1148421Y663212D01*
X1148548Y663128D01*
Y662962D01*
X1148421Y662878D01*
G01X1153521Y668045D02*
X1153014Y667878D01*
X1152634Y667462D01*
X1152381Y666962D01*
X1152191Y666295D01*
X1152128Y665545D01*
X1152191Y664795D01*
X1152381Y664128D01*
X1152634Y663628D01*
X1153014Y663212D01*
X1153521Y663045D01*
X1154028Y663212D01*
X1154408Y663628D01*
X1154661Y664128D01*
X1154851Y664795D01*
X1154914Y665545D01*
X1154851Y666295D01*
X1154661Y666962D01*
X1154408Y667462D01*
X1154028Y667878D01*
X1153521Y668045D01*
G01X1136828Y695995D02*
X1137208Y695412D01*
X1137714Y695078D01*
X1138284Y694995D01*
X1138791Y695078D01*
X1139298Y695495D01*
X1139614Y695995D01*
X1139678Y696495D01*
X1139551Y697078D01*
X1139108Y697495D01*
X1138664Y697662D01*
X1138094D01*
G01X1138664D02*
X1139044Y697912D01*
X1139361Y698328D01*
X1139488Y698828D01*
X1139361Y699328D01*
X1139044Y699745D01*
X1138474Y699995D01*
X1137904Y699912D01*
X1137334Y699578D01*
G01X1142118Y697078D02*
X1142561Y697662D01*
X1142941Y697995D01*
X1143448Y698162D01*
X1143891Y697995D01*
X1144208Y697662D01*
X1144461Y697162D01*
X1144524Y696578D01*
X1144461Y696078D01*
X1144208Y695578D01*
X1143828Y695162D01*
X1143384Y694995D01*
X1142878Y695162D01*
X1142434Y695662D01*
X1142181Y696412D01*
X1142118Y697245D01*
X1142244Y698328D01*
X1142434Y698912D01*
X1142751Y699495D01*
X1143194Y699912D01*
X1143638Y699995D01*
X1144081Y699828D01*
X1144398Y699412D01*
G01X1148421Y694828D02*
X1148294Y694912D01*
Y695078D01*
X1148421Y695162D01*
X1148548Y695078D01*
Y694912D01*
X1148421Y694828D01*
G01X1153521Y699995D02*
X1153014Y699828D01*
X1152634Y699412D01*
X1152381Y698912D01*
X1152191Y698245D01*
X1152128Y697495D01*
X1152191Y696745D01*
X1152381Y696078D01*
X1152634Y695578D01*
X1153014Y695162D01*
X1153521Y694995D01*
X1154028Y695162D01*
X1154408Y695578D01*
X1154661Y696078D01*
X1154851Y696745D01*
X1154914Y697495D01*
X1154851Y698245D01*
X1154661Y698912D01*
X1154408Y699412D01*
X1154028Y699828D01*
X1153521Y699995D01*
G01X1136828Y727945D02*
X1137208Y727362D01*
X1137714Y727028D01*
X1138284Y726945D01*
X1138791Y727028D01*
X1139298Y727445D01*
X1139614Y727945D01*
X1139678Y728445D01*
X1139551Y729028D01*
X1139108Y729445D01*
X1138664Y729612D01*
X1138094D01*
G01X1138664D02*
X1139044Y729862D01*
X1139361Y730278D01*
X1139488Y730778D01*
X1139361Y731278D01*
X1139044Y731695D01*
X1138474Y731945D01*
X1137904Y731862D01*
X1137334Y731528D01*
G01X1141928Y727945D02*
X1142308Y727362D01*
X1142814Y727028D01*
X1143384Y726945D01*
X1143891Y727028D01*
X1144398Y727445D01*
X1144714Y727945D01*
X1144778Y728445D01*
X1144651Y729028D01*
X1144208Y729445D01*
X1143764Y729612D01*
X1143194D01*
G01X1143764D02*
X1144144Y729862D01*
X1144461Y730278D01*
X1144588Y730778D01*
X1144461Y731278D01*
X1144144Y731695D01*
X1143574Y731945D01*
X1143004Y731862D01*
X1142434Y731528D01*
G01X1148421Y726778D02*
X1148294Y726862D01*
Y727028D01*
X1148421Y727112D01*
X1148548Y727028D01*
Y726862D01*
X1148421Y726778D01*
G01X1153521Y731945D02*
X1153014Y731778D01*
X1152634Y731362D01*
X1152381Y730862D01*
X1152191Y730195D01*
X1152128Y729445D01*
X1152191Y728695D01*
X1152381Y728028D01*
X1152634Y727528D01*
X1153014Y727112D01*
X1153521Y726945D01*
X1154028Y727112D01*
X1154408Y727528D01*
X1154661Y728028D01*
X1154851Y728695D01*
X1154914Y729445D01*
X1154851Y730195D01*
X1154661Y730862D01*
X1154408Y731362D01*
X1154028Y731778D01*
X1153521Y731945D01*
G01X1137018Y763062D02*
X1137398Y763562D01*
X1137841Y763812D01*
X1138348Y763895D01*
X1138981Y763728D01*
X1139424Y763312D01*
X1139551Y762812D01*
X1139488Y762312D01*
X1139234Y761895D01*
X1137968Y761062D01*
X1137398Y760478D01*
X1137018Y759645D01*
X1136891Y758895D01*
X1139551D01*
G01X1142118Y760978D02*
X1142561Y761562D01*
X1142941Y761895D01*
X1143448Y762062D01*
X1143891Y761895D01*
X1144208Y761562D01*
X1144461Y761062D01*
X1144524Y760478D01*
X1144461Y759978D01*
X1144208Y759478D01*
X1143828Y759062D01*
X1143384Y758895D01*
X1142878Y759062D01*
X1142434Y759562D01*
X1142181Y760312D01*
X1142118Y761145D01*
X1142244Y762228D01*
X1142434Y762812D01*
X1142751Y763395D01*
X1143194Y763812D01*
X1143638Y763895D01*
X1144081Y763728D01*
X1144398Y763312D01*
G01X1148421Y758728D02*
X1148294Y758812D01*
Y758978D01*
X1148421Y759062D01*
X1148548Y758978D01*
Y758812D01*
X1148421Y758728D01*
G01X1153521Y763895D02*
X1153014Y763728D01*
X1152634Y763312D01*
X1152381Y762812D01*
X1152191Y762145D01*
X1152128Y761395D01*
X1152191Y760645D01*
X1152381Y759978D01*
X1152634Y759478D01*
X1153014Y759062D01*
X1153521Y758895D01*
X1154028Y759062D01*
X1154408Y759478D01*
X1154661Y759978D01*
X1154851Y760645D01*
X1154914Y761395D01*
X1154851Y762145D01*
X1154661Y762812D01*
X1154408Y763312D01*
X1154028Y763728D01*
X1153521Y763895D01*
G01X1137018Y795012D02*
X1137398Y795512D01*
X1137841Y795762D01*
X1138348Y795845D01*
X1138981Y795678D01*
X1139424Y795262D01*
X1139551Y794762D01*
X1139488Y794262D01*
X1139234Y793845D01*
X1137968Y793012D01*
X1137398Y792428D01*
X1137018Y791595D01*
X1136891Y790845D01*
X1139551D01*
G01X1142118Y795012D02*
X1142498Y795512D01*
X1142941Y795762D01*
X1143448Y795845D01*
X1144081Y795678D01*
X1144524Y795262D01*
X1144651Y794762D01*
X1144588Y794262D01*
X1144334Y793845D01*
X1143068Y793012D01*
X1142498Y792428D01*
X1142118Y791595D01*
X1141991Y790845D01*
X1144651D01*
G01X1148421Y790678D02*
X1148294Y790762D01*
Y790928D01*
X1148421Y791012D01*
X1148548Y790928D01*
Y790762D01*
X1148421Y790678D01*
G01X1153521Y795845D02*
X1153014Y795678D01*
X1152634Y795262D01*
X1152381Y794762D01*
X1152191Y794095D01*
X1152128Y793345D01*
X1152191Y792595D01*
X1152381Y791928D01*
X1152634Y791428D01*
X1153014Y791012D01*
X1153521Y790845D01*
X1154028Y791012D01*
X1154408Y791428D01*
X1154661Y791928D01*
X1154851Y792595D01*
X1154914Y793345D01*
X1154851Y794095D01*
X1154661Y794762D01*
X1154408Y795262D01*
X1154028Y795678D01*
X1153521Y795845D01*
G01X1138221Y822795D02*
Y827795D01*
X1137461Y826795D01*
G01Y822795D02*
X1138981D01*
G01X1143321Y827795D02*
X1142814Y827628D01*
X1142434Y827212D01*
X1142181Y826712D01*
X1141991Y826045D01*
X1141928Y825295D01*
X1141991Y824545D01*
X1142181Y823878D01*
X1142434Y823378D01*
X1142814Y822962D01*
X1143321Y822795D01*
X1143828Y822962D01*
X1144208Y823378D01*
X1144461Y823878D01*
X1144651Y824545D01*
X1144714Y825295D01*
X1144651Y826045D01*
X1144461Y826712D01*
X1144208Y827212D01*
X1143828Y827628D01*
X1143321Y827795D01*
G01X1148421Y822628D02*
X1148294Y822712D01*
Y822878D01*
X1148421Y822962D01*
X1148548Y822878D01*
Y822712D01*
X1148421Y822628D01*
G01X1153521Y827795D02*
X1153014Y827628D01*
X1152634Y827212D01*
X1152381Y826712D01*
X1152191Y826045D01*
X1152128Y825295D01*
X1152191Y824545D01*
X1152381Y823878D01*
X1152634Y823378D01*
X1153014Y822962D01*
X1153521Y822795D01*
X1154028Y822962D01*
X1154408Y823378D01*
X1154661Y823878D01*
X1154851Y824545D01*
X1154914Y825295D01*
X1154851Y826045D01*
X1154661Y826712D01*
X1154408Y827212D01*
X1154028Y827628D01*
X1153521Y827795D01*
G01X1138221Y854745D02*
Y859745D01*
X1137461Y858745D01*
G01Y854745D02*
X1138981D01*
G01X1143321Y859745D02*
X1142814Y859578D01*
X1142434Y859162D01*
X1142181Y858662D01*
X1141991Y857995D01*
X1141928Y857245D01*
X1141991Y856495D01*
X1142181Y855828D01*
X1142434Y855328D01*
X1142814Y854912D01*
X1143321Y854745D01*
X1143828Y854912D01*
X1144208Y855328D01*
X1144461Y855828D01*
X1144651Y856495D01*
X1144714Y857245D01*
X1144651Y857995D01*
X1144461Y858662D01*
X1144208Y859162D01*
X1143828Y859578D01*
X1143321Y859745D01*
G01X1148421Y854578D02*
X1148294Y854662D01*
Y854828D01*
X1148421Y854912D01*
X1148548Y854828D01*
Y854662D01*
X1148421Y854578D01*
G01X1153521Y859745D02*
X1153014Y859578D01*
X1152634Y859162D01*
X1152381Y858662D01*
X1152191Y857995D01*
X1152128Y857245D01*
X1152191Y856495D01*
X1152381Y855828D01*
X1152634Y855328D01*
X1153014Y854912D01*
X1153521Y854745D01*
X1154028Y854912D01*
X1154408Y855328D01*
X1154661Y855828D01*
X1154851Y856495D01*
X1154914Y857245D01*
X1154851Y857995D01*
X1154661Y858662D01*
X1154408Y859162D01*
X1154028Y859578D01*
X1153521Y859745D01*
G01X1138221Y886695D02*
Y891695D01*
X1137461Y890695D01*
G01Y886695D02*
X1138981D01*
G01X1143321Y891695D02*
X1142814Y891528D01*
X1142434Y891112D01*
X1142181Y890612D01*
X1141991Y889945D01*
X1141928Y889195D01*
X1141991Y888445D01*
X1142181Y887778D01*
X1142434Y887278D01*
X1142814Y886862D01*
X1143321Y886695D01*
X1143828Y886862D01*
X1144208Y887278D01*
X1144461Y887778D01*
X1144651Y888445D01*
X1144714Y889195D01*
X1144651Y889945D01*
X1144461Y890612D01*
X1144208Y891112D01*
X1143828Y891528D01*
X1143321Y891695D01*
G01X1148421Y886528D02*
X1148294Y886612D01*
Y886778D01*
X1148421Y886862D01*
X1148548Y886778D01*
Y886612D01*
X1148421Y886528D01*
G01X1153521Y891695D02*
X1153014Y891528D01*
X1152634Y891112D01*
X1152381Y890612D01*
X1152191Y889945D01*
X1152128Y889195D01*
X1152191Y888445D01*
X1152381Y887778D01*
X1152634Y887278D01*
X1153014Y886862D01*
X1153521Y886695D01*
X1154028Y886862D01*
X1154408Y887278D01*
X1154661Y887778D01*
X1154851Y888445D01*
X1154914Y889195D01*
X1154851Y889945D01*
X1154661Y890612D01*
X1154408Y891112D01*
X1154028Y891528D01*
X1153521Y891695D01*
G01X1138221Y918645D02*
Y923645D01*
X1137461Y922645D01*
G01Y918645D02*
X1138981D01*
G01X1143321Y923645D02*
X1142814Y923478D01*
X1142434Y923062D01*
X1142181Y922562D01*
X1141991Y921895D01*
X1141928Y921145D01*
X1141991Y920395D01*
X1142181Y919728D01*
X1142434Y919228D01*
X1142814Y918812D01*
X1143321Y918645D01*
X1143828Y918812D01*
X1144208Y919228D01*
X1144461Y919728D01*
X1144651Y920395D01*
X1144714Y921145D01*
X1144651Y921895D01*
X1144461Y922562D01*
X1144208Y923062D01*
X1143828Y923478D01*
X1143321Y923645D01*
G01X1148421Y918478D02*
X1148294Y918562D01*
Y918728D01*
X1148421Y918812D01*
X1148548Y918728D01*
Y918562D01*
X1148421Y918478D01*
G01X1153521Y923645D02*
X1153014Y923478D01*
X1152634Y923062D01*
X1152381Y922562D01*
X1152191Y921895D01*
X1152128Y921145D01*
X1152191Y920395D01*
X1152381Y919728D01*
X1152634Y919228D01*
X1153014Y918812D01*
X1153521Y918645D01*
X1154028Y918812D01*
X1154408Y919228D01*
X1154661Y919728D01*
X1154851Y920395D01*
X1154914Y921145D01*
X1154851Y921895D01*
X1154661Y922562D01*
X1154408Y923062D01*
X1154028Y923478D01*
X1153521Y923645D01*
G01X1138221Y950595D02*
Y955595D01*
X1137461Y954595D01*
G01Y950595D02*
X1138981D01*
G01X1143321Y955595D02*
X1142814Y955428D01*
X1142434Y955012D01*
X1142181Y954512D01*
X1141991Y953845D01*
X1141928Y953095D01*
X1141991Y952345D01*
X1142181Y951678D01*
X1142434Y951178D01*
X1142814Y950762D01*
X1143321Y950595D01*
X1143828Y950762D01*
X1144208Y951178D01*
X1144461Y951678D01*
X1144651Y952345D01*
X1144714Y953095D01*
X1144651Y953845D01*
X1144461Y954512D01*
X1144208Y955012D01*
X1143828Y955428D01*
X1143321Y955595D01*
G01X1148421Y950428D02*
X1148294Y950512D01*
Y950678D01*
X1148421Y950762D01*
X1148548Y950678D01*
Y950512D01*
X1148421Y950428D01*
G01X1153521Y955595D02*
X1153014Y955428D01*
X1152634Y955012D01*
X1152381Y954512D01*
X1152191Y953845D01*
X1152128Y953095D01*
X1152191Y952345D01*
X1152381Y951678D01*
X1152634Y951178D01*
X1153014Y950762D01*
X1153521Y950595D01*
X1154028Y950762D01*
X1154408Y951178D01*
X1154661Y951678D01*
X1154851Y952345D01*
X1154914Y953095D01*
X1154851Y953845D01*
X1154661Y954512D01*
X1154408Y955012D01*
X1154028Y955428D01*
X1153521Y955595D01*
G01X1136891Y973537D02*
X1137398Y973120D01*
X1137968Y972870D01*
X1138474D01*
X1138981Y973120D01*
X1139361Y973537D01*
X1139551Y974120D01*
X1139424Y974703D01*
X1139108Y975203D01*
X1138538Y975537D01*
X1137778Y975703D01*
X1137334Y976037D01*
X1137144Y976620D01*
X1137271Y977203D01*
X1137588Y977620D01*
X1138031Y977870D01*
X1138474D01*
X1138918Y977703D01*
X1139298Y977287D01*
G01X1142561Y977870D02*
X1144081D01*
G01X1143321D02*
Y972870D01*
G01X1142561D02*
X1144081D01*
G01X1147218Y977870D02*
X1149624D01*
X1147218Y972870D01*
X1149624D01*
G01X1154788D02*
X1152254D01*
Y977870D01*
X1154788D01*
G01X1153774Y975453D02*
X1152254D01*
G01X1155788Y984170D02*
X1157371Y989170D01*
X1158954Y984170D01*
G01X1158384Y985920D02*
X1156358D01*
G01X1161204Y989170D02*
Y984170D01*
X1163738D01*
G01X1166304Y989170D02*
Y984170D01*
X1168838D01*
G01X1176378Y989170D02*
Y985587D01*
X1176631Y984837D01*
X1177138Y984337D01*
X1177771Y984170D01*
X1178404Y984337D01*
X1178911Y984837D01*
X1179164Y985587D01*
Y989170D01*
G01X1181414Y984170D02*
Y989170D01*
X1184328Y984170D01*
Y989170D01*
G01X1187211D02*
X1188731D01*
G01X1187971D02*
Y984170D01*
G01X1187211D02*
X1188731D01*
G01X1193071Y989170D02*
Y984170D01*
G01X1191614Y989170D02*
X1194528D01*
G01X1196841Y984837D02*
X1197348Y984420D01*
X1197918Y984170D01*
X1198424D01*
X1198931Y984420D01*
X1199311Y984837D01*
X1199501Y985420D01*
X1199374Y986003D01*
X1199058Y986503D01*
X1198488Y986837D01*
X1197728Y987003D01*
X1197284Y987337D01*
X1197094Y987920D01*
X1197221Y988503D01*
X1197538Y988920D01*
X1197981Y989170D01*
X1198424D01*
X1198868Y989003D01*
X1199248Y988587D01*
G01X1206788Y984170D02*
X1208371Y989170D01*
X1209954Y984170D01*
G01X1209384Y985920D02*
X1207358D01*
G01X1212204Y984170D02*
Y989170D01*
X1213788D01*
X1214294Y988920D01*
X1214611Y988587D01*
X1214738Y987920D01*
X1214611Y987253D01*
X1214231Y986837D01*
X1213788Y986587D01*
X1212204D01*
G01X1213788D02*
X1214738Y984170D01*
G01X1219838D02*
X1217304D01*
Y989170D01*
X1219838D01*
G01X1218824Y986753D02*
X1217304D01*
G01X1228011Y989170D02*
X1229531D01*
G01X1228771D02*
Y984170D01*
G01X1228011D02*
X1229531D01*
G01X1232414D02*
Y989170D01*
X1235328Y984170D01*
Y989170D01*
G01X1242424Y984170D02*
Y989170D01*
X1244071Y985003D01*
X1245718Y989170D01*
Y984170D01*
G01X1248411Y989170D02*
X1249931D01*
G01X1249171D02*
Y984170D01*
G01X1248411D02*
X1249931D01*
G01X1253004Y989170D02*
Y984170D01*
X1255538D01*
G01X1258041Y984837D02*
X1258548Y984420D01*
X1259118Y984170D01*
X1259624D01*
X1260131Y984420D01*
X1260511Y984837D01*
X1260701Y985420D01*
X1260574Y986003D01*
X1260258Y986503D01*
X1259688Y986837D01*
X1258928Y987003D01*
X1258484Y987337D01*
X1258294Y987920D01*
X1258421Y988503D01*
X1258738Y988920D01*
X1259181Y989170D01*
X1259624D01*
X1260068Y989003D01*
X1260448Y988587D01*
G01X1143228Y1009170D02*
Y1014170D01*
X1144494D01*
X1145001Y1013920D01*
X1145381Y1013587D01*
X1145698Y1013087D01*
X1145951Y1012503D01*
X1146014Y1011670D01*
X1145951Y1010837D01*
X1145698Y1010253D01*
X1145381Y1009753D01*
X1145001Y1009420D01*
X1144494Y1009170D01*
X1143228D01*
G01X1148454D02*
Y1014170D01*
X1150038D01*
X1150544Y1013920D01*
X1150861Y1013587D01*
X1150988Y1012920D01*
X1150861Y1012253D01*
X1150481Y1011837D01*
X1150038Y1011587D01*
X1148454D01*
G01X1150038D02*
X1150988Y1009170D01*
G01X1154061Y1014170D02*
X1155581D01*
G01X1154821D02*
Y1009170D01*
G01X1154061D02*
X1155581D01*
G01X1158654Y1014170D02*
Y1009170D01*
X1161188D01*
G01X1163754Y1014170D02*
Y1009170D01*
X1166288D01*
G01X1176614Y1013753D02*
X1176234Y1014003D01*
X1175791Y1014170D01*
X1175284D01*
X1174714Y1013920D01*
X1174271Y1013503D01*
X1173954Y1013003D01*
X1173701Y1012170D01*
X1173638Y1011420D01*
X1173764Y1010670D01*
X1173954Y1010170D01*
X1174334Y1009670D01*
X1174778Y1009337D01*
X1175221Y1009170D01*
X1175664D01*
X1176108Y1009337D01*
X1176488Y1009587D01*
X1176804Y1009920D01*
G01X1178991Y1009170D02*
Y1014170D01*
G01X1181651D02*
Y1009170D01*
G01Y1011670D02*
X1178991D01*
G01X1183838Y1009170D02*
X1185421Y1014170D01*
X1187004Y1009170D01*
G01X1186434Y1010920D02*
X1184408D01*
G01X1189254Y1009170D02*
Y1014170D01*
X1190838D01*
X1191344Y1013920D01*
X1191661Y1013587D01*
X1191788Y1012920D01*
X1191661Y1012253D01*
X1191281Y1011837D01*
X1190838Y1011587D01*
X1189254D01*
G01X1190838D02*
X1191788Y1009170D01*
G01X1195621Y1014170D02*
Y1009170D01*
G01X1194164Y1014170D02*
X1197078D01*
G01X1200721Y1009003D02*
X1200594Y1009087D01*
Y1009253D01*
X1200721Y1009337D01*
X1200848Y1009253D01*
Y1009087D01*
X1200721Y1009003D01*
G01Y1011253D02*
X1200594Y1011337D01*
Y1011503D01*
X1200721Y1011587D01*
X1200848Y1011503D01*
Y1011337D01*
X1200721Y1011253D01*
G01X1210921Y1014170D02*
Y1009170D01*
G01X1209464Y1014170D02*
X1212378D01*
G01X1216021Y1009170D02*
X1215514Y1009253D01*
X1215071Y1009587D01*
X1214691Y1010087D01*
X1214438Y1010670D01*
X1214311Y1011337D01*
Y1012003D01*
X1214438Y1012670D01*
X1214691Y1013253D01*
X1215071Y1013753D01*
X1215514Y1014087D01*
X1216021Y1014170D01*
X1216528Y1014087D01*
X1216971Y1013753D01*
X1217351Y1013253D01*
X1217604Y1012670D01*
X1217731Y1012003D01*
Y1011337D01*
X1217604Y1010670D01*
X1217351Y1010087D01*
X1216971Y1009587D01*
X1216528Y1009253D01*
X1216021Y1009170D01*
G01X1219854D02*
Y1014170D01*
X1221374D01*
X1221881Y1013920D01*
X1222261Y1013337D01*
X1222388Y1012670D01*
X1222261Y1012003D01*
X1221944Y1011503D01*
X1221374Y1011253D01*
X1219854D01*
G01X1231321Y1014170D02*
Y1009170D01*
G01X1230434Y1012503D02*
X1232208D01*
G01X1236421Y1009170D02*
X1236041Y1009253D01*
X1235661Y1009587D01*
X1235408Y1010170D01*
X1235281Y1010837D01*
X1235408Y1011503D01*
X1235661Y1012087D01*
X1236041Y1012420D01*
X1236421Y1012503D01*
X1236801Y1012420D01*
X1237181Y1012087D01*
X1237434Y1011503D01*
X1237498Y1010837D01*
X1237434Y1010170D01*
X1237181Y1009587D01*
X1236801Y1009253D01*
X1236421Y1009170D01*
G01X1247128Y1011837D02*
X1247381Y1012087D01*
X1247571Y1012503D01*
X1247698Y1013087D01*
X1247571Y1013587D01*
X1247318Y1013920D01*
X1246874Y1014170D01*
X1245164D01*
Y1009170D01*
X1247254D01*
X1247698Y1009503D01*
X1247951Y1010003D01*
X1248078Y1010587D01*
X1247951Y1011170D01*
X1247571Y1011670D01*
X1247128Y1011837D01*
X1245164D01*
G01X1251721Y1009170D02*
X1251214Y1009253D01*
X1250771Y1009587D01*
X1250391Y1010087D01*
X1250138Y1010670D01*
X1250011Y1011337D01*
Y1012003D01*
X1250138Y1012670D01*
X1250391Y1013253D01*
X1250771Y1013753D01*
X1251214Y1014087D01*
X1251721Y1014170D01*
X1252228Y1014087D01*
X1252671Y1013753D01*
X1253051Y1013253D01*
X1253304Y1012670D01*
X1253431Y1012003D01*
Y1011337D01*
X1253304Y1010670D01*
X1253051Y1010087D01*
X1252671Y1009587D01*
X1252228Y1009253D01*
X1251721Y1009170D01*
G01X1256821Y1014170D02*
Y1009170D01*
G01X1255364Y1014170D02*
X1258278D01*
G01X1261921D02*
Y1009170D01*
G01X1260464Y1014170D02*
X1263378D01*
G01X1267021Y1009170D02*
X1266514Y1009253D01*
X1266071Y1009587D01*
X1265691Y1010087D01*
X1265438Y1010670D01*
X1265311Y1011337D01*
Y1012003D01*
X1265438Y1012670D01*
X1265691Y1013253D01*
X1266071Y1013753D01*
X1266514Y1014087D01*
X1267021Y1014170D01*
X1267528Y1014087D01*
X1267971Y1013753D01*
X1268351Y1013253D01*
X1268604Y1012670D01*
X1268731Y1012003D01*
Y1011337D01*
X1268604Y1010670D01*
X1268351Y1010087D01*
X1267971Y1009587D01*
X1267528Y1009253D01*
X1267021Y1009170D01*
G01X1270474D02*
Y1014170D01*
X1272121Y1010003D01*
X1273768Y1014170D01*
Y1009170D01*
G01X1202574Y25712D02*
X1204094D01*
G01X1203271Y26795D02*
Y24628D01*
G01X1209131Y24045D02*
Y29045D01*
X1206788Y25462D01*
X1209954D01*
G01X1213471Y23878D02*
X1213344Y23962D01*
Y24128D01*
X1213471Y24212D01*
X1213598Y24128D01*
Y23962D01*
X1213471Y23878D01*
G01X1218571Y29045D02*
X1218064Y28878D01*
X1217684Y28462D01*
X1217431Y27962D01*
X1217241Y27295D01*
X1217178Y26545D01*
X1217241Y25795D01*
X1217431Y25128D01*
X1217684Y24628D01*
X1218064Y24212D01*
X1218571Y24045D01*
X1219078Y24212D01*
X1219458Y24628D01*
X1219711Y25128D01*
X1219901Y25795D01*
X1219964Y26545D01*
X1219901Y27295D01*
X1219711Y27962D01*
X1219458Y28462D01*
X1219078Y28878D01*
X1218571Y29045D01*
G01X1222531Y23878D02*
X1224811Y29045D01*
G01X1227948Y25712D02*
X1229594D01*
G01X1234631Y24045D02*
Y29045D01*
X1232288Y25462D01*
X1235454D01*
G01X1238971Y23878D02*
X1238844Y23962D01*
Y24128D01*
X1238971Y24212D01*
X1239098Y24128D01*
Y23962D01*
X1238971Y23878D01*
G01X1244071Y29045D02*
X1243564Y28878D01*
X1243184Y28462D01*
X1242931Y27962D01*
X1242741Y27295D01*
X1242678Y26545D01*
X1242741Y25795D01*
X1242931Y25128D01*
X1243184Y24628D01*
X1243564Y24212D01*
X1244071Y24045D01*
X1244578Y24212D01*
X1244958Y24628D01*
X1245211Y25128D01*
X1245401Y25795D01*
X1245464Y26545D01*
X1245401Y27295D01*
X1245211Y27962D01*
X1244958Y28462D01*
X1244578Y28878D01*
X1244071Y29045D01*
G01X1202574Y57662D02*
X1204094D01*
G01X1203271Y58745D02*
Y56578D01*
G01X1207168Y60162D02*
X1207548Y60662D01*
X1207991Y60912D01*
X1208498Y60995D01*
X1209131Y60828D01*
X1209574Y60412D01*
X1209701Y59912D01*
X1209638Y59412D01*
X1209384Y58995D01*
X1208118Y58162D01*
X1207548Y57578D01*
X1207168Y56745D01*
X1207041Y55995D01*
X1209701D01*
G01X1213471Y55828D02*
X1213344Y55912D01*
Y56078D01*
X1213471Y56162D01*
X1213598Y56078D01*
Y55912D01*
X1213471Y55828D01*
G01X1218571Y60995D02*
X1218064Y60828D01*
X1217684Y60412D01*
X1217431Y59912D01*
X1217241Y59245D01*
X1217178Y58495D01*
X1217241Y57745D01*
X1217431Y57078D01*
X1217684Y56578D01*
X1218064Y56162D01*
X1218571Y55995D01*
X1219078Y56162D01*
X1219458Y56578D01*
X1219711Y57078D01*
X1219901Y57745D01*
X1219964Y58495D01*
X1219901Y59245D01*
X1219711Y59912D01*
X1219458Y60412D01*
X1219078Y60828D01*
X1218571Y60995D01*
G01X1222531Y55828D02*
X1224811Y60995D01*
G01X1227948Y57662D02*
X1229594D01*
G01X1232668Y60162D02*
X1233048Y60662D01*
X1233491Y60912D01*
X1233998Y60995D01*
X1234631Y60828D01*
X1235074Y60412D01*
X1235201Y59912D01*
X1235138Y59412D01*
X1234884Y58995D01*
X1233618Y58162D01*
X1233048Y57578D01*
X1232668Y56745D01*
X1232541Y55995D01*
X1235201D01*
G01X1238971Y55828D02*
X1238844Y55912D01*
Y56078D01*
X1238971Y56162D01*
X1239098Y56078D01*
Y55912D01*
X1238971Y55828D01*
G01X1244071Y60995D02*
X1243564Y60828D01*
X1243184Y60412D01*
X1242931Y59912D01*
X1242741Y59245D01*
X1242678Y58495D01*
X1242741Y57745D01*
X1242931Y57078D01*
X1243184Y56578D01*
X1243564Y56162D01*
X1244071Y55995D01*
X1244578Y56162D01*
X1244958Y56578D01*
X1245211Y57078D01*
X1245401Y57745D01*
X1245464Y58495D01*
X1245401Y59245D01*
X1245211Y59912D01*
X1244958Y60412D01*
X1244578Y60828D01*
X1244071Y60995D01*
G01X1202574Y89612D02*
X1204094D01*
G01X1203271Y90695D02*
Y88528D01*
G01X1207168Y92112D02*
X1207548Y92612D01*
X1207991Y92862D01*
X1208498Y92945D01*
X1209131Y92778D01*
X1209574Y92362D01*
X1209701Y91862D01*
X1209638Y91362D01*
X1209384Y90945D01*
X1208118Y90112D01*
X1207548Y89528D01*
X1207168Y88695D01*
X1207041Y87945D01*
X1209701D01*
G01X1213471Y87778D02*
X1213344Y87862D01*
Y88028D01*
X1213471Y88112D01*
X1213598Y88028D01*
Y87862D01*
X1213471Y87778D01*
G01X1218571Y92945D02*
X1218064Y92778D01*
X1217684Y92362D01*
X1217431Y91862D01*
X1217241Y91195D01*
X1217178Y90445D01*
X1217241Y89695D01*
X1217431Y89028D01*
X1217684Y88528D01*
X1218064Y88112D01*
X1218571Y87945D01*
X1219078Y88112D01*
X1219458Y88528D01*
X1219711Y89028D01*
X1219901Y89695D01*
X1219964Y90445D01*
X1219901Y91195D01*
X1219711Y91862D01*
X1219458Y92362D01*
X1219078Y92778D01*
X1218571Y92945D01*
G01X1222531Y87778D02*
X1224811Y92945D01*
G01X1227948Y89612D02*
X1229594D01*
G01X1232668Y92112D02*
X1233048Y92612D01*
X1233491Y92862D01*
X1233998Y92945D01*
X1234631Y92778D01*
X1235074Y92362D01*
X1235201Y91862D01*
X1235138Y91362D01*
X1234884Y90945D01*
X1233618Y90112D01*
X1233048Y89528D01*
X1232668Y88695D01*
X1232541Y87945D01*
X1235201D01*
G01X1238971Y87778D02*
X1238844Y87862D01*
Y88028D01*
X1238971Y88112D01*
X1239098Y88028D01*
Y87862D01*
X1238971Y87778D01*
G01X1244071Y92945D02*
X1243564Y92778D01*
X1243184Y92362D01*
X1242931Y91862D01*
X1242741Y91195D01*
X1242678Y90445D01*
X1242741Y89695D01*
X1242931Y89028D01*
X1243184Y88528D01*
X1243564Y88112D01*
X1244071Y87945D01*
X1244578Y88112D01*
X1244958Y88528D01*
X1245211Y89028D01*
X1245401Y89695D01*
X1245464Y90445D01*
X1245401Y91195D01*
X1245211Y91862D01*
X1244958Y92362D01*
X1244578Y92778D01*
X1244071Y92945D01*
G01X1202574Y121562D02*
X1204094D01*
G01X1203271Y122645D02*
Y120478D01*
G01X1207168Y124062D02*
X1207548Y124562D01*
X1207991Y124812D01*
X1208498Y124895D01*
X1209131Y124728D01*
X1209574Y124312D01*
X1209701Y123812D01*
X1209638Y123312D01*
X1209384Y122895D01*
X1208118Y122062D01*
X1207548Y121478D01*
X1207168Y120645D01*
X1207041Y119895D01*
X1209701D01*
G01X1213471Y119728D02*
X1213344Y119812D01*
Y119978D01*
X1213471Y120062D01*
X1213598Y119978D01*
Y119812D01*
X1213471Y119728D01*
G01X1218571Y124895D02*
X1218064Y124728D01*
X1217684Y124312D01*
X1217431Y123812D01*
X1217241Y123145D01*
X1217178Y122395D01*
X1217241Y121645D01*
X1217431Y120978D01*
X1217684Y120478D01*
X1218064Y120062D01*
X1218571Y119895D01*
X1219078Y120062D01*
X1219458Y120478D01*
X1219711Y120978D01*
X1219901Y121645D01*
X1219964Y122395D01*
X1219901Y123145D01*
X1219711Y123812D01*
X1219458Y124312D01*
X1219078Y124728D01*
X1218571Y124895D01*
G01X1222531Y119728D02*
X1224811Y124895D01*
G01X1227948Y121562D02*
X1229594D01*
G01X1232668Y124062D02*
X1233048Y124562D01*
X1233491Y124812D01*
X1233998Y124895D01*
X1234631Y124728D01*
X1235074Y124312D01*
X1235201Y123812D01*
X1235138Y123312D01*
X1234884Y122895D01*
X1233618Y122062D01*
X1233048Y121478D01*
X1232668Y120645D01*
X1232541Y119895D01*
X1235201D01*
G01X1238971Y119728D02*
X1238844Y119812D01*
Y119978D01*
X1238971Y120062D01*
X1239098Y119978D01*
Y119812D01*
X1238971Y119728D01*
G01X1244071Y124895D02*
X1243564Y124728D01*
X1243184Y124312D01*
X1242931Y123812D01*
X1242741Y123145D01*
X1242678Y122395D01*
X1242741Y121645D01*
X1242931Y120978D01*
X1243184Y120478D01*
X1243564Y120062D01*
X1244071Y119895D01*
X1244578Y120062D01*
X1244958Y120478D01*
X1245211Y120978D01*
X1245401Y121645D01*
X1245464Y122395D01*
X1245401Y123145D01*
X1245211Y123812D01*
X1244958Y124312D01*
X1244578Y124728D01*
X1244071Y124895D01*
G01X1202574Y153512D02*
X1204094D01*
G01X1203271Y154595D02*
Y152428D01*
G01X1207168Y156012D02*
X1207548Y156512D01*
X1207991Y156762D01*
X1208498Y156845D01*
X1209131Y156678D01*
X1209574Y156262D01*
X1209701Y155762D01*
X1209638Y155262D01*
X1209384Y154845D01*
X1208118Y154012D01*
X1207548Y153428D01*
X1207168Y152595D01*
X1207041Y151845D01*
X1209701D01*
G01X1213471Y151678D02*
X1213344Y151762D01*
Y151928D01*
X1213471Y152012D01*
X1213598Y151928D01*
Y151762D01*
X1213471Y151678D01*
G01X1218571Y156845D02*
X1218064Y156678D01*
X1217684Y156262D01*
X1217431Y155762D01*
X1217241Y155095D01*
X1217178Y154345D01*
X1217241Y153595D01*
X1217431Y152928D01*
X1217684Y152428D01*
X1218064Y152012D01*
X1218571Y151845D01*
X1219078Y152012D01*
X1219458Y152428D01*
X1219711Y152928D01*
X1219901Y153595D01*
X1219964Y154345D01*
X1219901Y155095D01*
X1219711Y155762D01*
X1219458Y156262D01*
X1219078Y156678D01*
X1218571Y156845D01*
G01X1222531Y151678D02*
X1224811Y156845D01*
G01X1227948Y153512D02*
X1229594D01*
G01X1232668Y156012D02*
X1233048Y156512D01*
X1233491Y156762D01*
X1233998Y156845D01*
X1234631Y156678D01*
X1235074Y156262D01*
X1235201Y155762D01*
X1235138Y155262D01*
X1234884Y154845D01*
X1233618Y154012D01*
X1233048Y153428D01*
X1232668Y152595D01*
X1232541Y151845D01*
X1235201D01*
G01X1238971Y151678D02*
X1238844Y151762D01*
Y151928D01*
X1238971Y152012D01*
X1239098Y151928D01*
Y151762D01*
X1238971Y151678D01*
G01X1244071Y156845D02*
X1243564Y156678D01*
X1243184Y156262D01*
X1242931Y155762D01*
X1242741Y155095D01*
X1242678Y154345D01*
X1242741Y153595D01*
X1242931Y152928D01*
X1243184Y152428D01*
X1243564Y152012D01*
X1244071Y151845D01*
X1244578Y152012D01*
X1244958Y152428D01*
X1245211Y152928D01*
X1245401Y153595D01*
X1245464Y154345D01*
X1245401Y155095D01*
X1245211Y155762D01*
X1244958Y156262D01*
X1244578Y156678D01*
X1244071Y156845D01*
G01X1202574Y185462D02*
X1204094D01*
G01X1203271Y186545D02*
Y184378D01*
G01X1207168Y187962D02*
X1207548Y188462D01*
X1207991Y188712D01*
X1208498Y188795D01*
X1209131Y188628D01*
X1209574Y188212D01*
X1209701Y187712D01*
X1209638Y187212D01*
X1209384Y186795D01*
X1208118Y185962D01*
X1207548Y185378D01*
X1207168Y184545D01*
X1207041Y183795D01*
X1209701D01*
G01X1213471Y183628D02*
X1213344Y183712D01*
Y183878D01*
X1213471Y183962D01*
X1213598Y183878D01*
Y183712D01*
X1213471Y183628D01*
G01X1218571Y188795D02*
X1218064Y188628D01*
X1217684Y188212D01*
X1217431Y187712D01*
X1217241Y187045D01*
X1217178Y186295D01*
X1217241Y185545D01*
X1217431Y184878D01*
X1217684Y184378D01*
X1218064Y183962D01*
X1218571Y183795D01*
X1219078Y183962D01*
X1219458Y184378D01*
X1219711Y184878D01*
X1219901Y185545D01*
X1219964Y186295D01*
X1219901Y187045D01*
X1219711Y187712D01*
X1219458Y188212D01*
X1219078Y188628D01*
X1218571Y188795D01*
G01X1222531Y183628D02*
X1224811Y188795D01*
G01X1227948Y185462D02*
X1229594D01*
G01X1232668Y187962D02*
X1233048Y188462D01*
X1233491Y188712D01*
X1233998Y188795D01*
X1234631Y188628D01*
X1235074Y188212D01*
X1235201Y187712D01*
X1235138Y187212D01*
X1234884Y186795D01*
X1233618Y185962D01*
X1233048Y185378D01*
X1232668Y184545D01*
X1232541Y183795D01*
X1235201D01*
G01X1238971Y183628D02*
X1238844Y183712D01*
Y183878D01*
X1238971Y183962D01*
X1239098Y183878D01*
Y183712D01*
X1238971Y183628D01*
G01X1244071Y188795D02*
X1243564Y188628D01*
X1243184Y188212D01*
X1242931Y187712D01*
X1242741Y187045D01*
X1242678Y186295D01*
X1242741Y185545D01*
X1242931Y184878D01*
X1243184Y184378D01*
X1243564Y183962D01*
X1244071Y183795D01*
X1244578Y183962D01*
X1244958Y184378D01*
X1245211Y184878D01*
X1245401Y185545D01*
X1245464Y186295D01*
X1245401Y187045D01*
X1245211Y187712D01*
X1244958Y188212D01*
X1244578Y188628D01*
X1244071Y188795D01*
G01X1202574Y217412D02*
X1204094D01*
G01X1203271Y218495D02*
Y216328D01*
G01X1207168Y219912D02*
X1207548Y220412D01*
X1207991Y220662D01*
X1208498Y220745D01*
X1209131Y220578D01*
X1209574Y220162D01*
X1209701Y219662D01*
X1209638Y219162D01*
X1209384Y218745D01*
X1208118Y217912D01*
X1207548Y217328D01*
X1207168Y216495D01*
X1207041Y215745D01*
X1209701D01*
G01X1213471Y215578D02*
X1213344Y215662D01*
Y215828D01*
X1213471Y215912D01*
X1213598Y215828D01*
Y215662D01*
X1213471Y215578D01*
G01X1218571Y220745D02*
X1218064Y220578D01*
X1217684Y220162D01*
X1217431Y219662D01*
X1217241Y218995D01*
X1217178Y218245D01*
X1217241Y217495D01*
X1217431Y216828D01*
X1217684Y216328D01*
X1218064Y215912D01*
X1218571Y215745D01*
X1219078Y215912D01*
X1219458Y216328D01*
X1219711Y216828D01*
X1219901Y217495D01*
X1219964Y218245D01*
X1219901Y218995D01*
X1219711Y219662D01*
X1219458Y220162D01*
X1219078Y220578D01*
X1218571Y220745D01*
G01X1222531Y215578D02*
X1224811Y220745D01*
G01X1227948Y217412D02*
X1229594D01*
G01X1232668Y219912D02*
X1233048Y220412D01*
X1233491Y220662D01*
X1233998Y220745D01*
X1234631Y220578D01*
X1235074Y220162D01*
X1235201Y219662D01*
X1235138Y219162D01*
X1234884Y218745D01*
X1233618Y217912D01*
X1233048Y217328D01*
X1232668Y216495D01*
X1232541Y215745D01*
X1235201D01*
G01X1238971Y215578D02*
X1238844Y215662D01*
Y215828D01*
X1238971Y215912D01*
X1239098Y215828D01*
Y215662D01*
X1238971Y215578D01*
G01X1244071Y220745D02*
X1243564Y220578D01*
X1243184Y220162D01*
X1242931Y219662D01*
X1242741Y218995D01*
X1242678Y218245D01*
X1242741Y217495D01*
X1242931Y216828D01*
X1243184Y216328D01*
X1243564Y215912D01*
X1244071Y215745D01*
X1244578Y215912D01*
X1244958Y216328D01*
X1245211Y216828D01*
X1245401Y217495D01*
X1245464Y218245D01*
X1245401Y218995D01*
X1245211Y219662D01*
X1244958Y220162D01*
X1244578Y220578D01*
X1244071Y220745D01*
G01X1202574Y249362D02*
X1204094D01*
G01X1203271Y250445D02*
Y248278D01*
G01X1207168Y251862D02*
X1207548Y252362D01*
X1207991Y252612D01*
X1208498Y252695D01*
X1209131Y252528D01*
X1209574Y252112D01*
X1209701Y251612D01*
X1209638Y251112D01*
X1209384Y250695D01*
X1208118Y249862D01*
X1207548Y249278D01*
X1207168Y248445D01*
X1207041Y247695D01*
X1209701D01*
G01X1213471Y247528D02*
X1213344Y247612D01*
Y247778D01*
X1213471Y247862D01*
X1213598Y247778D01*
Y247612D01*
X1213471Y247528D01*
G01X1218571Y252695D02*
X1218064Y252528D01*
X1217684Y252112D01*
X1217431Y251612D01*
X1217241Y250945D01*
X1217178Y250195D01*
X1217241Y249445D01*
X1217431Y248778D01*
X1217684Y248278D01*
X1218064Y247862D01*
X1218571Y247695D01*
X1219078Y247862D01*
X1219458Y248278D01*
X1219711Y248778D01*
X1219901Y249445D01*
X1219964Y250195D01*
X1219901Y250945D01*
X1219711Y251612D01*
X1219458Y252112D01*
X1219078Y252528D01*
X1218571Y252695D01*
G01X1222531Y247528D02*
X1224811Y252695D01*
G01X1227948Y249362D02*
X1229594D01*
G01X1232668Y251862D02*
X1233048Y252362D01*
X1233491Y252612D01*
X1233998Y252695D01*
X1234631Y252528D01*
X1235074Y252112D01*
X1235201Y251612D01*
X1235138Y251112D01*
X1234884Y250695D01*
X1233618Y249862D01*
X1233048Y249278D01*
X1232668Y248445D01*
X1232541Y247695D01*
X1235201D01*
G01X1238971Y247528D02*
X1238844Y247612D01*
Y247778D01*
X1238971Y247862D01*
X1239098Y247778D01*
Y247612D01*
X1238971Y247528D01*
G01X1244071Y252695D02*
X1243564Y252528D01*
X1243184Y252112D01*
X1242931Y251612D01*
X1242741Y250945D01*
X1242678Y250195D01*
X1242741Y249445D01*
X1242931Y248778D01*
X1243184Y248278D01*
X1243564Y247862D01*
X1244071Y247695D01*
X1244578Y247862D01*
X1244958Y248278D01*
X1245211Y248778D01*
X1245401Y249445D01*
X1245464Y250195D01*
X1245401Y250945D01*
X1245211Y251612D01*
X1244958Y252112D01*
X1244578Y252528D01*
X1244071Y252695D01*
G01X1202574Y281312D02*
X1204094D01*
G01X1203271Y282395D02*
Y280228D01*
G01X1207168Y283812D02*
X1207548Y284312D01*
X1207991Y284562D01*
X1208498Y284645D01*
X1209131Y284478D01*
X1209574Y284062D01*
X1209701Y283562D01*
X1209638Y283062D01*
X1209384Y282645D01*
X1208118Y281812D01*
X1207548Y281228D01*
X1207168Y280395D01*
X1207041Y279645D01*
X1209701D01*
G01X1213471Y279478D02*
X1213344Y279562D01*
Y279728D01*
X1213471Y279812D01*
X1213598Y279728D01*
Y279562D01*
X1213471Y279478D01*
G01X1218571Y284645D02*
X1218064Y284478D01*
X1217684Y284062D01*
X1217431Y283562D01*
X1217241Y282895D01*
X1217178Y282145D01*
X1217241Y281395D01*
X1217431Y280728D01*
X1217684Y280228D01*
X1218064Y279812D01*
X1218571Y279645D01*
X1219078Y279812D01*
X1219458Y280228D01*
X1219711Y280728D01*
X1219901Y281395D01*
X1219964Y282145D01*
X1219901Y282895D01*
X1219711Y283562D01*
X1219458Y284062D01*
X1219078Y284478D01*
X1218571Y284645D01*
G01X1222531Y279478D02*
X1224811Y284645D01*
G01X1227948Y281312D02*
X1229594D01*
G01X1232668Y283812D02*
X1233048Y284312D01*
X1233491Y284562D01*
X1233998Y284645D01*
X1234631Y284478D01*
X1235074Y284062D01*
X1235201Y283562D01*
X1235138Y283062D01*
X1234884Y282645D01*
X1233618Y281812D01*
X1233048Y281228D01*
X1232668Y280395D01*
X1232541Y279645D01*
X1235201D01*
G01X1238971Y279478D02*
X1238844Y279562D01*
Y279728D01*
X1238971Y279812D01*
X1239098Y279728D01*
Y279562D01*
X1238971Y279478D01*
G01X1244071Y284645D02*
X1243564Y284478D01*
X1243184Y284062D01*
X1242931Y283562D01*
X1242741Y282895D01*
X1242678Y282145D01*
X1242741Y281395D01*
X1242931Y280728D01*
X1243184Y280228D01*
X1243564Y279812D01*
X1244071Y279645D01*
X1244578Y279812D01*
X1244958Y280228D01*
X1245211Y280728D01*
X1245401Y281395D01*
X1245464Y282145D01*
X1245401Y282895D01*
X1245211Y283562D01*
X1244958Y284062D01*
X1244578Y284478D01*
X1244071Y284645D01*
G01X1202574Y313262D02*
X1204094D01*
G01X1203271Y314345D02*
Y312178D01*
G01X1207168Y315762D02*
X1207548Y316262D01*
X1207991Y316512D01*
X1208498Y316595D01*
X1209131Y316428D01*
X1209574Y316012D01*
X1209701Y315512D01*
X1209638Y315012D01*
X1209384Y314595D01*
X1208118Y313762D01*
X1207548Y313178D01*
X1207168Y312345D01*
X1207041Y311595D01*
X1209701D01*
G01X1213471Y311428D02*
X1213344Y311512D01*
Y311678D01*
X1213471Y311762D01*
X1213598Y311678D01*
Y311512D01*
X1213471Y311428D01*
G01X1218571Y316595D02*
X1218064Y316428D01*
X1217684Y316012D01*
X1217431Y315512D01*
X1217241Y314845D01*
X1217178Y314095D01*
X1217241Y313345D01*
X1217431Y312678D01*
X1217684Y312178D01*
X1218064Y311762D01*
X1218571Y311595D01*
X1219078Y311762D01*
X1219458Y312178D01*
X1219711Y312678D01*
X1219901Y313345D01*
X1219964Y314095D01*
X1219901Y314845D01*
X1219711Y315512D01*
X1219458Y316012D01*
X1219078Y316428D01*
X1218571Y316595D01*
G01X1222531Y311428D02*
X1224811Y316595D01*
G01X1227948Y313262D02*
X1229594D01*
G01X1232668Y315762D02*
X1233048Y316262D01*
X1233491Y316512D01*
X1233998Y316595D01*
X1234631Y316428D01*
X1235074Y316012D01*
X1235201Y315512D01*
X1235138Y315012D01*
X1234884Y314595D01*
X1233618Y313762D01*
X1233048Y313178D01*
X1232668Y312345D01*
X1232541Y311595D01*
X1235201D01*
G01X1238971Y311428D02*
X1238844Y311512D01*
Y311678D01*
X1238971Y311762D01*
X1239098Y311678D01*
Y311512D01*
X1238971Y311428D01*
G01X1244071Y316595D02*
X1243564Y316428D01*
X1243184Y316012D01*
X1242931Y315512D01*
X1242741Y314845D01*
X1242678Y314095D01*
X1242741Y313345D01*
X1242931Y312678D01*
X1243184Y312178D01*
X1243564Y311762D01*
X1244071Y311595D01*
X1244578Y311762D01*
X1244958Y312178D01*
X1245211Y312678D01*
X1245401Y313345D01*
X1245464Y314095D01*
X1245401Y314845D01*
X1245211Y315512D01*
X1244958Y316012D01*
X1244578Y316428D01*
X1244071Y316595D01*
G01X1202574Y345212D02*
X1204094D01*
G01X1203271Y346295D02*
Y344128D01*
G01X1207168Y347712D02*
X1207548Y348212D01*
X1207991Y348462D01*
X1208498Y348545D01*
X1209131Y348378D01*
X1209574Y347962D01*
X1209701Y347462D01*
X1209638Y346962D01*
X1209384Y346545D01*
X1208118Y345712D01*
X1207548Y345128D01*
X1207168Y344295D01*
X1207041Y343545D01*
X1209701D01*
G01X1213471Y343378D02*
X1213344Y343462D01*
Y343628D01*
X1213471Y343712D01*
X1213598Y343628D01*
Y343462D01*
X1213471Y343378D01*
G01X1218571Y348545D02*
X1218064Y348378D01*
X1217684Y347962D01*
X1217431Y347462D01*
X1217241Y346795D01*
X1217178Y346045D01*
X1217241Y345295D01*
X1217431Y344628D01*
X1217684Y344128D01*
X1218064Y343712D01*
X1218571Y343545D01*
X1219078Y343712D01*
X1219458Y344128D01*
X1219711Y344628D01*
X1219901Y345295D01*
X1219964Y346045D01*
X1219901Y346795D01*
X1219711Y347462D01*
X1219458Y347962D01*
X1219078Y348378D01*
X1218571Y348545D01*
G01X1222531Y343378D02*
X1224811Y348545D01*
G01X1227948Y345212D02*
X1229594D01*
G01X1232668Y347712D02*
X1233048Y348212D01*
X1233491Y348462D01*
X1233998Y348545D01*
X1234631Y348378D01*
X1235074Y347962D01*
X1235201Y347462D01*
X1235138Y346962D01*
X1234884Y346545D01*
X1233618Y345712D01*
X1233048Y345128D01*
X1232668Y344295D01*
X1232541Y343545D01*
X1235201D01*
G01X1238971Y343378D02*
X1238844Y343462D01*
Y343628D01*
X1238971Y343712D01*
X1239098Y343628D01*
Y343462D01*
X1238971Y343378D01*
G01X1244071Y348545D02*
X1243564Y348378D01*
X1243184Y347962D01*
X1242931Y347462D01*
X1242741Y346795D01*
X1242678Y346045D01*
X1242741Y345295D01*
X1242931Y344628D01*
X1243184Y344128D01*
X1243564Y343712D01*
X1244071Y343545D01*
X1244578Y343712D01*
X1244958Y344128D01*
X1245211Y344628D01*
X1245401Y345295D01*
X1245464Y346045D01*
X1245401Y346795D01*
X1245211Y347462D01*
X1244958Y347962D01*
X1244578Y348378D01*
X1244071Y348545D01*
G01X1202574Y377162D02*
X1204094D01*
G01X1203271Y378245D02*
Y376078D01*
G01X1207168Y379662D02*
X1207548Y380162D01*
X1207991Y380412D01*
X1208498Y380495D01*
X1209131Y380328D01*
X1209574Y379912D01*
X1209701Y379412D01*
X1209638Y378912D01*
X1209384Y378495D01*
X1208118Y377662D01*
X1207548Y377078D01*
X1207168Y376245D01*
X1207041Y375495D01*
X1209701D01*
G01X1213471Y375328D02*
X1213344Y375412D01*
Y375578D01*
X1213471Y375662D01*
X1213598Y375578D01*
Y375412D01*
X1213471Y375328D01*
G01X1218571Y380495D02*
X1218064Y380328D01*
X1217684Y379912D01*
X1217431Y379412D01*
X1217241Y378745D01*
X1217178Y377995D01*
X1217241Y377245D01*
X1217431Y376578D01*
X1217684Y376078D01*
X1218064Y375662D01*
X1218571Y375495D01*
X1219078Y375662D01*
X1219458Y376078D01*
X1219711Y376578D01*
X1219901Y377245D01*
X1219964Y377995D01*
X1219901Y378745D01*
X1219711Y379412D01*
X1219458Y379912D01*
X1219078Y380328D01*
X1218571Y380495D01*
G01X1222531Y375328D02*
X1224811Y380495D01*
G01X1227948Y377162D02*
X1229594D01*
G01X1232668Y379662D02*
X1233048Y380162D01*
X1233491Y380412D01*
X1233998Y380495D01*
X1234631Y380328D01*
X1235074Y379912D01*
X1235201Y379412D01*
X1235138Y378912D01*
X1234884Y378495D01*
X1233618Y377662D01*
X1233048Y377078D01*
X1232668Y376245D01*
X1232541Y375495D01*
X1235201D01*
G01X1238971Y375328D02*
X1238844Y375412D01*
Y375578D01*
X1238971Y375662D01*
X1239098Y375578D01*
Y375412D01*
X1238971Y375328D01*
G01X1244071Y380495D02*
X1243564Y380328D01*
X1243184Y379912D01*
X1242931Y379412D01*
X1242741Y378745D01*
X1242678Y377995D01*
X1242741Y377245D01*
X1242931Y376578D01*
X1243184Y376078D01*
X1243564Y375662D01*
X1244071Y375495D01*
X1244578Y375662D01*
X1244958Y376078D01*
X1245211Y376578D01*
X1245401Y377245D01*
X1245464Y377995D01*
X1245401Y378745D01*
X1245211Y379412D01*
X1244958Y379912D01*
X1244578Y380328D01*
X1244071Y380495D01*
G01X1202574Y409112D02*
X1204094D01*
G01X1203271Y410195D02*
Y408028D01*
G01X1207168Y411612D02*
X1207548Y412112D01*
X1207991Y412362D01*
X1208498Y412445D01*
X1209131Y412278D01*
X1209574Y411862D01*
X1209701Y411362D01*
X1209638Y410862D01*
X1209384Y410445D01*
X1208118Y409612D01*
X1207548Y409028D01*
X1207168Y408195D01*
X1207041Y407445D01*
X1209701D01*
G01X1213471Y407278D02*
X1213344Y407362D01*
Y407528D01*
X1213471Y407612D01*
X1213598Y407528D01*
Y407362D01*
X1213471Y407278D01*
G01X1218571Y412445D02*
X1218064Y412278D01*
X1217684Y411862D01*
X1217431Y411362D01*
X1217241Y410695D01*
X1217178Y409945D01*
X1217241Y409195D01*
X1217431Y408528D01*
X1217684Y408028D01*
X1218064Y407612D01*
X1218571Y407445D01*
X1219078Y407612D01*
X1219458Y408028D01*
X1219711Y408528D01*
X1219901Y409195D01*
X1219964Y409945D01*
X1219901Y410695D01*
X1219711Y411362D01*
X1219458Y411862D01*
X1219078Y412278D01*
X1218571Y412445D01*
G01X1222531Y407278D02*
X1224811Y412445D01*
G01X1227948Y409112D02*
X1229594D01*
G01X1232668Y411612D02*
X1233048Y412112D01*
X1233491Y412362D01*
X1233998Y412445D01*
X1234631Y412278D01*
X1235074Y411862D01*
X1235201Y411362D01*
X1235138Y410862D01*
X1234884Y410445D01*
X1233618Y409612D01*
X1233048Y409028D01*
X1232668Y408195D01*
X1232541Y407445D01*
X1235201D01*
G01X1238971Y407278D02*
X1238844Y407362D01*
Y407528D01*
X1238971Y407612D01*
X1239098Y407528D01*
Y407362D01*
X1238971Y407278D01*
G01X1244071Y412445D02*
X1243564Y412278D01*
X1243184Y411862D01*
X1242931Y411362D01*
X1242741Y410695D01*
X1242678Y409945D01*
X1242741Y409195D01*
X1242931Y408528D01*
X1243184Y408028D01*
X1243564Y407612D01*
X1244071Y407445D01*
X1244578Y407612D01*
X1244958Y408028D01*
X1245211Y408528D01*
X1245401Y409195D01*
X1245464Y409945D01*
X1245401Y410695D01*
X1245211Y411362D01*
X1244958Y411862D01*
X1244578Y412278D01*
X1244071Y412445D01*
G01X1202574Y441062D02*
X1204094D01*
G01X1203271Y442145D02*
Y439978D01*
G01X1206978Y440395D02*
X1207358Y439812D01*
X1207864Y439478D01*
X1208434Y439395D01*
X1208941Y439478D01*
X1209448Y439895D01*
X1209764Y440395D01*
X1209828Y440895D01*
X1209701Y441478D01*
X1209258Y441895D01*
X1208814Y442062D01*
X1208244D01*
G01X1208814D02*
X1209194Y442312D01*
X1209511Y442728D01*
X1209638Y443228D01*
X1209511Y443728D01*
X1209194Y444145D01*
X1208624Y444395D01*
X1208054Y444312D01*
X1207484Y443978D01*
G01X1213471Y439228D02*
X1213344Y439312D01*
Y439478D01*
X1213471Y439562D01*
X1213598Y439478D01*
Y439312D01*
X1213471Y439228D01*
G01X1218571Y444395D02*
X1218064Y444228D01*
X1217684Y443812D01*
X1217431Y443312D01*
X1217241Y442645D01*
X1217178Y441895D01*
X1217241Y441145D01*
X1217431Y440478D01*
X1217684Y439978D01*
X1218064Y439562D01*
X1218571Y439395D01*
X1219078Y439562D01*
X1219458Y439978D01*
X1219711Y440478D01*
X1219901Y441145D01*
X1219964Y441895D01*
X1219901Y442645D01*
X1219711Y443312D01*
X1219458Y443812D01*
X1219078Y444228D01*
X1218571Y444395D01*
G01X1222531Y439228D02*
X1224811Y444395D01*
G01X1227948Y441062D02*
X1229594D01*
G01X1232478Y440395D02*
X1232858Y439812D01*
X1233364Y439478D01*
X1233934Y439395D01*
X1234441Y439478D01*
X1234948Y439895D01*
X1235264Y440395D01*
X1235328Y440895D01*
X1235201Y441478D01*
X1234758Y441895D01*
X1234314Y442062D01*
X1233744D01*
G01X1234314D02*
X1234694Y442312D01*
X1235011Y442728D01*
X1235138Y443228D01*
X1235011Y443728D01*
X1234694Y444145D01*
X1234124Y444395D01*
X1233554Y444312D01*
X1232984Y443978D01*
G01X1238971Y439228D02*
X1238844Y439312D01*
Y439478D01*
X1238971Y439562D01*
X1239098Y439478D01*
Y439312D01*
X1238971Y439228D01*
G01X1244071Y444395D02*
X1243564Y444228D01*
X1243184Y443812D01*
X1242931Y443312D01*
X1242741Y442645D01*
X1242678Y441895D01*
X1242741Y441145D01*
X1242931Y440478D01*
X1243184Y439978D01*
X1243564Y439562D01*
X1244071Y439395D01*
X1244578Y439562D01*
X1244958Y439978D01*
X1245211Y440478D01*
X1245401Y441145D01*
X1245464Y441895D01*
X1245401Y442645D01*
X1245211Y443312D01*
X1244958Y443812D01*
X1244578Y444228D01*
X1244071Y444395D01*
G01X1202574Y473012D02*
X1204094D01*
G01X1203271Y474095D02*
Y471928D01*
G01X1206978Y472345D02*
X1207358Y471762D01*
X1207864Y471428D01*
X1208434Y471345D01*
X1208941Y471428D01*
X1209448Y471845D01*
X1209764Y472345D01*
X1209828Y472845D01*
X1209701Y473428D01*
X1209258Y473845D01*
X1208814Y474012D01*
X1208244D01*
G01X1208814D02*
X1209194Y474262D01*
X1209511Y474678D01*
X1209638Y475178D01*
X1209511Y475678D01*
X1209194Y476095D01*
X1208624Y476345D01*
X1208054Y476262D01*
X1207484Y475928D01*
G01X1213471Y471178D02*
X1213344Y471262D01*
Y471428D01*
X1213471Y471512D01*
X1213598Y471428D01*
Y471262D01*
X1213471Y471178D01*
G01X1218571Y476345D02*
X1218064Y476178D01*
X1217684Y475762D01*
X1217431Y475262D01*
X1217241Y474595D01*
X1217178Y473845D01*
X1217241Y473095D01*
X1217431Y472428D01*
X1217684Y471928D01*
X1218064Y471512D01*
X1218571Y471345D01*
X1219078Y471512D01*
X1219458Y471928D01*
X1219711Y472428D01*
X1219901Y473095D01*
X1219964Y473845D01*
X1219901Y474595D01*
X1219711Y475262D01*
X1219458Y475762D01*
X1219078Y476178D01*
X1218571Y476345D01*
G01X1222531Y471178D02*
X1224811Y476345D01*
G01X1227948Y473012D02*
X1229594D01*
G01X1232478Y472345D02*
X1232858Y471762D01*
X1233364Y471428D01*
X1233934Y471345D01*
X1234441Y471428D01*
X1234948Y471845D01*
X1235264Y472345D01*
X1235328Y472845D01*
X1235201Y473428D01*
X1234758Y473845D01*
X1234314Y474012D01*
X1233744D01*
G01X1234314D02*
X1234694Y474262D01*
X1235011Y474678D01*
X1235138Y475178D01*
X1235011Y475678D01*
X1234694Y476095D01*
X1234124Y476345D01*
X1233554Y476262D01*
X1232984Y475928D01*
G01X1238971Y471178D02*
X1238844Y471262D01*
Y471428D01*
X1238971Y471512D01*
X1239098Y471428D01*
Y471262D01*
X1238971Y471178D01*
G01X1244071Y476345D02*
X1243564Y476178D01*
X1243184Y475762D01*
X1242931Y475262D01*
X1242741Y474595D01*
X1242678Y473845D01*
X1242741Y473095D01*
X1242931Y472428D01*
X1243184Y471928D01*
X1243564Y471512D01*
X1244071Y471345D01*
X1244578Y471512D01*
X1244958Y471928D01*
X1245211Y472428D01*
X1245401Y473095D01*
X1245464Y473845D01*
X1245401Y474595D01*
X1245211Y475262D01*
X1244958Y475762D01*
X1244578Y476178D01*
X1244071Y476345D01*
G01X1202574Y504962D02*
X1204094D01*
G01X1203271Y506045D02*
Y503878D01*
G01X1206978Y504295D02*
X1207358Y503712D01*
X1207864Y503378D01*
X1208434Y503295D01*
X1208941Y503378D01*
X1209448Y503795D01*
X1209764Y504295D01*
X1209828Y504795D01*
X1209701Y505378D01*
X1209258Y505795D01*
X1208814Y505962D01*
X1208244D01*
G01X1208814D02*
X1209194Y506212D01*
X1209511Y506628D01*
X1209638Y507128D01*
X1209511Y507628D01*
X1209194Y508045D01*
X1208624Y508295D01*
X1208054Y508212D01*
X1207484Y507878D01*
G01X1213471Y503128D02*
X1213344Y503212D01*
Y503378D01*
X1213471Y503462D01*
X1213598Y503378D01*
Y503212D01*
X1213471Y503128D01*
G01X1218571Y508295D02*
X1218064Y508128D01*
X1217684Y507712D01*
X1217431Y507212D01*
X1217241Y506545D01*
X1217178Y505795D01*
X1217241Y505045D01*
X1217431Y504378D01*
X1217684Y503878D01*
X1218064Y503462D01*
X1218571Y503295D01*
X1219078Y503462D01*
X1219458Y503878D01*
X1219711Y504378D01*
X1219901Y505045D01*
X1219964Y505795D01*
X1219901Y506545D01*
X1219711Y507212D01*
X1219458Y507712D01*
X1219078Y508128D01*
X1218571Y508295D01*
G01X1222531Y503128D02*
X1224811Y508295D01*
G01X1227948Y504962D02*
X1229594D01*
G01X1232478Y504295D02*
X1232858Y503712D01*
X1233364Y503378D01*
X1233934Y503295D01*
X1234441Y503378D01*
X1234948Y503795D01*
X1235264Y504295D01*
X1235328Y504795D01*
X1235201Y505378D01*
X1234758Y505795D01*
X1234314Y505962D01*
X1233744D01*
G01X1234314D02*
X1234694Y506212D01*
X1235011Y506628D01*
X1235138Y507128D01*
X1235011Y507628D01*
X1234694Y508045D01*
X1234124Y508295D01*
X1233554Y508212D01*
X1232984Y507878D01*
G01X1238971Y503128D02*
X1238844Y503212D01*
Y503378D01*
X1238971Y503462D01*
X1239098Y503378D01*
Y503212D01*
X1238971Y503128D01*
G01X1244071Y508295D02*
X1243564Y508128D01*
X1243184Y507712D01*
X1242931Y507212D01*
X1242741Y506545D01*
X1242678Y505795D01*
X1242741Y505045D01*
X1242931Y504378D01*
X1243184Y503878D01*
X1243564Y503462D01*
X1244071Y503295D01*
X1244578Y503462D01*
X1244958Y503878D01*
X1245211Y504378D01*
X1245401Y505045D01*
X1245464Y505795D01*
X1245401Y506545D01*
X1245211Y507212D01*
X1244958Y507712D01*
X1244578Y508128D01*
X1244071Y508295D01*
G01X1202574Y536912D02*
X1204094D01*
G01X1203271Y537995D02*
Y535828D01*
G01X1206978Y536245D02*
X1207358Y535662D01*
X1207864Y535328D01*
X1208434Y535245D01*
X1208941Y535328D01*
X1209448Y535745D01*
X1209764Y536245D01*
X1209828Y536745D01*
X1209701Y537328D01*
X1209258Y537745D01*
X1208814Y537912D01*
X1208244D01*
G01X1208814D02*
X1209194Y538162D01*
X1209511Y538578D01*
X1209638Y539078D01*
X1209511Y539578D01*
X1209194Y539995D01*
X1208624Y540245D01*
X1208054Y540162D01*
X1207484Y539828D01*
G01X1213471Y535078D02*
X1213344Y535162D01*
Y535328D01*
X1213471Y535412D01*
X1213598Y535328D01*
Y535162D01*
X1213471Y535078D01*
G01X1218571Y540245D02*
X1218064Y540078D01*
X1217684Y539662D01*
X1217431Y539162D01*
X1217241Y538495D01*
X1217178Y537745D01*
X1217241Y536995D01*
X1217431Y536328D01*
X1217684Y535828D01*
X1218064Y535412D01*
X1218571Y535245D01*
X1219078Y535412D01*
X1219458Y535828D01*
X1219711Y536328D01*
X1219901Y536995D01*
X1219964Y537745D01*
X1219901Y538495D01*
X1219711Y539162D01*
X1219458Y539662D01*
X1219078Y540078D01*
X1218571Y540245D01*
G01X1222531Y535078D02*
X1224811Y540245D01*
G01X1227948Y536912D02*
X1229594D01*
G01X1232478Y536245D02*
X1232858Y535662D01*
X1233364Y535328D01*
X1233934Y535245D01*
X1234441Y535328D01*
X1234948Y535745D01*
X1235264Y536245D01*
X1235328Y536745D01*
X1235201Y537328D01*
X1234758Y537745D01*
X1234314Y537912D01*
X1233744D01*
G01X1234314D02*
X1234694Y538162D01*
X1235011Y538578D01*
X1235138Y539078D01*
X1235011Y539578D01*
X1234694Y539995D01*
X1234124Y540245D01*
X1233554Y540162D01*
X1232984Y539828D01*
G01X1238971Y535078D02*
X1238844Y535162D01*
Y535328D01*
X1238971Y535412D01*
X1239098Y535328D01*
Y535162D01*
X1238971Y535078D01*
G01X1244071Y540245D02*
X1243564Y540078D01*
X1243184Y539662D01*
X1242931Y539162D01*
X1242741Y538495D01*
X1242678Y537745D01*
X1242741Y536995D01*
X1242931Y536328D01*
X1243184Y535828D01*
X1243564Y535412D01*
X1244071Y535245D01*
X1244578Y535412D01*
X1244958Y535828D01*
X1245211Y536328D01*
X1245401Y536995D01*
X1245464Y537745D01*
X1245401Y538495D01*
X1245211Y539162D01*
X1244958Y539662D01*
X1244578Y540078D01*
X1244071Y540245D01*
G01X1202574Y568862D02*
X1204094D01*
G01X1203271Y569945D02*
Y567778D01*
G01X1206978Y568195D02*
X1207358Y567612D01*
X1207864Y567278D01*
X1208434Y567195D01*
X1208941Y567278D01*
X1209448Y567695D01*
X1209764Y568195D01*
X1209828Y568695D01*
X1209701Y569278D01*
X1209258Y569695D01*
X1208814Y569862D01*
X1208244D01*
G01X1208814D02*
X1209194Y570112D01*
X1209511Y570528D01*
X1209638Y571028D01*
X1209511Y571528D01*
X1209194Y571945D01*
X1208624Y572195D01*
X1208054Y572112D01*
X1207484Y571778D01*
G01X1213471Y567028D02*
X1213344Y567112D01*
Y567278D01*
X1213471Y567362D01*
X1213598Y567278D01*
Y567112D01*
X1213471Y567028D01*
G01X1218571Y572195D02*
X1218064Y572028D01*
X1217684Y571612D01*
X1217431Y571112D01*
X1217241Y570445D01*
X1217178Y569695D01*
X1217241Y568945D01*
X1217431Y568278D01*
X1217684Y567778D01*
X1218064Y567362D01*
X1218571Y567195D01*
X1219078Y567362D01*
X1219458Y567778D01*
X1219711Y568278D01*
X1219901Y568945D01*
X1219964Y569695D01*
X1219901Y570445D01*
X1219711Y571112D01*
X1219458Y571612D01*
X1219078Y572028D01*
X1218571Y572195D01*
G01X1222531Y567028D02*
X1224811Y572195D01*
G01X1227948Y568862D02*
X1229594D01*
G01X1232478Y568195D02*
X1232858Y567612D01*
X1233364Y567278D01*
X1233934Y567195D01*
X1234441Y567278D01*
X1234948Y567695D01*
X1235264Y568195D01*
X1235328Y568695D01*
X1235201Y569278D01*
X1234758Y569695D01*
X1234314Y569862D01*
X1233744D01*
G01X1234314D02*
X1234694Y570112D01*
X1235011Y570528D01*
X1235138Y571028D01*
X1235011Y571528D01*
X1234694Y571945D01*
X1234124Y572195D01*
X1233554Y572112D01*
X1232984Y571778D01*
G01X1238971Y567028D02*
X1238844Y567112D01*
Y567278D01*
X1238971Y567362D01*
X1239098Y567278D01*
Y567112D01*
X1238971Y567028D01*
G01X1244071Y572195D02*
X1243564Y572028D01*
X1243184Y571612D01*
X1242931Y571112D01*
X1242741Y570445D01*
X1242678Y569695D01*
X1242741Y568945D01*
X1242931Y568278D01*
X1243184Y567778D01*
X1243564Y567362D01*
X1244071Y567195D01*
X1244578Y567362D01*
X1244958Y567778D01*
X1245211Y568278D01*
X1245401Y568945D01*
X1245464Y569695D01*
X1245401Y570445D01*
X1245211Y571112D01*
X1244958Y571612D01*
X1244578Y572028D01*
X1244071Y572195D01*
G01X1202574Y600812D02*
X1204094D01*
G01X1203271Y601895D02*
Y599728D01*
G01X1206978Y600145D02*
X1207358Y599562D01*
X1207864Y599228D01*
X1208434Y599145D01*
X1208941Y599228D01*
X1209448Y599645D01*
X1209764Y600145D01*
X1209828Y600645D01*
X1209701Y601228D01*
X1209258Y601645D01*
X1208814Y601812D01*
X1208244D01*
G01X1208814D02*
X1209194Y602062D01*
X1209511Y602478D01*
X1209638Y602978D01*
X1209511Y603478D01*
X1209194Y603895D01*
X1208624Y604145D01*
X1208054Y604062D01*
X1207484Y603728D01*
G01X1213471Y598978D02*
X1213344Y599062D01*
Y599228D01*
X1213471Y599312D01*
X1213598Y599228D01*
Y599062D01*
X1213471Y598978D01*
G01X1218571Y604145D02*
X1218064Y603978D01*
X1217684Y603562D01*
X1217431Y603062D01*
X1217241Y602395D01*
X1217178Y601645D01*
X1217241Y600895D01*
X1217431Y600228D01*
X1217684Y599728D01*
X1218064Y599312D01*
X1218571Y599145D01*
X1219078Y599312D01*
X1219458Y599728D01*
X1219711Y600228D01*
X1219901Y600895D01*
X1219964Y601645D01*
X1219901Y602395D01*
X1219711Y603062D01*
X1219458Y603562D01*
X1219078Y603978D01*
X1218571Y604145D01*
G01X1222531Y598978D02*
X1224811Y604145D01*
G01X1227948Y600812D02*
X1229594D01*
G01X1232478Y600145D02*
X1232858Y599562D01*
X1233364Y599228D01*
X1233934Y599145D01*
X1234441Y599228D01*
X1234948Y599645D01*
X1235264Y600145D01*
X1235328Y600645D01*
X1235201Y601228D01*
X1234758Y601645D01*
X1234314Y601812D01*
X1233744D01*
G01X1234314D02*
X1234694Y602062D01*
X1235011Y602478D01*
X1235138Y602978D01*
X1235011Y603478D01*
X1234694Y603895D01*
X1234124Y604145D01*
X1233554Y604062D01*
X1232984Y603728D01*
G01X1238971Y598978D02*
X1238844Y599062D01*
Y599228D01*
X1238971Y599312D01*
X1239098Y599228D01*
Y599062D01*
X1238971Y598978D01*
G01X1244071Y604145D02*
X1243564Y603978D01*
X1243184Y603562D01*
X1242931Y603062D01*
X1242741Y602395D01*
X1242678Y601645D01*
X1242741Y600895D01*
X1242931Y600228D01*
X1243184Y599728D01*
X1243564Y599312D01*
X1244071Y599145D01*
X1244578Y599312D01*
X1244958Y599728D01*
X1245211Y600228D01*
X1245401Y600895D01*
X1245464Y601645D01*
X1245401Y602395D01*
X1245211Y603062D01*
X1244958Y603562D01*
X1244578Y603978D01*
X1244071Y604145D01*
G01X1202574Y632762D02*
X1204094D01*
G01X1203271Y633845D02*
Y631678D01*
G01X1206978Y632095D02*
X1207358Y631512D01*
X1207864Y631178D01*
X1208434Y631095D01*
X1208941Y631178D01*
X1209448Y631595D01*
X1209764Y632095D01*
X1209828Y632595D01*
X1209701Y633178D01*
X1209258Y633595D01*
X1208814Y633762D01*
X1208244D01*
G01X1208814D02*
X1209194Y634012D01*
X1209511Y634428D01*
X1209638Y634928D01*
X1209511Y635428D01*
X1209194Y635845D01*
X1208624Y636095D01*
X1208054Y636012D01*
X1207484Y635678D01*
G01X1213471Y630928D02*
X1213344Y631012D01*
Y631178D01*
X1213471Y631262D01*
X1213598Y631178D01*
Y631012D01*
X1213471Y630928D01*
G01X1218571Y636095D02*
X1218064Y635928D01*
X1217684Y635512D01*
X1217431Y635012D01*
X1217241Y634345D01*
X1217178Y633595D01*
X1217241Y632845D01*
X1217431Y632178D01*
X1217684Y631678D01*
X1218064Y631262D01*
X1218571Y631095D01*
X1219078Y631262D01*
X1219458Y631678D01*
X1219711Y632178D01*
X1219901Y632845D01*
X1219964Y633595D01*
X1219901Y634345D01*
X1219711Y635012D01*
X1219458Y635512D01*
X1219078Y635928D01*
X1218571Y636095D01*
G01X1222531Y630928D02*
X1224811Y636095D01*
G01X1227948Y632762D02*
X1229594D01*
G01X1232478Y632095D02*
X1232858Y631512D01*
X1233364Y631178D01*
X1233934Y631095D01*
X1234441Y631178D01*
X1234948Y631595D01*
X1235264Y632095D01*
X1235328Y632595D01*
X1235201Y633178D01*
X1234758Y633595D01*
X1234314Y633762D01*
X1233744D01*
G01X1234314D02*
X1234694Y634012D01*
X1235011Y634428D01*
X1235138Y634928D01*
X1235011Y635428D01*
X1234694Y635845D01*
X1234124Y636095D01*
X1233554Y636012D01*
X1232984Y635678D01*
G01X1238971Y630928D02*
X1238844Y631012D01*
Y631178D01*
X1238971Y631262D01*
X1239098Y631178D01*
Y631012D01*
X1238971Y630928D01*
G01X1244071Y636095D02*
X1243564Y635928D01*
X1243184Y635512D01*
X1242931Y635012D01*
X1242741Y634345D01*
X1242678Y633595D01*
X1242741Y632845D01*
X1242931Y632178D01*
X1243184Y631678D01*
X1243564Y631262D01*
X1244071Y631095D01*
X1244578Y631262D01*
X1244958Y631678D01*
X1245211Y632178D01*
X1245401Y632845D01*
X1245464Y633595D01*
X1245401Y634345D01*
X1245211Y635012D01*
X1244958Y635512D01*
X1244578Y635928D01*
X1244071Y636095D01*
G01X1202574Y664712D02*
X1204094D01*
G01X1203271Y665795D02*
Y663628D01*
G01X1206978Y664045D02*
X1207358Y663462D01*
X1207864Y663128D01*
X1208434Y663045D01*
X1208941Y663128D01*
X1209448Y663545D01*
X1209764Y664045D01*
X1209828Y664545D01*
X1209701Y665128D01*
X1209258Y665545D01*
X1208814Y665712D01*
X1208244D01*
G01X1208814D02*
X1209194Y665962D01*
X1209511Y666378D01*
X1209638Y666878D01*
X1209511Y667378D01*
X1209194Y667795D01*
X1208624Y668045D01*
X1208054Y667962D01*
X1207484Y667628D01*
G01X1213471Y662878D02*
X1213344Y662962D01*
Y663128D01*
X1213471Y663212D01*
X1213598Y663128D01*
Y662962D01*
X1213471Y662878D01*
G01X1218571Y668045D02*
X1218064Y667878D01*
X1217684Y667462D01*
X1217431Y666962D01*
X1217241Y666295D01*
X1217178Y665545D01*
X1217241Y664795D01*
X1217431Y664128D01*
X1217684Y663628D01*
X1218064Y663212D01*
X1218571Y663045D01*
X1219078Y663212D01*
X1219458Y663628D01*
X1219711Y664128D01*
X1219901Y664795D01*
X1219964Y665545D01*
X1219901Y666295D01*
X1219711Y666962D01*
X1219458Y667462D01*
X1219078Y667878D01*
X1218571Y668045D01*
G01X1222531Y662878D02*
X1224811Y668045D01*
G01X1227948Y664712D02*
X1229594D01*
G01X1232478Y664045D02*
X1232858Y663462D01*
X1233364Y663128D01*
X1233934Y663045D01*
X1234441Y663128D01*
X1234948Y663545D01*
X1235264Y664045D01*
X1235328Y664545D01*
X1235201Y665128D01*
X1234758Y665545D01*
X1234314Y665712D01*
X1233744D01*
G01X1234314D02*
X1234694Y665962D01*
X1235011Y666378D01*
X1235138Y666878D01*
X1235011Y667378D01*
X1234694Y667795D01*
X1234124Y668045D01*
X1233554Y667962D01*
X1232984Y667628D01*
G01X1238971Y662878D02*
X1238844Y662962D01*
Y663128D01*
X1238971Y663212D01*
X1239098Y663128D01*
Y662962D01*
X1238971Y662878D01*
G01X1244071Y668045D02*
X1243564Y667878D01*
X1243184Y667462D01*
X1242931Y666962D01*
X1242741Y666295D01*
X1242678Y665545D01*
X1242741Y664795D01*
X1242931Y664128D01*
X1243184Y663628D01*
X1243564Y663212D01*
X1244071Y663045D01*
X1244578Y663212D01*
X1244958Y663628D01*
X1245211Y664128D01*
X1245401Y664795D01*
X1245464Y665545D01*
X1245401Y666295D01*
X1245211Y666962D01*
X1244958Y667462D01*
X1244578Y667878D01*
X1244071Y668045D01*
G01X1202574Y696662D02*
X1204094D01*
G01X1203271Y697745D02*
Y695578D01*
G01X1206978Y695995D02*
X1207358Y695412D01*
X1207864Y695078D01*
X1208434Y694995D01*
X1208941Y695078D01*
X1209448Y695495D01*
X1209764Y695995D01*
X1209828Y696495D01*
X1209701Y697078D01*
X1209258Y697495D01*
X1208814Y697662D01*
X1208244D01*
G01X1208814D02*
X1209194Y697912D01*
X1209511Y698328D01*
X1209638Y698828D01*
X1209511Y699328D01*
X1209194Y699745D01*
X1208624Y699995D01*
X1208054Y699912D01*
X1207484Y699578D01*
G01X1213471Y694828D02*
X1213344Y694912D01*
Y695078D01*
X1213471Y695162D01*
X1213598Y695078D01*
Y694912D01*
X1213471Y694828D01*
G01X1218571Y699995D02*
X1218064Y699828D01*
X1217684Y699412D01*
X1217431Y698912D01*
X1217241Y698245D01*
X1217178Y697495D01*
X1217241Y696745D01*
X1217431Y696078D01*
X1217684Y695578D01*
X1218064Y695162D01*
X1218571Y694995D01*
X1219078Y695162D01*
X1219458Y695578D01*
X1219711Y696078D01*
X1219901Y696745D01*
X1219964Y697495D01*
X1219901Y698245D01*
X1219711Y698912D01*
X1219458Y699412D01*
X1219078Y699828D01*
X1218571Y699995D01*
G01X1222531Y694828D02*
X1224811Y699995D01*
G01X1227948Y696662D02*
X1229594D01*
G01X1232478Y695995D02*
X1232858Y695412D01*
X1233364Y695078D01*
X1233934Y694995D01*
X1234441Y695078D01*
X1234948Y695495D01*
X1235264Y695995D01*
X1235328Y696495D01*
X1235201Y697078D01*
X1234758Y697495D01*
X1234314Y697662D01*
X1233744D01*
G01X1234314D02*
X1234694Y697912D01*
X1235011Y698328D01*
X1235138Y698828D01*
X1235011Y699328D01*
X1234694Y699745D01*
X1234124Y699995D01*
X1233554Y699912D01*
X1232984Y699578D01*
G01X1238971Y694828D02*
X1238844Y694912D01*
Y695078D01*
X1238971Y695162D01*
X1239098Y695078D01*
Y694912D01*
X1238971Y694828D01*
G01X1244071Y699995D02*
X1243564Y699828D01*
X1243184Y699412D01*
X1242931Y698912D01*
X1242741Y698245D01*
X1242678Y697495D01*
X1242741Y696745D01*
X1242931Y696078D01*
X1243184Y695578D01*
X1243564Y695162D01*
X1244071Y694995D01*
X1244578Y695162D01*
X1244958Y695578D01*
X1245211Y696078D01*
X1245401Y696745D01*
X1245464Y697495D01*
X1245401Y698245D01*
X1245211Y698912D01*
X1244958Y699412D01*
X1244578Y699828D01*
X1244071Y699995D01*
G01X1202574Y728612D02*
X1204094D01*
G01X1203271Y729695D02*
Y727528D01*
G01X1206978Y727945D02*
X1207358Y727362D01*
X1207864Y727028D01*
X1208434Y726945D01*
X1208941Y727028D01*
X1209448Y727445D01*
X1209764Y727945D01*
X1209828Y728445D01*
X1209701Y729028D01*
X1209258Y729445D01*
X1208814Y729612D01*
X1208244D01*
G01X1208814D02*
X1209194Y729862D01*
X1209511Y730278D01*
X1209638Y730778D01*
X1209511Y731278D01*
X1209194Y731695D01*
X1208624Y731945D01*
X1208054Y731862D01*
X1207484Y731528D01*
G01X1213471Y726778D02*
X1213344Y726862D01*
Y727028D01*
X1213471Y727112D01*
X1213598Y727028D01*
Y726862D01*
X1213471Y726778D01*
G01X1218571Y731945D02*
X1218064Y731778D01*
X1217684Y731362D01*
X1217431Y730862D01*
X1217241Y730195D01*
X1217178Y729445D01*
X1217241Y728695D01*
X1217431Y728028D01*
X1217684Y727528D01*
X1218064Y727112D01*
X1218571Y726945D01*
X1219078Y727112D01*
X1219458Y727528D01*
X1219711Y728028D01*
X1219901Y728695D01*
X1219964Y729445D01*
X1219901Y730195D01*
X1219711Y730862D01*
X1219458Y731362D01*
X1219078Y731778D01*
X1218571Y731945D01*
G01X1222531Y726778D02*
X1224811Y731945D01*
G01X1227948Y728612D02*
X1229594D01*
G01X1232478Y727945D02*
X1232858Y727362D01*
X1233364Y727028D01*
X1233934Y726945D01*
X1234441Y727028D01*
X1234948Y727445D01*
X1235264Y727945D01*
X1235328Y728445D01*
X1235201Y729028D01*
X1234758Y729445D01*
X1234314Y729612D01*
X1233744D01*
G01X1234314D02*
X1234694Y729862D01*
X1235011Y730278D01*
X1235138Y730778D01*
X1235011Y731278D01*
X1234694Y731695D01*
X1234124Y731945D01*
X1233554Y731862D01*
X1232984Y731528D01*
G01X1238971Y726778D02*
X1238844Y726862D01*
Y727028D01*
X1238971Y727112D01*
X1239098Y727028D01*
Y726862D01*
X1238971Y726778D01*
G01X1244071Y731945D02*
X1243564Y731778D01*
X1243184Y731362D01*
X1242931Y730862D01*
X1242741Y730195D01*
X1242678Y729445D01*
X1242741Y728695D01*
X1242931Y728028D01*
X1243184Y727528D01*
X1243564Y727112D01*
X1244071Y726945D01*
X1244578Y727112D01*
X1244958Y727528D01*
X1245211Y728028D01*
X1245401Y728695D01*
X1245464Y729445D01*
X1245401Y730195D01*
X1245211Y730862D01*
X1244958Y731362D01*
X1244578Y731778D01*
X1244071Y731945D01*
G01X1202574Y760562D02*
X1204094D01*
G01X1203271Y761645D02*
Y759478D01*
G01X1206978Y759895D02*
X1207358Y759312D01*
X1207864Y758978D01*
X1208434Y758895D01*
X1208941Y758978D01*
X1209448Y759395D01*
X1209764Y759895D01*
X1209828Y760395D01*
X1209701Y760978D01*
X1209258Y761395D01*
X1208814Y761562D01*
X1208244D01*
G01X1208814D02*
X1209194Y761812D01*
X1209511Y762228D01*
X1209638Y762728D01*
X1209511Y763228D01*
X1209194Y763645D01*
X1208624Y763895D01*
X1208054Y763812D01*
X1207484Y763478D01*
G01X1213471Y758728D02*
X1213344Y758812D01*
Y758978D01*
X1213471Y759062D01*
X1213598Y758978D01*
Y758812D01*
X1213471Y758728D01*
G01X1218571Y763895D02*
X1218064Y763728D01*
X1217684Y763312D01*
X1217431Y762812D01*
X1217241Y762145D01*
X1217178Y761395D01*
X1217241Y760645D01*
X1217431Y759978D01*
X1217684Y759478D01*
X1218064Y759062D01*
X1218571Y758895D01*
X1219078Y759062D01*
X1219458Y759478D01*
X1219711Y759978D01*
X1219901Y760645D01*
X1219964Y761395D01*
X1219901Y762145D01*
X1219711Y762812D01*
X1219458Y763312D01*
X1219078Y763728D01*
X1218571Y763895D01*
G01X1222531Y758728D02*
X1224811Y763895D01*
G01X1227948Y760562D02*
X1229594D01*
G01X1232478Y759895D02*
X1232858Y759312D01*
X1233364Y758978D01*
X1233934Y758895D01*
X1234441Y758978D01*
X1234948Y759395D01*
X1235264Y759895D01*
X1235328Y760395D01*
X1235201Y760978D01*
X1234758Y761395D01*
X1234314Y761562D01*
X1233744D01*
G01X1234314D02*
X1234694Y761812D01*
X1235011Y762228D01*
X1235138Y762728D01*
X1235011Y763228D01*
X1234694Y763645D01*
X1234124Y763895D01*
X1233554Y763812D01*
X1232984Y763478D01*
G01X1238971Y758728D02*
X1238844Y758812D01*
Y758978D01*
X1238971Y759062D01*
X1239098Y758978D01*
Y758812D01*
X1238971Y758728D01*
G01X1244071Y763895D02*
X1243564Y763728D01*
X1243184Y763312D01*
X1242931Y762812D01*
X1242741Y762145D01*
X1242678Y761395D01*
X1242741Y760645D01*
X1242931Y759978D01*
X1243184Y759478D01*
X1243564Y759062D01*
X1244071Y758895D01*
X1244578Y759062D01*
X1244958Y759478D01*
X1245211Y759978D01*
X1245401Y760645D01*
X1245464Y761395D01*
X1245401Y762145D01*
X1245211Y762812D01*
X1244958Y763312D01*
X1244578Y763728D01*
X1244071Y763895D01*
G01X1202574Y792512D02*
X1204094D01*
G01X1203271Y793595D02*
Y791428D01*
G01X1206978Y791845D02*
X1207358Y791262D01*
X1207864Y790928D01*
X1208434Y790845D01*
X1208941Y790928D01*
X1209448Y791345D01*
X1209764Y791845D01*
X1209828Y792345D01*
X1209701Y792928D01*
X1209258Y793345D01*
X1208814Y793512D01*
X1208244D01*
G01X1208814D02*
X1209194Y793762D01*
X1209511Y794178D01*
X1209638Y794678D01*
X1209511Y795178D01*
X1209194Y795595D01*
X1208624Y795845D01*
X1208054Y795762D01*
X1207484Y795428D01*
G01X1213471Y790678D02*
X1213344Y790762D01*
Y790928D01*
X1213471Y791012D01*
X1213598Y790928D01*
Y790762D01*
X1213471Y790678D01*
G01X1218571Y795845D02*
X1218064Y795678D01*
X1217684Y795262D01*
X1217431Y794762D01*
X1217241Y794095D01*
X1217178Y793345D01*
X1217241Y792595D01*
X1217431Y791928D01*
X1217684Y791428D01*
X1218064Y791012D01*
X1218571Y790845D01*
X1219078Y791012D01*
X1219458Y791428D01*
X1219711Y791928D01*
X1219901Y792595D01*
X1219964Y793345D01*
X1219901Y794095D01*
X1219711Y794762D01*
X1219458Y795262D01*
X1219078Y795678D01*
X1218571Y795845D01*
G01X1222531Y790678D02*
X1224811Y795845D01*
G01X1227948Y792512D02*
X1229594D01*
G01X1232478Y791845D02*
X1232858Y791262D01*
X1233364Y790928D01*
X1233934Y790845D01*
X1234441Y790928D01*
X1234948Y791345D01*
X1235264Y791845D01*
X1235328Y792345D01*
X1235201Y792928D01*
X1234758Y793345D01*
X1234314Y793512D01*
X1233744D01*
G01X1234314D02*
X1234694Y793762D01*
X1235011Y794178D01*
X1235138Y794678D01*
X1235011Y795178D01*
X1234694Y795595D01*
X1234124Y795845D01*
X1233554Y795762D01*
X1232984Y795428D01*
G01X1238971Y790678D02*
X1238844Y790762D01*
Y790928D01*
X1238971Y791012D01*
X1239098Y790928D01*
Y790762D01*
X1238971Y790678D01*
G01X1244071Y795845D02*
X1243564Y795678D01*
X1243184Y795262D01*
X1242931Y794762D01*
X1242741Y794095D01*
X1242678Y793345D01*
X1242741Y792595D01*
X1242931Y791928D01*
X1243184Y791428D01*
X1243564Y791012D01*
X1244071Y790845D01*
X1244578Y791012D01*
X1244958Y791428D01*
X1245211Y791928D01*
X1245401Y792595D01*
X1245464Y793345D01*
X1245401Y794095D01*
X1245211Y794762D01*
X1244958Y795262D01*
X1244578Y795678D01*
X1244071Y795845D01*
G01X1200024Y824462D02*
X1201544D01*
G01X1200721Y825545D02*
Y823378D01*
G01X1206581Y822795D02*
Y827795D01*
X1204238Y824212D01*
X1207404D01*
G01X1210921Y822628D02*
X1210794Y822712D01*
Y822878D01*
X1210921Y822962D01*
X1211048Y822878D01*
Y822712D01*
X1210921Y822628D01*
G01X1216021Y827795D02*
X1215514Y827628D01*
X1215134Y827212D01*
X1214881Y826712D01*
X1214691Y826045D01*
X1214628Y825295D01*
X1214691Y824545D01*
X1214881Y823878D01*
X1215134Y823378D01*
X1215514Y822962D01*
X1216021Y822795D01*
X1216528Y822962D01*
X1216908Y823378D01*
X1217161Y823878D01*
X1217351Y824545D01*
X1217414Y825295D01*
X1217351Y826045D01*
X1217161Y826712D01*
X1216908Y827212D01*
X1216528Y827628D01*
X1216021Y827795D01*
G01X1219981Y822628D02*
X1222261Y827795D01*
G01X1225398Y824462D02*
X1227044D01*
G01X1231321Y822795D02*
Y827795D01*
X1230561Y826795D01*
G01Y822795D02*
X1232081D01*
G01X1236421Y827795D02*
X1235914Y827628D01*
X1235534Y827212D01*
X1235281Y826712D01*
X1235091Y826045D01*
X1235028Y825295D01*
X1235091Y824545D01*
X1235281Y823878D01*
X1235534Y823378D01*
X1235914Y822962D01*
X1236421Y822795D01*
X1236928Y822962D01*
X1237308Y823378D01*
X1237561Y823878D01*
X1237751Y824545D01*
X1237814Y825295D01*
X1237751Y826045D01*
X1237561Y826712D01*
X1237308Y827212D01*
X1236928Y827628D01*
X1236421Y827795D01*
G01X1241521Y822628D02*
X1241394Y822712D01*
Y822878D01*
X1241521Y822962D01*
X1241648Y822878D01*
Y822712D01*
X1241521Y822628D01*
G01X1246621Y827795D02*
X1246114Y827628D01*
X1245734Y827212D01*
X1245481Y826712D01*
X1245291Y826045D01*
X1245228Y825295D01*
X1245291Y824545D01*
X1245481Y823878D01*
X1245734Y823378D01*
X1246114Y822962D01*
X1246621Y822795D01*
X1247128Y822962D01*
X1247508Y823378D01*
X1247761Y823878D01*
X1247951Y824545D01*
X1248014Y825295D01*
X1247951Y826045D01*
X1247761Y826712D01*
X1247508Y827212D01*
X1247128Y827628D01*
X1246621Y827795D01*
G01X1202574Y856412D02*
X1204094D01*
G01X1203271Y857495D02*
Y855328D01*
G01X1206978Y855745D02*
X1207358Y855162D01*
X1207864Y854828D01*
X1208434Y854745D01*
X1208941Y854828D01*
X1209448Y855245D01*
X1209764Y855745D01*
X1209828Y856245D01*
X1209701Y856828D01*
X1209258Y857245D01*
X1208814Y857412D01*
X1208244D01*
G01X1208814D02*
X1209194Y857662D01*
X1209511Y858078D01*
X1209638Y858578D01*
X1209511Y859078D01*
X1209194Y859495D01*
X1208624Y859745D01*
X1208054Y859662D01*
X1207484Y859328D01*
G01X1213471Y854578D02*
X1213344Y854662D01*
Y854828D01*
X1213471Y854912D01*
X1213598Y854828D01*
Y854662D01*
X1213471Y854578D01*
G01X1218571Y859745D02*
X1218064Y859578D01*
X1217684Y859162D01*
X1217431Y858662D01*
X1217241Y857995D01*
X1217178Y857245D01*
X1217241Y856495D01*
X1217431Y855828D01*
X1217684Y855328D01*
X1218064Y854912D01*
X1218571Y854745D01*
X1219078Y854912D01*
X1219458Y855328D01*
X1219711Y855828D01*
X1219901Y856495D01*
X1219964Y857245D01*
X1219901Y857995D01*
X1219711Y858662D01*
X1219458Y859162D01*
X1219078Y859578D01*
X1218571Y859745D01*
G01X1222531Y854578D02*
X1224811Y859745D01*
G01X1227948Y856412D02*
X1229594D01*
G01X1232478Y855745D02*
X1232858Y855162D01*
X1233364Y854828D01*
X1233934Y854745D01*
X1234441Y854828D01*
X1234948Y855245D01*
X1235264Y855745D01*
X1235328Y856245D01*
X1235201Y856828D01*
X1234758Y857245D01*
X1234314Y857412D01*
X1233744D01*
G01X1234314D02*
X1234694Y857662D01*
X1235011Y858078D01*
X1235138Y858578D01*
X1235011Y859078D01*
X1234694Y859495D01*
X1234124Y859745D01*
X1233554Y859662D01*
X1232984Y859328D01*
G01X1238971Y854578D02*
X1238844Y854662D01*
Y854828D01*
X1238971Y854912D01*
X1239098Y854828D01*
Y854662D01*
X1238971Y854578D01*
G01X1244071Y859745D02*
X1243564Y859578D01*
X1243184Y859162D01*
X1242931Y858662D01*
X1242741Y857995D01*
X1242678Y857245D01*
X1242741Y856495D01*
X1242931Y855828D01*
X1243184Y855328D01*
X1243564Y854912D01*
X1244071Y854745D01*
X1244578Y854912D01*
X1244958Y855328D01*
X1245211Y855828D01*
X1245401Y856495D01*
X1245464Y857245D01*
X1245401Y857995D01*
X1245211Y858662D01*
X1244958Y859162D01*
X1244578Y859578D01*
X1244071Y859745D01*
G01X1202574Y888362D02*
X1204094D01*
G01X1203271Y889445D02*
Y887278D01*
G01X1206978Y887695D02*
X1207358Y887112D01*
X1207864Y886778D01*
X1208434Y886695D01*
X1208941Y886778D01*
X1209448Y887195D01*
X1209764Y887695D01*
X1209828Y888195D01*
X1209701Y888778D01*
X1209258Y889195D01*
X1208814Y889362D01*
X1208244D01*
G01X1208814D02*
X1209194Y889612D01*
X1209511Y890028D01*
X1209638Y890528D01*
X1209511Y891028D01*
X1209194Y891445D01*
X1208624Y891695D01*
X1208054Y891612D01*
X1207484Y891278D01*
G01X1213471Y886528D02*
X1213344Y886612D01*
Y886778D01*
X1213471Y886862D01*
X1213598Y886778D01*
Y886612D01*
X1213471Y886528D01*
G01X1218571Y891695D02*
X1218064Y891528D01*
X1217684Y891112D01*
X1217431Y890612D01*
X1217241Y889945D01*
X1217178Y889195D01*
X1217241Y888445D01*
X1217431Y887778D01*
X1217684Y887278D01*
X1218064Y886862D01*
X1218571Y886695D01*
X1219078Y886862D01*
X1219458Y887278D01*
X1219711Y887778D01*
X1219901Y888445D01*
X1219964Y889195D01*
X1219901Y889945D01*
X1219711Y890612D01*
X1219458Y891112D01*
X1219078Y891528D01*
X1218571Y891695D01*
G01X1222531Y886528D02*
X1224811Y891695D01*
G01X1227948Y888362D02*
X1229594D01*
G01X1232478Y887695D02*
X1232858Y887112D01*
X1233364Y886778D01*
X1233934Y886695D01*
X1234441Y886778D01*
X1234948Y887195D01*
X1235264Y887695D01*
X1235328Y888195D01*
X1235201Y888778D01*
X1234758Y889195D01*
X1234314Y889362D01*
X1233744D01*
G01X1234314D02*
X1234694Y889612D01*
X1235011Y890028D01*
X1235138Y890528D01*
X1235011Y891028D01*
X1234694Y891445D01*
X1234124Y891695D01*
X1233554Y891612D01*
X1232984Y891278D01*
G01X1238971Y886528D02*
X1238844Y886612D01*
Y886778D01*
X1238971Y886862D01*
X1239098Y886778D01*
Y886612D01*
X1238971Y886528D01*
G01X1244071Y891695D02*
X1243564Y891528D01*
X1243184Y891112D01*
X1242931Y890612D01*
X1242741Y889945D01*
X1242678Y889195D01*
X1242741Y888445D01*
X1242931Y887778D01*
X1243184Y887278D01*
X1243564Y886862D01*
X1244071Y886695D01*
X1244578Y886862D01*
X1244958Y887278D01*
X1245211Y887778D01*
X1245401Y888445D01*
X1245464Y889195D01*
X1245401Y889945D01*
X1245211Y890612D01*
X1244958Y891112D01*
X1244578Y891528D01*
X1244071Y891695D01*
G01X1202574Y920312D02*
X1204094D01*
G01X1203271Y921395D02*
Y919228D01*
G01X1206978Y919645D02*
X1207358Y919062D01*
X1207864Y918728D01*
X1208434Y918645D01*
X1208941Y918728D01*
X1209448Y919145D01*
X1209764Y919645D01*
X1209828Y920145D01*
X1209701Y920728D01*
X1209258Y921145D01*
X1208814Y921312D01*
X1208244D01*
G01X1208814D02*
X1209194Y921562D01*
X1209511Y921978D01*
X1209638Y922478D01*
X1209511Y922978D01*
X1209194Y923395D01*
X1208624Y923645D01*
X1208054Y923562D01*
X1207484Y923228D01*
G01X1213471Y918478D02*
X1213344Y918562D01*
Y918728D01*
X1213471Y918812D01*
X1213598Y918728D01*
Y918562D01*
X1213471Y918478D01*
G01X1218571Y923645D02*
X1218064Y923478D01*
X1217684Y923062D01*
X1217431Y922562D01*
X1217241Y921895D01*
X1217178Y921145D01*
X1217241Y920395D01*
X1217431Y919728D01*
X1217684Y919228D01*
X1218064Y918812D01*
X1218571Y918645D01*
X1219078Y918812D01*
X1219458Y919228D01*
X1219711Y919728D01*
X1219901Y920395D01*
X1219964Y921145D01*
X1219901Y921895D01*
X1219711Y922562D01*
X1219458Y923062D01*
X1219078Y923478D01*
X1218571Y923645D01*
G01X1222531Y918478D02*
X1224811Y923645D01*
G01X1227948Y920312D02*
X1229594D01*
G01X1232478Y919645D02*
X1232858Y919062D01*
X1233364Y918728D01*
X1233934Y918645D01*
X1234441Y918728D01*
X1234948Y919145D01*
X1235264Y919645D01*
X1235328Y920145D01*
X1235201Y920728D01*
X1234758Y921145D01*
X1234314Y921312D01*
X1233744D01*
G01X1234314D02*
X1234694Y921562D01*
X1235011Y921978D01*
X1235138Y922478D01*
X1235011Y922978D01*
X1234694Y923395D01*
X1234124Y923645D01*
X1233554Y923562D01*
X1232984Y923228D01*
G01X1238971Y918478D02*
X1238844Y918562D01*
Y918728D01*
X1238971Y918812D01*
X1239098Y918728D01*
Y918562D01*
X1238971Y918478D01*
G01X1244071Y923645D02*
X1243564Y923478D01*
X1243184Y923062D01*
X1242931Y922562D01*
X1242741Y921895D01*
X1242678Y921145D01*
X1242741Y920395D01*
X1242931Y919728D01*
X1243184Y919228D01*
X1243564Y918812D01*
X1244071Y918645D01*
X1244578Y918812D01*
X1244958Y919228D01*
X1245211Y919728D01*
X1245401Y920395D01*
X1245464Y921145D01*
X1245401Y921895D01*
X1245211Y922562D01*
X1244958Y923062D01*
X1244578Y923478D01*
X1244071Y923645D01*
G01X1202574Y952262D02*
X1204094D01*
G01X1203271Y953345D02*
Y951178D01*
G01X1206978Y951595D02*
X1207358Y951012D01*
X1207864Y950678D01*
X1208434Y950595D01*
X1208941Y950678D01*
X1209448Y951095D01*
X1209764Y951595D01*
X1209828Y952095D01*
X1209701Y952678D01*
X1209258Y953095D01*
X1208814Y953262D01*
X1208244D01*
G01X1208814D02*
X1209194Y953512D01*
X1209511Y953928D01*
X1209638Y954428D01*
X1209511Y954928D01*
X1209194Y955345D01*
X1208624Y955595D01*
X1208054Y955512D01*
X1207484Y955178D01*
G01X1213471Y950428D02*
X1213344Y950512D01*
Y950678D01*
X1213471Y950762D01*
X1213598Y950678D01*
Y950512D01*
X1213471Y950428D01*
G01X1218571Y955595D02*
X1218064Y955428D01*
X1217684Y955012D01*
X1217431Y954512D01*
X1217241Y953845D01*
X1217178Y953095D01*
X1217241Y952345D01*
X1217431Y951678D01*
X1217684Y951178D01*
X1218064Y950762D01*
X1218571Y950595D01*
X1219078Y950762D01*
X1219458Y951178D01*
X1219711Y951678D01*
X1219901Y952345D01*
X1219964Y953095D01*
X1219901Y953845D01*
X1219711Y954512D01*
X1219458Y955012D01*
X1219078Y955428D01*
X1218571Y955595D01*
G01X1222531Y950428D02*
X1224811Y955595D01*
G01X1227948Y952262D02*
X1229594D01*
G01X1232478Y951595D02*
X1232858Y951012D01*
X1233364Y950678D01*
X1233934Y950595D01*
X1234441Y950678D01*
X1234948Y951095D01*
X1235264Y951595D01*
X1235328Y952095D01*
X1235201Y952678D01*
X1234758Y953095D01*
X1234314Y953262D01*
X1233744D01*
G01X1234314D02*
X1234694Y953512D01*
X1235011Y953928D01*
X1235138Y954428D01*
X1235011Y954928D01*
X1234694Y955345D01*
X1234124Y955595D01*
X1233554Y955512D01*
X1232984Y955178D01*
G01X1238971Y950428D02*
X1238844Y950512D01*
Y950678D01*
X1238971Y950762D01*
X1239098Y950678D01*
Y950512D01*
X1238971Y950428D01*
G01X1244071Y955595D02*
X1243564Y955428D01*
X1243184Y955012D01*
X1242931Y954512D01*
X1242741Y953845D01*
X1242678Y953095D01*
X1242741Y952345D01*
X1242931Y951678D01*
X1243184Y951178D01*
X1243564Y950762D01*
X1244071Y950595D01*
X1244578Y950762D01*
X1244958Y951178D01*
X1245211Y951678D01*
X1245401Y952345D01*
X1245464Y953095D01*
X1245401Y953845D01*
X1245211Y954512D01*
X1244958Y955012D01*
X1244578Y955428D01*
X1244071Y955595D01*
G01X1203271Y977870D02*
Y972870D01*
G01X1201814Y977870D02*
X1204728D01*
G01X1208371Y972870D02*
X1207864Y972953D01*
X1207421Y973287D01*
X1207041Y973787D01*
X1206788Y974370D01*
X1206661Y975037D01*
Y975703D01*
X1206788Y976370D01*
X1207041Y976953D01*
X1207421Y977453D01*
X1207864Y977787D01*
X1208371Y977870D01*
X1208878Y977787D01*
X1209321Y977453D01*
X1209701Y976953D01*
X1209954Y976370D01*
X1210081Y975703D01*
Y975037D01*
X1209954Y974370D01*
X1209701Y973787D01*
X1209321Y973287D01*
X1208878Y972953D01*
X1208371Y972870D01*
G01X1212204Y977870D02*
Y972870D01*
X1214738D01*
G01X1219838D02*
X1217304D01*
Y977870D01*
X1219838D01*
G01X1218824Y975453D02*
X1217304D01*
G01X1222404Y972870D02*
Y977870D01*
X1223988D01*
X1224494Y977620D01*
X1224811Y977287D01*
X1224938Y976620D01*
X1224811Y975953D01*
X1224431Y975537D01*
X1223988Y975287D01*
X1222404D01*
G01X1223988D02*
X1224938Y972870D01*
G01X1227188D02*
X1228771Y977870D01*
X1230354Y972870D01*
G01X1229784Y974620D02*
X1227758D01*
G01X1232414Y972870D02*
Y977870D01*
X1235328Y972870D01*
Y977870D01*
G01X1240364Y977453D02*
X1239984Y977703D01*
X1239541Y977870D01*
X1239034D01*
X1238464Y977620D01*
X1238021Y977203D01*
X1237704Y976703D01*
X1237451Y975870D01*
X1237388Y975120D01*
X1237514Y974370D01*
X1237704Y973870D01*
X1238084Y973370D01*
X1238528Y973037D01*
X1238971Y972870D01*
X1239414D01*
X1239858Y973037D01*
X1240238Y973287D01*
X1240554Y973620D01*
G01X1245338Y972870D02*
X1242804D01*
Y977870D01*
X1245338D01*
G01X1244324Y975453D02*
X1242804D01*
G01X1264314Y55995D02*
Y60995D01*
X1267228Y55995D01*
Y60995D01*
G01X1270871Y55995D02*
X1270364Y56078D01*
X1269921Y56412D01*
X1269541Y56912D01*
X1269288Y57495D01*
X1269161Y58162D01*
Y58828D01*
X1269288Y59495D01*
X1269541Y60078D01*
X1269921Y60578D01*
X1270364Y60912D01*
X1270871Y60995D01*
X1271378Y60912D01*
X1271821Y60578D01*
X1272201Y60078D01*
X1272454Y59495D01*
X1272581Y58828D01*
Y58162D01*
X1272454Y57495D01*
X1272201Y56912D01*
X1271821Y56412D01*
X1271378Y56078D01*
X1270871Y55995D01*
G01X1274514D02*
Y60995D01*
X1277428Y55995D01*
Y60995D01*
G01X1280248Y57662D02*
X1281894D01*
G01X1284904Y55995D02*
Y60995D01*
X1286424D01*
X1286931Y60745D01*
X1287311Y60162D01*
X1287438Y59495D01*
X1287311Y58828D01*
X1286994Y58328D01*
X1286424Y58078D01*
X1284904D01*
G01X1290004Y60995D02*
Y55995D01*
X1292538D01*
G01X1294788D02*
X1296371Y60995D01*
X1297954Y55995D01*
G01X1297384Y57745D02*
X1295358D01*
G01X1301471Y60995D02*
Y55995D01*
G01X1300014Y60995D02*
X1302928D01*
G01X1307838Y55995D02*
X1305304D01*
Y60995D01*
X1307838D01*
G01X1306824Y58578D02*
X1305304D01*
G01X1310278Y55995D02*
Y60995D01*
X1311544D01*
X1312051Y60745D01*
X1312431Y60412D01*
X1312748Y59912D01*
X1313001Y59328D01*
X1313064Y58495D01*
X1313001Y57662D01*
X1312748Y57078D01*
X1312431Y56578D01*
X1312051Y56245D01*
X1311544Y55995D01*
X1310278D01*
G01X1264314Y87945D02*
Y92945D01*
X1267228Y87945D01*
Y92945D01*
G01X1270871Y87945D02*
X1270364Y88028D01*
X1269921Y88362D01*
X1269541Y88862D01*
X1269288Y89445D01*
X1269161Y90112D01*
Y90778D01*
X1269288Y91445D01*
X1269541Y92028D01*
X1269921Y92528D01*
X1270364Y92862D01*
X1270871Y92945D01*
X1271378Y92862D01*
X1271821Y92528D01*
X1272201Y92028D01*
X1272454Y91445D01*
X1272581Y90778D01*
Y90112D01*
X1272454Y89445D01*
X1272201Y88862D01*
X1271821Y88362D01*
X1271378Y88028D01*
X1270871Y87945D01*
G01X1274514D02*
Y92945D01*
X1277428Y87945D01*
Y92945D01*
G01X1280248Y89612D02*
X1281894D01*
G01X1284904Y87945D02*
Y92945D01*
X1286424D01*
X1286931Y92695D01*
X1287311Y92112D01*
X1287438Y91445D01*
X1287311Y90778D01*
X1286994Y90278D01*
X1286424Y90028D01*
X1284904D01*
G01X1290004Y92945D02*
Y87945D01*
X1292538D01*
G01X1294788D02*
X1296371Y92945D01*
X1297954Y87945D01*
G01X1297384Y89695D02*
X1295358D01*
G01X1301471Y92945D02*
Y87945D01*
G01X1300014Y92945D02*
X1302928D01*
G01X1307838Y87945D02*
X1305304D01*
Y92945D01*
X1307838D01*
G01X1306824Y90528D02*
X1305304D01*
G01X1310278Y87945D02*
Y92945D01*
X1311544D01*
X1312051Y92695D01*
X1312431Y92362D01*
X1312748Y91862D01*
X1313001Y91278D01*
X1313064Y90445D01*
X1313001Y89612D01*
X1312748Y89028D01*
X1312431Y88528D01*
X1312051Y88195D01*
X1311544Y87945D01*
X1310278D01*
G01X1264314Y119895D02*
Y124895D01*
X1267228Y119895D01*
Y124895D01*
G01X1270871Y119895D02*
X1270364Y119978D01*
X1269921Y120312D01*
X1269541Y120812D01*
X1269288Y121395D01*
X1269161Y122062D01*
Y122728D01*
X1269288Y123395D01*
X1269541Y123978D01*
X1269921Y124478D01*
X1270364Y124812D01*
X1270871Y124895D01*
X1271378Y124812D01*
X1271821Y124478D01*
X1272201Y123978D01*
X1272454Y123395D01*
X1272581Y122728D01*
Y122062D01*
X1272454Y121395D01*
X1272201Y120812D01*
X1271821Y120312D01*
X1271378Y119978D01*
X1270871Y119895D01*
G01X1274514D02*
Y124895D01*
X1277428Y119895D01*
Y124895D01*
G01X1280248Y121562D02*
X1281894D01*
G01X1284904Y119895D02*
Y124895D01*
X1286424D01*
X1286931Y124645D01*
X1287311Y124062D01*
X1287438Y123395D01*
X1287311Y122728D01*
X1286994Y122228D01*
X1286424Y121978D01*
X1284904D01*
G01X1290004Y124895D02*
Y119895D01*
X1292538D01*
G01X1294788D02*
X1296371Y124895D01*
X1297954Y119895D01*
G01X1297384Y121645D02*
X1295358D01*
G01X1301471Y124895D02*
Y119895D01*
G01X1300014Y124895D02*
X1302928D01*
G01X1307838Y119895D02*
X1305304D01*
Y124895D01*
X1307838D01*
G01X1306824Y122478D02*
X1305304D01*
G01X1310278Y119895D02*
Y124895D01*
X1311544D01*
X1312051Y124645D01*
X1312431Y124312D01*
X1312748Y123812D01*
X1313001Y123228D01*
X1313064Y122395D01*
X1313001Y121562D01*
X1312748Y120978D01*
X1312431Y120478D01*
X1312051Y120145D01*
X1311544Y119895D01*
X1310278D01*
G01X1264314Y151845D02*
Y156845D01*
X1267228Y151845D01*
Y156845D01*
G01X1270871Y151845D02*
X1270364Y151928D01*
X1269921Y152262D01*
X1269541Y152762D01*
X1269288Y153345D01*
X1269161Y154012D01*
Y154678D01*
X1269288Y155345D01*
X1269541Y155928D01*
X1269921Y156428D01*
X1270364Y156762D01*
X1270871Y156845D01*
X1271378Y156762D01*
X1271821Y156428D01*
X1272201Y155928D01*
X1272454Y155345D01*
X1272581Y154678D01*
Y154012D01*
X1272454Y153345D01*
X1272201Y152762D01*
X1271821Y152262D01*
X1271378Y151928D01*
X1270871Y151845D01*
G01X1274514D02*
Y156845D01*
X1277428Y151845D01*
Y156845D01*
G01X1280248Y153512D02*
X1281894D01*
G01X1284904Y151845D02*
Y156845D01*
X1286424D01*
X1286931Y156595D01*
X1287311Y156012D01*
X1287438Y155345D01*
X1287311Y154678D01*
X1286994Y154178D01*
X1286424Y153928D01*
X1284904D01*
G01X1290004Y156845D02*
Y151845D01*
X1292538D01*
G01X1294788D02*
X1296371Y156845D01*
X1297954Y151845D01*
G01X1297384Y153595D02*
X1295358D01*
G01X1301471Y156845D02*
Y151845D01*
G01X1300014Y156845D02*
X1302928D01*
G01X1307838Y151845D02*
X1305304D01*
Y156845D01*
X1307838D01*
G01X1306824Y154428D02*
X1305304D01*
G01X1310278Y151845D02*
Y156845D01*
X1311544D01*
X1312051Y156595D01*
X1312431Y156262D01*
X1312748Y155762D01*
X1313001Y155178D01*
X1313064Y154345D01*
X1313001Y153512D01*
X1312748Y152928D01*
X1312431Y152428D01*
X1312051Y152095D01*
X1311544Y151845D01*
X1310278D01*
G01X1264314Y183795D02*
Y188795D01*
X1267228Y183795D01*
Y188795D01*
G01X1270871Y183795D02*
X1270364Y183878D01*
X1269921Y184212D01*
X1269541Y184712D01*
X1269288Y185295D01*
X1269161Y185962D01*
Y186628D01*
X1269288Y187295D01*
X1269541Y187878D01*
X1269921Y188378D01*
X1270364Y188712D01*
X1270871Y188795D01*
X1271378Y188712D01*
X1271821Y188378D01*
X1272201Y187878D01*
X1272454Y187295D01*
X1272581Y186628D01*
Y185962D01*
X1272454Y185295D01*
X1272201Y184712D01*
X1271821Y184212D01*
X1271378Y183878D01*
X1270871Y183795D01*
G01X1274514D02*
Y188795D01*
X1277428Y183795D01*
Y188795D01*
G01X1280248Y185462D02*
X1281894D01*
G01X1284904Y183795D02*
Y188795D01*
X1286424D01*
X1286931Y188545D01*
X1287311Y187962D01*
X1287438Y187295D01*
X1287311Y186628D01*
X1286994Y186128D01*
X1286424Y185878D01*
X1284904D01*
G01X1290004Y188795D02*
Y183795D01*
X1292538D01*
G01X1294788D02*
X1296371Y188795D01*
X1297954Y183795D01*
G01X1297384Y185545D02*
X1295358D01*
G01X1301471Y188795D02*
Y183795D01*
G01X1300014Y188795D02*
X1302928D01*
G01X1307838Y183795D02*
X1305304D01*
Y188795D01*
X1307838D01*
G01X1306824Y186378D02*
X1305304D01*
G01X1310278Y183795D02*
Y188795D01*
X1311544D01*
X1312051Y188545D01*
X1312431Y188212D01*
X1312748Y187712D01*
X1313001Y187128D01*
X1313064Y186295D01*
X1313001Y185462D01*
X1312748Y184878D01*
X1312431Y184378D01*
X1312051Y184045D01*
X1311544Y183795D01*
X1310278D01*
G01X1264314Y215745D02*
Y220745D01*
X1267228Y215745D01*
Y220745D01*
G01X1270871Y215745D02*
X1270364Y215828D01*
X1269921Y216162D01*
X1269541Y216662D01*
X1269288Y217245D01*
X1269161Y217912D01*
Y218578D01*
X1269288Y219245D01*
X1269541Y219828D01*
X1269921Y220328D01*
X1270364Y220662D01*
X1270871Y220745D01*
X1271378Y220662D01*
X1271821Y220328D01*
X1272201Y219828D01*
X1272454Y219245D01*
X1272581Y218578D01*
Y217912D01*
X1272454Y217245D01*
X1272201Y216662D01*
X1271821Y216162D01*
X1271378Y215828D01*
X1270871Y215745D01*
G01X1274514D02*
Y220745D01*
X1277428Y215745D01*
Y220745D01*
G01X1280248Y217412D02*
X1281894D01*
G01X1284904Y215745D02*
Y220745D01*
X1286424D01*
X1286931Y220495D01*
X1287311Y219912D01*
X1287438Y219245D01*
X1287311Y218578D01*
X1286994Y218078D01*
X1286424Y217828D01*
X1284904D01*
G01X1290004Y220745D02*
Y215745D01*
X1292538D01*
G01X1294788D02*
X1296371Y220745D01*
X1297954Y215745D01*
G01X1297384Y217495D02*
X1295358D01*
G01X1301471Y220745D02*
Y215745D01*
G01X1300014Y220745D02*
X1302928D01*
G01X1307838Y215745D02*
X1305304D01*
Y220745D01*
X1307838D01*
G01X1306824Y218328D02*
X1305304D01*
G01X1310278Y215745D02*
Y220745D01*
X1311544D01*
X1312051Y220495D01*
X1312431Y220162D01*
X1312748Y219662D01*
X1313001Y219078D01*
X1313064Y218245D01*
X1313001Y217412D01*
X1312748Y216828D01*
X1312431Y216328D01*
X1312051Y215995D01*
X1311544Y215745D01*
X1310278D01*
G01X1264314Y247695D02*
Y252695D01*
X1267228Y247695D01*
Y252695D01*
G01X1270871Y247695D02*
X1270364Y247778D01*
X1269921Y248112D01*
X1269541Y248612D01*
X1269288Y249195D01*
X1269161Y249862D01*
Y250528D01*
X1269288Y251195D01*
X1269541Y251778D01*
X1269921Y252278D01*
X1270364Y252612D01*
X1270871Y252695D01*
X1271378Y252612D01*
X1271821Y252278D01*
X1272201Y251778D01*
X1272454Y251195D01*
X1272581Y250528D01*
Y249862D01*
X1272454Y249195D01*
X1272201Y248612D01*
X1271821Y248112D01*
X1271378Y247778D01*
X1270871Y247695D01*
G01X1274514D02*
Y252695D01*
X1277428Y247695D01*
Y252695D01*
G01X1280248Y249362D02*
X1281894D01*
G01X1284904Y247695D02*
Y252695D01*
X1286424D01*
X1286931Y252445D01*
X1287311Y251862D01*
X1287438Y251195D01*
X1287311Y250528D01*
X1286994Y250028D01*
X1286424Y249778D01*
X1284904D01*
G01X1290004Y252695D02*
Y247695D01*
X1292538D01*
G01X1294788D02*
X1296371Y252695D01*
X1297954Y247695D01*
G01X1297384Y249445D02*
X1295358D01*
G01X1301471Y252695D02*
Y247695D01*
G01X1300014Y252695D02*
X1302928D01*
G01X1307838Y247695D02*
X1305304D01*
Y252695D01*
X1307838D01*
G01X1306824Y250278D02*
X1305304D01*
G01X1310278Y247695D02*
Y252695D01*
X1311544D01*
X1312051Y252445D01*
X1312431Y252112D01*
X1312748Y251612D01*
X1313001Y251028D01*
X1313064Y250195D01*
X1313001Y249362D01*
X1312748Y248778D01*
X1312431Y248278D01*
X1312051Y247945D01*
X1311544Y247695D01*
X1310278D01*
G01X1264314Y279645D02*
Y284645D01*
X1267228Y279645D01*
Y284645D01*
G01X1270871Y279645D02*
X1270364Y279728D01*
X1269921Y280062D01*
X1269541Y280562D01*
X1269288Y281145D01*
X1269161Y281812D01*
Y282478D01*
X1269288Y283145D01*
X1269541Y283728D01*
X1269921Y284228D01*
X1270364Y284562D01*
X1270871Y284645D01*
X1271378Y284562D01*
X1271821Y284228D01*
X1272201Y283728D01*
X1272454Y283145D01*
X1272581Y282478D01*
Y281812D01*
X1272454Y281145D01*
X1272201Y280562D01*
X1271821Y280062D01*
X1271378Y279728D01*
X1270871Y279645D01*
G01X1274514D02*
Y284645D01*
X1277428Y279645D01*
Y284645D01*
G01X1280248Y281312D02*
X1281894D01*
G01X1284904Y279645D02*
Y284645D01*
X1286424D01*
X1286931Y284395D01*
X1287311Y283812D01*
X1287438Y283145D01*
X1287311Y282478D01*
X1286994Y281978D01*
X1286424Y281728D01*
X1284904D01*
G01X1290004Y284645D02*
Y279645D01*
X1292538D01*
G01X1294788D02*
X1296371Y284645D01*
X1297954Y279645D01*
G01X1297384Y281395D02*
X1295358D01*
G01X1301471Y284645D02*
Y279645D01*
G01X1300014Y284645D02*
X1302928D01*
G01X1307838Y279645D02*
X1305304D01*
Y284645D01*
X1307838D01*
G01X1306824Y282228D02*
X1305304D01*
G01X1310278Y279645D02*
Y284645D01*
X1311544D01*
X1312051Y284395D01*
X1312431Y284062D01*
X1312748Y283562D01*
X1313001Y282978D01*
X1313064Y282145D01*
X1313001Y281312D01*
X1312748Y280728D01*
X1312431Y280228D01*
X1312051Y279895D01*
X1311544Y279645D01*
X1310278D01*
G01X1264314Y311595D02*
Y316595D01*
X1267228Y311595D01*
Y316595D01*
G01X1270871Y311595D02*
X1270364Y311678D01*
X1269921Y312012D01*
X1269541Y312512D01*
X1269288Y313095D01*
X1269161Y313762D01*
Y314428D01*
X1269288Y315095D01*
X1269541Y315678D01*
X1269921Y316178D01*
X1270364Y316512D01*
X1270871Y316595D01*
X1271378Y316512D01*
X1271821Y316178D01*
X1272201Y315678D01*
X1272454Y315095D01*
X1272581Y314428D01*
Y313762D01*
X1272454Y313095D01*
X1272201Y312512D01*
X1271821Y312012D01*
X1271378Y311678D01*
X1270871Y311595D01*
G01X1274514D02*
Y316595D01*
X1277428Y311595D01*
Y316595D01*
G01X1280248Y313262D02*
X1281894D01*
G01X1284904Y311595D02*
Y316595D01*
X1286424D01*
X1286931Y316345D01*
X1287311Y315762D01*
X1287438Y315095D01*
X1287311Y314428D01*
X1286994Y313928D01*
X1286424Y313678D01*
X1284904D01*
G01X1290004Y316595D02*
Y311595D01*
X1292538D01*
G01X1294788D02*
X1296371Y316595D01*
X1297954Y311595D01*
G01X1297384Y313345D02*
X1295358D01*
G01X1301471Y316595D02*
Y311595D01*
G01X1300014Y316595D02*
X1302928D01*
G01X1307838Y311595D02*
X1305304D01*
Y316595D01*
X1307838D01*
G01X1306824Y314178D02*
X1305304D01*
G01X1310278Y311595D02*
Y316595D01*
X1311544D01*
X1312051Y316345D01*
X1312431Y316012D01*
X1312748Y315512D01*
X1313001Y314928D01*
X1313064Y314095D01*
X1313001Y313262D01*
X1312748Y312678D01*
X1312431Y312178D01*
X1312051Y311845D01*
X1311544Y311595D01*
X1310278D01*
G01X1264314Y343545D02*
Y348545D01*
X1267228Y343545D01*
Y348545D01*
G01X1270871Y343545D02*
X1270364Y343628D01*
X1269921Y343962D01*
X1269541Y344462D01*
X1269288Y345045D01*
X1269161Y345712D01*
Y346378D01*
X1269288Y347045D01*
X1269541Y347628D01*
X1269921Y348128D01*
X1270364Y348462D01*
X1270871Y348545D01*
X1271378Y348462D01*
X1271821Y348128D01*
X1272201Y347628D01*
X1272454Y347045D01*
X1272581Y346378D01*
Y345712D01*
X1272454Y345045D01*
X1272201Y344462D01*
X1271821Y343962D01*
X1271378Y343628D01*
X1270871Y343545D01*
G01X1274514D02*
Y348545D01*
X1277428Y343545D01*
Y348545D01*
G01X1280248Y345212D02*
X1281894D01*
G01X1284904Y343545D02*
Y348545D01*
X1286424D01*
X1286931Y348295D01*
X1287311Y347712D01*
X1287438Y347045D01*
X1287311Y346378D01*
X1286994Y345878D01*
X1286424Y345628D01*
X1284904D01*
G01X1290004Y348545D02*
Y343545D01*
X1292538D01*
G01X1294788D02*
X1296371Y348545D01*
X1297954Y343545D01*
G01X1297384Y345295D02*
X1295358D01*
G01X1301471Y348545D02*
Y343545D01*
G01X1300014Y348545D02*
X1302928D01*
G01X1307838Y343545D02*
X1305304D01*
Y348545D01*
X1307838D01*
G01X1306824Y346128D02*
X1305304D01*
G01X1310278Y343545D02*
Y348545D01*
X1311544D01*
X1312051Y348295D01*
X1312431Y347962D01*
X1312748Y347462D01*
X1313001Y346878D01*
X1313064Y346045D01*
X1313001Y345212D01*
X1312748Y344628D01*
X1312431Y344128D01*
X1312051Y343795D01*
X1311544Y343545D01*
X1310278D01*
G01X1264314Y375495D02*
Y380495D01*
X1267228Y375495D01*
Y380495D01*
G01X1270871Y375495D02*
X1270364Y375578D01*
X1269921Y375912D01*
X1269541Y376412D01*
X1269288Y376995D01*
X1269161Y377662D01*
Y378328D01*
X1269288Y378995D01*
X1269541Y379578D01*
X1269921Y380078D01*
X1270364Y380412D01*
X1270871Y380495D01*
X1271378Y380412D01*
X1271821Y380078D01*
X1272201Y379578D01*
X1272454Y378995D01*
X1272581Y378328D01*
Y377662D01*
X1272454Y376995D01*
X1272201Y376412D01*
X1271821Y375912D01*
X1271378Y375578D01*
X1270871Y375495D01*
G01X1274514D02*
Y380495D01*
X1277428Y375495D01*
Y380495D01*
G01X1280248Y377162D02*
X1281894D01*
G01X1284904Y375495D02*
Y380495D01*
X1286424D01*
X1286931Y380245D01*
X1287311Y379662D01*
X1287438Y378995D01*
X1287311Y378328D01*
X1286994Y377828D01*
X1286424Y377578D01*
X1284904D01*
G01X1290004Y380495D02*
Y375495D01*
X1292538D01*
G01X1294788D02*
X1296371Y380495D01*
X1297954Y375495D01*
G01X1297384Y377245D02*
X1295358D01*
G01X1301471Y380495D02*
Y375495D01*
G01X1300014Y380495D02*
X1302928D01*
G01X1307838Y375495D02*
X1305304D01*
Y380495D01*
X1307838D01*
G01X1306824Y378078D02*
X1305304D01*
G01X1310278Y375495D02*
Y380495D01*
X1311544D01*
X1312051Y380245D01*
X1312431Y379912D01*
X1312748Y379412D01*
X1313001Y378828D01*
X1313064Y377995D01*
X1313001Y377162D01*
X1312748Y376578D01*
X1312431Y376078D01*
X1312051Y375745D01*
X1311544Y375495D01*
X1310278D01*
G01X1274704Y24045D02*
Y29045D01*
X1276224D01*
X1276731Y28795D01*
X1277111Y28212D01*
X1277238Y27545D01*
X1277111Y26878D01*
X1276794Y26378D01*
X1276224Y26128D01*
X1274704D01*
G01X1279804Y29045D02*
Y24045D01*
X1282338D01*
G01X1284588D02*
X1286171Y29045D01*
X1287754Y24045D01*
G01X1287184Y25795D02*
X1285158D01*
G01X1291271Y29045D02*
Y24045D01*
G01X1289814Y29045D02*
X1292728D01*
G01X1297638Y24045D02*
X1295104D01*
Y29045D01*
X1297638D01*
G01X1296624Y26628D02*
X1295104D01*
G01X1300078Y24045D02*
Y29045D01*
X1301344D01*
X1301851Y28795D01*
X1302231Y28462D01*
X1302548Y27962D01*
X1302801Y27378D01*
X1302864Y26545D01*
X1302801Y25712D01*
X1302548Y25128D01*
X1302231Y24628D01*
X1301851Y24295D01*
X1301344Y24045D01*
X1300078D01*
G01X1274704Y407445D02*
Y412445D01*
X1276224D01*
X1276731Y412195D01*
X1277111Y411612D01*
X1277238Y410945D01*
X1277111Y410278D01*
X1276794Y409778D01*
X1276224Y409528D01*
X1274704D01*
G01X1279804Y412445D02*
Y407445D01*
X1282338D01*
G01X1284588D02*
X1286171Y412445D01*
X1287754Y407445D01*
G01X1287184Y409195D02*
X1285158D01*
G01X1291271Y412445D02*
Y407445D01*
G01X1289814Y412445D02*
X1292728D01*
G01X1297638Y407445D02*
X1295104D01*
Y412445D01*
X1297638D01*
G01X1296624Y410028D02*
X1295104D01*
G01X1300078Y407445D02*
Y412445D01*
X1301344D01*
X1301851Y412195D01*
X1302231Y411862D01*
X1302548Y411362D01*
X1302801Y410778D01*
X1302864Y409945D01*
X1302801Y409112D01*
X1302548Y408528D01*
X1302231Y408028D01*
X1301851Y407695D01*
X1301344Y407445D01*
X1300078D01*
G01X1274704Y439395D02*
Y444395D01*
X1276224D01*
X1276731Y444145D01*
X1277111Y443562D01*
X1277238Y442895D01*
X1277111Y442228D01*
X1276794Y441728D01*
X1276224Y441478D01*
X1274704D01*
G01X1279804Y444395D02*
Y439395D01*
X1282338D01*
G01X1284588D02*
X1286171Y444395D01*
X1287754Y439395D01*
G01X1287184Y441145D02*
X1285158D01*
G01X1291271Y444395D02*
Y439395D01*
G01X1289814Y444395D02*
X1292728D01*
G01X1297638Y439395D02*
X1295104D01*
Y444395D01*
X1297638D01*
G01X1296624Y441978D02*
X1295104D01*
G01X1300078Y439395D02*
Y444395D01*
X1301344D01*
X1301851Y444145D01*
X1302231Y443812D01*
X1302548Y443312D01*
X1302801Y442728D01*
X1302864Y441895D01*
X1302801Y441062D01*
X1302548Y440478D01*
X1302231Y439978D01*
X1301851Y439645D01*
X1301344Y439395D01*
X1300078D01*
G01X1274704Y471345D02*
Y476345D01*
X1276224D01*
X1276731Y476095D01*
X1277111Y475512D01*
X1277238Y474845D01*
X1277111Y474178D01*
X1276794Y473678D01*
X1276224Y473428D01*
X1274704D01*
G01X1279804Y476345D02*
Y471345D01*
X1282338D01*
G01X1284588D02*
X1286171Y476345D01*
X1287754Y471345D01*
G01X1287184Y473095D02*
X1285158D01*
G01X1291271Y476345D02*
Y471345D01*
G01X1289814Y476345D02*
X1292728D01*
G01X1297638Y471345D02*
X1295104D01*
Y476345D01*
X1297638D01*
G01X1296624Y473928D02*
X1295104D01*
G01X1300078Y471345D02*
Y476345D01*
X1301344D01*
X1301851Y476095D01*
X1302231Y475762D01*
X1302548Y475262D01*
X1302801Y474678D01*
X1302864Y473845D01*
X1302801Y473012D01*
X1302548Y472428D01*
X1302231Y471928D01*
X1301851Y471595D01*
X1301344Y471345D01*
X1300078D01*
G01X1274704Y503295D02*
Y508295D01*
X1276224D01*
X1276731Y508045D01*
X1277111Y507462D01*
X1277238Y506795D01*
X1277111Y506128D01*
X1276794Y505628D01*
X1276224Y505378D01*
X1274704D01*
G01X1279804Y508295D02*
Y503295D01*
X1282338D01*
G01X1284588D02*
X1286171Y508295D01*
X1287754Y503295D01*
G01X1287184Y505045D02*
X1285158D01*
G01X1291271Y508295D02*
Y503295D01*
G01X1289814Y508295D02*
X1292728D01*
G01X1297638Y503295D02*
X1295104D01*
Y508295D01*
X1297638D01*
G01X1296624Y505878D02*
X1295104D01*
G01X1300078Y503295D02*
Y508295D01*
X1301344D01*
X1301851Y508045D01*
X1302231Y507712D01*
X1302548Y507212D01*
X1302801Y506628D01*
X1302864Y505795D01*
X1302801Y504962D01*
X1302548Y504378D01*
X1302231Y503878D01*
X1301851Y503545D01*
X1301344Y503295D01*
X1300078D01*
G01X1274704Y535245D02*
Y540245D01*
X1276224D01*
X1276731Y539995D01*
X1277111Y539412D01*
X1277238Y538745D01*
X1277111Y538078D01*
X1276794Y537578D01*
X1276224Y537328D01*
X1274704D01*
G01X1279804Y540245D02*
Y535245D01*
X1282338D01*
G01X1284588D02*
X1286171Y540245D01*
X1287754Y535245D01*
G01X1287184Y536995D02*
X1285158D01*
G01X1291271Y540245D02*
Y535245D01*
G01X1289814Y540245D02*
X1292728D01*
G01X1297638Y535245D02*
X1295104D01*
Y540245D01*
X1297638D01*
G01X1296624Y537828D02*
X1295104D01*
G01X1300078Y535245D02*
Y540245D01*
X1301344D01*
X1301851Y539995D01*
X1302231Y539662D01*
X1302548Y539162D01*
X1302801Y538578D01*
X1302864Y537745D01*
X1302801Y536912D01*
X1302548Y536328D01*
X1302231Y535828D01*
X1301851Y535495D01*
X1301344Y535245D01*
X1300078D01*
G01X1274704Y567195D02*
Y572195D01*
X1276224D01*
X1276731Y571945D01*
X1277111Y571362D01*
X1277238Y570695D01*
X1277111Y570028D01*
X1276794Y569528D01*
X1276224Y569278D01*
X1274704D01*
G01X1279804Y572195D02*
Y567195D01*
X1282338D01*
G01X1284588D02*
X1286171Y572195D01*
X1287754Y567195D01*
G01X1287184Y568945D02*
X1285158D01*
G01X1291271Y572195D02*
Y567195D01*
G01X1289814Y572195D02*
X1292728D01*
G01X1297638Y567195D02*
X1295104D01*
Y572195D01*
X1297638D01*
G01X1296624Y569778D02*
X1295104D01*
G01X1300078Y567195D02*
Y572195D01*
X1301344D01*
X1301851Y571945D01*
X1302231Y571612D01*
X1302548Y571112D01*
X1302801Y570528D01*
X1302864Y569695D01*
X1302801Y568862D01*
X1302548Y568278D01*
X1302231Y567778D01*
X1301851Y567445D01*
X1301344Y567195D01*
X1300078D01*
G01X1274704Y599145D02*
Y604145D01*
X1276224D01*
X1276731Y603895D01*
X1277111Y603312D01*
X1277238Y602645D01*
X1277111Y601978D01*
X1276794Y601478D01*
X1276224Y601228D01*
X1274704D01*
G01X1279804Y604145D02*
Y599145D01*
X1282338D01*
G01X1284588D02*
X1286171Y604145D01*
X1287754Y599145D01*
G01X1287184Y600895D02*
X1285158D01*
G01X1291271Y604145D02*
Y599145D01*
G01X1289814Y604145D02*
X1292728D01*
G01X1297638Y599145D02*
X1295104D01*
Y604145D01*
X1297638D01*
G01X1296624Y601728D02*
X1295104D01*
G01X1300078Y599145D02*
Y604145D01*
X1301344D01*
X1301851Y603895D01*
X1302231Y603562D01*
X1302548Y603062D01*
X1302801Y602478D01*
X1302864Y601645D01*
X1302801Y600812D01*
X1302548Y600228D01*
X1302231Y599728D01*
X1301851Y599395D01*
X1301344Y599145D01*
X1300078D01*
G01X1274704Y631095D02*
Y636095D01*
X1276224D01*
X1276731Y635845D01*
X1277111Y635262D01*
X1277238Y634595D01*
X1277111Y633928D01*
X1276794Y633428D01*
X1276224Y633178D01*
X1274704D01*
G01X1279804Y636095D02*
Y631095D01*
X1282338D01*
G01X1284588D02*
X1286171Y636095D01*
X1287754Y631095D01*
G01X1287184Y632845D02*
X1285158D01*
G01X1291271Y636095D02*
Y631095D01*
G01X1289814Y636095D02*
X1292728D01*
G01X1297638Y631095D02*
X1295104D01*
Y636095D01*
X1297638D01*
G01X1296624Y633678D02*
X1295104D01*
G01X1300078Y631095D02*
Y636095D01*
X1301344D01*
X1301851Y635845D01*
X1302231Y635512D01*
X1302548Y635012D01*
X1302801Y634428D01*
X1302864Y633595D01*
X1302801Y632762D01*
X1302548Y632178D01*
X1302231Y631678D01*
X1301851Y631345D01*
X1301344Y631095D01*
X1300078D01*
G01X1274704Y663045D02*
Y668045D01*
X1276224D01*
X1276731Y667795D01*
X1277111Y667212D01*
X1277238Y666545D01*
X1277111Y665878D01*
X1276794Y665378D01*
X1276224Y665128D01*
X1274704D01*
G01X1279804Y668045D02*
Y663045D01*
X1282338D01*
G01X1284588D02*
X1286171Y668045D01*
X1287754Y663045D01*
G01X1287184Y664795D02*
X1285158D01*
G01X1291271Y668045D02*
Y663045D01*
G01X1289814Y668045D02*
X1292728D01*
G01X1297638Y663045D02*
X1295104D01*
Y668045D01*
X1297638D01*
G01X1296624Y665628D02*
X1295104D01*
G01X1300078Y663045D02*
Y668045D01*
X1301344D01*
X1301851Y667795D01*
X1302231Y667462D01*
X1302548Y666962D01*
X1302801Y666378D01*
X1302864Y665545D01*
X1302801Y664712D01*
X1302548Y664128D01*
X1302231Y663628D01*
X1301851Y663295D01*
X1301344Y663045D01*
X1300078D01*
G01X1274704Y694995D02*
Y699995D01*
X1276224D01*
X1276731Y699745D01*
X1277111Y699162D01*
X1277238Y698495D01*
X1277111Y697828D01*
X1276794Y697328D01*
X1276224Y697078D01*
X1274704D01*
G01X1279804Y699995D02*
Y694995D01*
X1282338D01*
G01X1284588D02*
X1286171Y699995D01*
X1287754Y694995D01*
G01X1287184Y696745D02*
X1285158D01*
G01X1291271Y699995D02*
Y694995D01*
G01X1289814Y699995D02*
X1292728D01*
G01X1297638Y694995D02*
X1295104D01*
Y699995D01*
X1297638D01*
G01X1296624Y697578D02*
X1295104D01*
G01X1300078Y694995D02*
Y699995D01*
X1301344D01*
X1301851Y699745D01*
X1302231Y699412D01*
X1302548Y698912D01*
X1302801Y698328D01*
X1302864Y697495D01*
X1302801Y696662D01*
X1302548Y696078D01*
X1302231Y695578D01*
X1301851Y695245D01*
X1301344Y694995D01*
X1300078D01*
G01X1274704Y726945D02*
Y731945D01*
X1276224D01*
X1276731Y731695D01*
X1277111Y731112D01*
X1277238Y730445D01*
X1277111Y729778D01*
X1276794Y729278D01*
X1276224Y729028D01*
X1274704D01*
G01X1279804Y731945D02*
Y726945D01*
X1282338D01*
G01X1284588D02*
X1286171Y731945D01*
X1287754Y726945D01*
G01X1287184Y728695D02*
X1285158D01*
G01X1291271Y731945D02*
Y726945D01*
G01X1289814Y731945D02*
X1292728D01*
G01X1297638Y726945D02*
X1295104D01*
Y731945D01*
X1297638D01*
G01X1296624Y729528D02*
X1295104D01*
G01X1300078Y726945D02*
Y731945D01*
X1301344D01*
X1301851Y731695D01*
X1302231Y731362D01*
X1302548Y730862D01*
X1302801Y730278D01*
X1302864Y729445D01*
X1302801Y728612D01*
X1302548Y728028D01*
X1302231Y727528D01*
X1301851Y727195D01*
X1301344Y726945D01*
X1300078D01*
G01X1274704Y758895D02*
Y763895D01*
X1276224D01*
X1276731Y763645D01*
X1277111Y763062D01*
X1277238Y762395D01*
X1277111Y761728D01*
X1276794Y761228D01*
X1276224Y760978D01*
X1274704D01*
G01X1279804Y763895D02*
Y758895D01*
X1282338D01*
G01X1284588D02*
X1286171Y763895D01*
X1287754Y758895D01*
G01X1287184Y760645D02*
X1285158D01*
G01X1291271Y763895D02*
Y758895D01*
G01X1289814Y763895D02*
X1292728D01*
G01X1297638Y758895D02*
X1295104D01*
Y763895D01*
X1297638D01*
G01X1296624Y761478D02*
X1295104D01*
G01X1300078Y758895D02*
Y763895D01*
X1301344D01*
X1301851Y763645D01*
X1302231Y763312D01*
X1302548Y762812D01*
X1302801Y762228D01*
X1302864Y761395D01*
X1302801Y760562D01*
X1302548Y759978D01*
X1302231Y759478D01*
X1301851Y759145D01*
X1301344Y758895D01*
X1300078D01*
G01X1274704Y790845D02*
Y795845D01*
X1276224D01*
X1276731Y795595D01*
X1277111Y795012D01*
X1277238Y794345D01*
X1277111Y793678D01*
X1276794Y793178D01*
X1276224Y792928D01*
X1274704D01*
G01X1279804Y795845D02*
Y790845D01*
X1282338D01*
G01X1284588D02*
X1286171Y795845D01*
X1287754Y790845D01*
G01X1287184Y792595D02*
X1285158D01*
G01X1291271Y795845D02*
Y790845D01*
G01X1289814Y795845D02*
X1292728D01*
G01X1297638Y790845D02*
X1295104D01*
Y795845D01*
X1297638D01*
G01X1296624Y793428D02*
X1295104D01*
G01X1300078Y790845D02*
Y795845D01*
X1301344D01*
X1301851Y795595D01*
X1302231Y795262D01*
X1302548Y794762D01*
X1302801Y794178D01*
X1302864Y793345D01*
X1302801Y792512D01*
X1302548Y791928D01*
X1302231Y791428D01*
X1301851Y791095D01*
X1301344Y790845D01*
X1300078D01*
G01X1274704Y822795D02*
Y827795D01*
X1276224D01*
X1276731Y827545D01*
X1277111Y826962D01*
X1277238Y826295D01*
X1277111Y825628D01*
X1276794Y825128D01*
X1276224Y824878D01*
X1274704D01*
G01X1279804Y827795D02*
Y822795D01*
X1282338D01*
G01X1284588D02*
X1286171Y827795D01*
X1287754Y822795D01*
G01X1287184Y824545D02*
X1285158D01*
G01X1291271Y827795D02*
Y822795D01*
G01X1289814Y827795D02*
X1292728D01*
G01X1297638Y822795D02*
X1295104D01*
Y827795D01*
X1297638D01*
G01X1296624Y825378D02*
X1295104D01*
G01X1300078Y822795D02*
Y827795D01*
X1301344D01*
X1301851Y827545D01*
X1302231Y827212D01*
X1302548Y826712D01*
X1302801Y826128D01*
X1302864Y825295D01*
X1302801Y824462D01*
X1302548Y823878D01*
X1302231Y823378D01*
X1301851Y823045D01*
X1301344Y822795D01*
X1300078D01*
G01X1274704Y854745D02*
Y859745D01*
X1276224D01*
X1276731Y859495D01*
X1277111Y858912D01*
X1277238Y858245D01*
X1277111Y857578D01*
X1276794Y857078D01*
X1276224Y856828D01*
X1274704D01*
G01X1279804Y859745D02*
Y854745D01*
X1282338D01*
G01X1284588D02*
X1286171Y859745D01*
X1287754Y854745D01*
G01X1287184Y856495D02*
X1285158D01*
G01X1291271Y859745D02*
Y854745D01*
G01X1289814Y859745D02*
X1292728D01*
G01X1297638Y854745D02*
X1295104D01*
Y859745D01*
X1297638D01*
G01X1296624Y857328D02*
X1295104D01*
G01X1300078Y854745D02*
Y859745D01*
X1301344D01*
X1301851Y859495D01*
X1302231Y859162D01*
X1302548Y858662D01*
X1302801Y858078D01*
X1302864Y857245D01*
X1302801Y856412D01*
X1302548Y855828D01*
X1302231Y855328D01*
X1301851Y854995D01*
X1301344Y854745D01*
X1300078D01*
G01X1274704Y886695D02*
Y891695D01*
X1276224D01*
X1276731Y891445D01*
X1277111Y890862D01*
X1277238Y890195D01*
X1277111Y889528D01*
X1276794Y889028D01*
X1276224Y888778D01*
X1274704D01*
G01X1279804Y891695D02*
Y886695D01*
X1282338D01*
G01X1284588D02*
X1286171Y891695D01*
X1287754Y886695D01*
G01X1287184Y888445D02*
X1285158D01*
G01X1291271Y891695D02*
Y886695D01*
G01X1289814Y891695D02*
X1292728D01*
G01X1297638Y886695D02*
X1295104D01*
Y891695D01*
X1297638D01*
G01X1296624Y889278D02*
X1295104D01*
G01X1300078Y886695D02*
Y891695D01*
X1301344D01*
X1301851Y891445D01*
X1302231Y891112D01*
X1302548Y890612D01*
X1302801Y890028D01*
X1302864Y889195D01*
X1302801Y888362D01*
X1302548Y887778D01*
X1302231Y887278D01*
X1301851Y886945D01*
X1301344Y886695D01*
X1300078D01*
G01X1274704Y918645D02*
Y923645D01*
X1276224D01*
X1276731Y923395D01*
X1277111Y922812D01*
X1277238Y922145D01*
X1277111Y921478D01*
X1276794Y920978D01*
X1276224Y920728D01*
X1274704D01*
G01X1279804Y923645D02*
Y918645D01*
X1282338D01*
G01X1284588D02*
X1286171Y923645D01*
X1287754Y918645D01*
G01X1287184Y920395D02*
X1285158D01*
G01X1291271Y923645D02*
Y918645D01*
G01X1289814Y923645D02*
X1292728D01*
G01X1297638Y918645D02*
X1295104D01*
Y923645D01*
X1297638D01*
G01X1296624Y921228D02*
X1295104D01*
G01X1300078Y918645D02*
Y923645D01*
X1301344D01*
X1301851Y923395D01*
X1302231Y923062D01*
X1302548Y922562D01*
X1302801Y921978D01*
X1302864Y921145D01*
X1302801Y920312D01*
X1302548Y919728D01*
X1302231Y919228D01*
X1301851Y918895D01*
X1301344Y918645D01*
X1300078D01*
G01X1274704Y950595D02*
Y955595D01*
X1276224D01*
X1276731Y955345D01*
X1277111Y954762D01*
X1277238Y954095D01*
X1277111Y953428D01*
X1276794Y952928D01*
X1276224Y952678D01*
X1274704D01*
G01X1279804Y955595D02*
Y950595D01*
X1282338D01*
G01X1284588D02*
X1286171Y955595D01*
X1287754Y950595D01*
G01X1287184Y952345D02*
X1285158D01*
G01X1291271Y955595D02*
Y950595D01*
G01X1289814Y955595D02*
X1292728D01*
G01X1297638Y950595D02*
X1295104D01*
Y955595D01*
X1297638D01*
G01X1296624Y953178D02*
X1295104D01*
G01X1300078Y950595D02*
Y955595D01*
X1301344D01*
X1301851Y955345D01*
X1302231Y955012D01*
X1302548Y954512D01*
X1302801Y953928D01*
X1302864Y953095D01*
X1302801Y952262D01*
X1302548Y951678D01*
X1302231Y951178D01*
X1301851Y950845D01*
X1301344Y950595D01*
X1300078D01*
G01X1274704Y972870D02*
Y977870D01*
X1276224D01*
X1276731Y977620D01*
X1277111Y977037D01*
X1277238Y976370D01*
X1277111Y975703D01*
X1276794Y975203D01*
X1276224Y974953D01*
X1274704D01*
G01X1279804Y977870D02*
Y972870D01*
X1282338D01*
G01X1284588D02*
X1286171Y977870D01*
X1287754Y972870D01*
G01X1287184Y974620D02*
X1285158D01*
G01X1291271Y977870D02*
Y972870D01*
G01X1289814Y977870D02*
X1292728D01*
G01X1297638Y972870D02*
X1295104D01*
Y977870D01*
X1297638D01*
G01X1296624Y975453D02*
X1295104D01*
G01X1300078Y972870D02*
Y977870D01*
X1301344D01*
X1301851Y977620D01*
X1302231Y977287D01*
X1302548Y976787D01*
X1302801Y976203D01*
X1302864Y975370D01*
X1302801Y974537D01*
X1302548Y973953D01*
X1302231Y973453D01*
X1301851Y973120D01*
X1301344Y972870D01*
X1300078D01*
G01X1329618Y28212D02*
X1329998Y28712D01*
X1330441Y28962D01*
X1330948Y29045D01*
X1331581Y28878D01*
X1332024Y28462D01*
X1332151Y27962D01*
X1332088Y27462D01*
X1331834Y27045D01*
X1330568Y26212D01*
X1329998Y25628D01*
X1329618Y24795D01*
X1329491Y24045D01*
X1332151D01*
G01X1330821Y55995D02*
Y60995D01*
X1330061Y59995D01*
G01Y55995D02*
X1331581D01*
G01X1329618Y92112D02*
X1329998Y92612D01*
X1330441Y92862D01*
X1330948Y92945D01*
X1331581Y92778D01*
X1332024Y92362D01*
X1332151Y91862D01*
X1332088Y91362D01*
X1331834Y90945D01*
X1330568Y90112D01*
X1329998Y89528D01*
X1329618Y88695D01*
X1329491Y87945D01*
X1332151D01*
G01X1329618Y124062D02*
X1329998Y124562D01*
X1330441Y124812D01*
X1330948Y124895D01*
X1331581Y124728D01*
X1332024Y124312D01*
X1332151Y123812D01*
X1332088Y123312D01*
X1331834Y122895D01*
X1330568Y122062D01*
X1329998Y121478D01*
X1329618Y120645D01*
X1329491Y119895D01*
X1332151D01*
G01X1329618Y156012D02*
X1329998Y156512D01*
X1330441Y156762D01*
X1330948Y156845D01*
X1331581Y156678D01*
X1332024Y156262D01*
X1332151Y155762D01*
X1332088Y155262D01*
X1331834Y154845D01*
X1330568Y154012D01*
X1329998Y153428D01*
X1329618Y152595D01*
X1329491Y151845D01*
X1332151D01*
G01X1331581Y183795D02*
Y188795D01*
X1329238Y185212D01*
X1332404D01*
G01X1330821Y215745D02*
Y220745D01*
X1330061Y219745D01*
G01Y215745D02*
X1331581D01*
G01X1329618Y251862D02*
X1329998Y252362D01*
X1330441Y252612D01*
X1330948Y252695D01*
X1331581Y252528D01*
X1332024Y252112D01*
X1332151Y251612D01*
X1332088Y251112D01*
X1331834Y250695D01*
X1330568Y249862D01*
X1329998Y249278D01*
X1329618Y248445D01*
X1329491Y247695D01*
X1332151D01*
G01X1328271Y279645D02*
Y284645D01*
X1327511Y283645D01*
G01Y279645D02*
X1329031D01*
G01X1332168Y281728D02*
X1332611Y282312D01*
X1332991Y282645D01*
X1333498Y282812D01*
X1333941Y282645D01*
X1334258Y282312D01*
X1334511Y281812D01*
X1334574Y281228D01*
X1334511Y280728D01*
X1334258Y280228D01*
X1333878Y279812D01*
X1333434Y279645D01*
X1332928Y279812D01*
X1332484Y280312D01*
X1332231Y281062D01*
X1332168Y281895D01*
X1332294Y282978D01*
X1332484Y283562D01*
X1332801Y284145D01*
X1333244Y284562D01*
X1333688Y284645D01*
X1334131Y284478D01*
X1334448Y284062D01*
G01X1331581Y311595D02*
Y316595D01*
X1329238Y313012D01*
X1332404D01*
G01X1330821Y343545D02*
Y348545D01*
X1330061Y347545D01*
G01Y343545D02*
X1331581D01*
G01X1329618Y379662D02*
X1329998Y380162D01*
X1330441Y380412D01*
X1330948Y380495D01*
X1331581Y380328D01*
X1332024Y379912D01*
X1332151Y379412D01*
X1332088Y378912D01*
X1331834Y378495D01*
X1330568Y377662D01*
X1329998Y377078D01*
X1329618Y376245D01*
X1329491Y375495D01*
X1332151D01*
G01X1330821Y407445D02*
Y412445D01*
X1330061Y411445D01*
G01Y407445D02*
X1331581D01*
G01X1330821Y439395D02*
X1331264Y439478D01*
X1331771Y439728D01*
X1332088Y440145D01*
X1332214Y440728D01*
X1332088Y441312D01*
X1331708Y441812D01*
X1331138Y442062D01*
X1330504D01*
X1330124Y442228D01*
X1329808Y442645D01*
X1329681Y443228D01*
X1329871Y443812D01*
X1330314Y444228D01*
X1330821Y444395D01*
X1331328Y444228D01*
X1331771Y443812D01*
X1331961Y443228D01*
X1331834Y442645D01*
X1331518Y442228D01*
X1331138Y442062D01*
X1330504D01*
X1329934Y441812D01*
X1329554Y441312D01*
X1329428Y440728D01*
X1329554Y440145D01*
X1329871Y439728D01*
X1330378Y439478D01*
X1330821Y439395D01*
G01X1331581Y471345D02*
Y476345D01*
X1329238Y472762D01*
X1332404D01*
G01X1329618Y507462D02*
X1329998Y507962D01*
X1330441Y508212D01*
X1330948Y508295D01*
X1331581Y508128D01*
X1332024Y507712D01*
X1332151Y507212D01*
X1332088Y506712D01*
X1331834Y506295D01*
X1330568Y505462D01*
X1329998Y504878D01*
X1329618Y504045D01*
X1329491Y503295D01*
X1332151D01*
G01X1331581Y535245D02*
Y540245D01*
X1329238Y536662D01*
X1332404D01*
G01X1326878Y568195D02*
X1327258Y567612D01*
X1327764Y567278D01*
X1328334Y567195D01*
X1328841Y567278D01*
X1329348Y567695D01*
X1329664Y568195D01*
X1329728Y568695D01*
X1329601Y569278D01*
X1329158Y569695D01*
X1328714Y569862D01*
X1328144D01*
G01X1328714D02*
X1329094Y570112D01*
X1329411Y570528D01*
X1329538Y571028D01*
X1329411Y571528D01*
X1329094Y571945D01*
X1328524Y572195D01*
X1327954Y572112D01*
X1327384Y571778D01*
G01X1333371Y572195D02*
X1332864Y572028D01*
X1332484Y571612D01*
X1332231Y571112D01*
X1332041Y570445D01*
X1331978Y569695D01*
X1332041Y568945D01*
X1332231Y568278D01*
X1332484Y567778D01*
X1332864Y567362D01*
X1333371Y567195D01*
X1333878Y567362D01*
X1334258Y567778D01*
X1334511Y568278D01*
X1334701Y568945D01*
X1334764Y569695D01*
X1334701Y570445D01*
X1334511Y571112D01*
X1334258Y571612D01*
X1333878Y572028D01*
X1333371Y572195D01*
G01X1330821Y599145D02*
Y604145D01*
X1330061Y603145D01*
G01Y599145D02*
X1331581D01*
G01X1329618Y635262D02*
X1329998Y635762D01*
X1330441Y636012D01*
X1330948Y636095D01*
X1331581Y635928D01*
X1332024Y635512D01*
X1332151Y635012D01*
X1332088Y634512D01*
X1331834Y634095D01*
X1330568Y633262D01*
X1329998Y632678D01*
X1329618Y631845D01*
X1329491Y631095D01*
X1332151D01*
G01X1327068Y667212D02*
X1327448Y667712D01*
X1327891Y667962D01*
X1328398Y668045D01*
X1329031Y667878D01*
X1329474Y667462D01*
X1329601Y666962D01*
X1329538Y666462D01*
X1329284Y666045D01*
X1328018Y665212D01*
X1327448Y664628D01*
X1327068Y663795D01*
X1326941Y663045D01*
X1329601D01*
G01X1331978Y663795D02*
X1332358Y663378D01*
X1332801Y663128D01*
X1333371Y663045D01*
X1333941Y663212D01*
X1334384Y663545D01*
X1334701Y664128D01*
X1334764Y664795D01*
X1334638Y665462D01*
X1334321Y665878D01*
X1333878Y666212D01*
X1333434Y666295D01*
X1332991Y666212D01*
X1332421Y665878D01*
X1332611Y668045D01*
X1334321D01*
G01X1330821Y694995D02*
X1331264Y695078D01*
X1331771Y695328D01*
X1332088Y695745D01*
X1332214Y696328D01*
X1332088Y696912D01*
X1331708Y697412D01*
X1331138Y697662D01*
X1330504D01*
X1330124Y697828D01*
X1329808Y698245D01*
X1329681Y698828D01*
X1329871Y699412D01*
X1330314Y699828D01*
X1330821Y699995D01*
X1331328Y699828D01*
X1331771Y699412D01*
X1331961Y698828D01*
X1331834Y698245D01*
X1331518Y697828D01*
X1331138Y697662D01*
X1330504D01*
X1329934Y697412D01*
X1329554Y696912D01*
X1329428Y696328D01*
X1329554Y695745D01*
X1329871Y695328D01*
X1330378Y695078D01*
X1330821Y694995D01*
G01X1328271Y726945D02*
Y731945D01*
X1327511Y730945D01*
G01Y726945D02*
X1329031D01*
G01X1331978Y727695D02*
X1332358Y727278D01*
X1332801Y727028D01*
X1333371Y726945D01*
X1333941Y727112D01*
X1334384Y727445D01*
X1334701Y728028D01*
X1334764Y728695D01*
X1334638Y729362D01*
X1334321Y729778D01*
X1333878Y730112D01*
X1333434Y730195D01*
X1332991Y730112D01*
X1332421Y729778D01*
X1332611Y731945D01*
X1334321D01*
G01X1330694Y758895D02*
X1330821Y759978D01*
X1331011Y760895D01*
X1331264Y761728D01*
X1331581Y762645D01*
X1332088Y763895D01*
X1329554D01*
G01X1330821Y790845D02*
X1331264Y790928D01*
X1331771Y791178D01*
X1332088Y791595D01*
X1332214Y792178D01*
X1332088Y792762D01*
X1331708Y793262D01*
X1331138Y793512D01*
X1330504D01*
X1330124Y793678D01*
X1329808Y794095D01*
X1329681Y794678D01*
X1329871Y795262D01*
X1330314Y795678D01*
X1330821Y795845D01*
X1331328Y795678D01*
X1331771Y795262D01*
X1331961Y794678D01*
X1331834Y794095D01*
X1331518Y793678D01*
X1331138Y793512D01*
X1330504D01*
X1329934Y793262D01*
X1329554Y792762D01*
X1329428Y792178D01*
X1329554Y791595D01*
X1329871Y791178D01*
X1330378Y790928D01*
X1330821Y790845D01*
G01X1328271Y822795D02*
Y827795D01*
X1327511Y826795D01*
G01Y822795D02*
X1329031D01*
G01X1332168Y826962D02*
X1332548Y827462D01*
X1332991Y827712D01*
X1333498Y827795D01*
X1334131Y827628D01*
X1334574Y827212D01*
X1334701Y826712D01*
X1334638Y826212D01*
X1334384Y825795D01*
X1333118Y824962D01*
X1332548Y824378D01*
X1332168Y823545D01*
X1332041Y822795D01*
X1334701D01*
G01X1323171Y854745D02*
Y859745D01*
X1322411Y858745D01*
G01Y854745D02*
X1323931D01*
G01X1327068Y856828D02*
X1327511Y857412D01*
X1327891Y857745D01*
X1328398Y857912D01*
X1328841Y857745D01*
X1329158Y857412D01*
X1329411Y856912D01*
X1329474Y856328D01*
X1329411Y855828D01*
X1329158Y855328D01*
X1328778Y854912D01*
X1328334Y854745D01*
X1327828Y854912D01*
X1327384Y855412D01*
X1327131Y856162D01*
X1327068Y856995D01*
X1327194Y858078D01*
X1327384Y858662D01*
X1327701Y859245D01*
X1328144Y859662D01*
X1328588Y859745D01*
X1329031Y859578D01*
X1329348Y859162D01*
G01X1333371Y854745D02*
Y859745D01*
X1332611Y858745D01*
G01Y854745D02*
X1334131D01*
G01X1337268Y858912D02*
X1337648Y859412D01*
X1338091Y859662D01*
X1338598Y859745D01*
X1339231Y859578D01*
X1339674Y859162D01*
X1339801Y858662D01*
X1339738Y858162D01*
X1339484Y857745D01*
X1338218Y856912D01*
X1337648Y856328D01*
X1337268Y855495D01*
X1337141Y854745D01*
X1339801D01*
G01X1323931Y886695D02*
Y891695D01*
X1321588Y888112D01*
X1324754D01*
G01X1326878Y887695D02*
X1327258Y887112D01*
X1327764Y886778D01*
X1328334Y886695D01*
X1328841Y886778D01*
X1329348Y887195D01*
X1329664Y887695D01*
X1329728Y888195D01*
X1329601Y888778D01*
X1329158Y889195D01*
X1328714Y889362D01*
X1328144D01*
G01X1328714D02*
X1329094Y889612D01*
X1329411Y890028D01*
X1329538Y890528D01*
X1329411Y891028D01*
X1329094Y891445D01*
X1328524Y891695D01*
X1327954Y891612D01*
X1327384Y891278D01*
G01X1332294Y887278D02*
X1332738Y886862D01*
X1333244Y886695D01*
X1333751Y886862D01*
X1334194Y887362D01*
X1334511Y888112D01*
X1334638Y888862D01*
Y889778D01*
X1334511Y890528D01*
X1334194Y891195D01*
X1333814Y891528D01*
X1333371Y891695D01*
X1332864Y891528D01*
X1332484Y891195D01*
X1332231Y890695D01*
X1332104Y890028D01*
X1332231Y889445D01*
X1332548Y888862D01*
X1332928Y888528D01*
X1333371Y888445D01*
X1333878Y888612D01*
X1334258Y889028D01*
X1334638Y889778D01*
G01X1338471Y886695D02*
X1338914Y886778D01*
X1339421Y887028D01*
X1339738Y887445D01*
X1339864Y888028D01*
X1339738Y888612D01*
X1339358Y889112D01*
X1338788Y889362D01*
X1338154D01*
X1337774Y889528D01*
X1337458Y889945D01*
X1337331Y890528D01*
X1337521Y891112D01*
X1337964Y891528D01*
X1338471Y891695D01*
X1338978Y891528D01*
X1339421Y891112D01*
X1339611Y890528D01*
X1339484Y889945D01*
X1339168Y889528D01*
X1338788Y889362D01*
X1338154D01*
X1337584Y889112D01*
X1337204Y888612D01*
X1337078Y888028D01*
X1337204Y887445D01*
X1337521Y887028D01*
X1338028Y886778D01*
X1338471Y886695D01*
G01X1328271Y918645D02*
Y923645D01*
X1327511Y922645D01*
G01Y918645D02*
X1329031D01*
G01X1333371Y923645D02*
X1332864Y923478D01*
X1332484Y923062D01*
X1332231Y922562D01*
X1332041Y921895D01*
X1331978Y921145D01*
X1332041Y920395D01*
X1332231Y919728D01*
X1332484Y919228D01*
X1332864Y918812D01*
X1333371Y918645D01*
X1333878Y918812D01*
X1334258Y919228D01*
X1334511Y919728D01*
X1334701Y920395D01*
X1334764Y921145D01*
X1334701Y921895D01*
X1334511Y922562D01*
X1334258Y923062D01*
X1333878Y923478D01*
X1333371Y923645D01*
G01X1330821Y950595D02*
X1331264Y950678D01*
X1331771Y950928D01*
X1332088Y951345D01*
X1332214Y951928D01*
X1332088Y952512D01*
X1331708Y953012D01*
X1331138Y953262D01*
X1330504D01*
X1330124Y953428D01*
X1329808Y953845D01*
X1329681Y954428D01*
X1329871Y955012D01*
X1330314Y955428D01*
X1330821Y955595D01*
X1331328Y955428D01*
X1331771Y955012D01*
X1331961Y954428D01*
X1331834Y953845D01*
X1331518Y953428D01*
X1331138Y953262D01*
X1330504D01*
X1329934Y953012D01*
X1329554Y952512D01*
X1329428Y951928D01*
X1329554Y951345D01*
X1329871Y950928D01*
X1330378Y950678D01*
X1330821Y950595D01*
G01X1325721Y972870D02*
X1325214Y972953D01*
X1324771Y973287D01*
X1324391Y973787D01*
X1324138Y974370D01*
X1324011Y975037D01*
Y975703D01*
X1324138Y976370D01*
X1324391Y976953D01*
X1324771Y977453D01*
X1325214Y977787D01*
X1325721Y977870D01*
X1326228Y977787D01*
X1326671Y977453D01*
X1327051Y976953D01*
X1327304Y976370D01*
X1327431Y975703D01*
Y975037D01*
X1327304Y974370D01*
X1327051Y973787D01*
X1326671Y973287D01*
X1326228Y972953D01*
X1325721Y972870D01*
G01X1326228Y974203D02*
X1326988Y972870D01*
G01X1330821Y977870D02*
Y972870D01*
G01X1329364Y977870D02*
X1332278D01*
G01X1335921Y972870D02*
Y975120D01*
X1334654Y977870D01*
G01X1337188D02*
X1335921Y975120D01*
G01X1691427Y435293D02*
G03I-150000J0D01*
G01X1496427Y555293D02*
X1492427D01*
Y563293D01*
X1496427D01*
G01X1494827Y559426D02*
X1492427D01*
G01X1504227Y563293D02*
Y555293D01*
G01Y556493D02*
X1503827Y555826D01*
X1503227Y555426D01*
X1502527Y555293D01*
X1501727Y555560D01*
X1501127Y556226D01*
X1500727Y557026D01*
X1500627Y557960D01*
X1500727Y558893D01*
X1501127Y559693D01*
X1501727Y560360D01*
X1502527Y560626D01*
X1503227Y560493D01*
X1503727Y560226D01*
X1504227Y559693D01*
G01X1509027Y553293D02*
X1509727Y552760D01*
X1510527Y552626D01*
X1511227Y552760D01*
X1511827Y553426D01*
X1512227Y554360D01*
Y560626D01*
G01Y559560D02*
X1511827Y560093D01*
X1511227Y560493D01*
X1510527Y560626D01*
X1509727Y560360D01*
X1509227Y559826D01*
X1508827Y558893D01*
X1508627Y557960D01*
X1508727Y557160D01*
X1509127Y556226D01*
X1509727Y555560D01*
X1510527Y555293D01*
X1511127Y555426D01*
X1511827Y555960D01*
X1512227Y556493D01*
G01X1516927Y558893D02*
X1520127D01*
X1519827Y559826D01*
X1519327Y560360D01*
X1518627Y560626D01*
X1517927Y560493D01*
X1517327Y560093D01*
X1516927Y559160D01*
X1516727Y558359D01*
Y557560D01*
X1516927Y556760D01*
X1517427Y555960D01*
X1518027Y555426D01*
X1518727Y555293D01*
X1519427Y555560D01*
X1520127Y556359D01*
G01X1536627Y562626D02*
X1536027Y563026D01*
X1535327Y563293D01*
X1534527D01*
X1533627Y562893D01*
X1532927Y562226D01*
X1532427Y561426D01*
X1532027Y560093D01*
X1531927Y558893D01*
X1532127Y557693D01*
X1532427Y556893D01*
X1533027Y556093D01*
X1533727Y555560D01*
X1534427Y555293D01*
X1535127D01*
X1535827Y555560D01*
X1536427Y555960D01*
X1536927Y556493D01*
G01X1542427Y555293D02*
X1541827Y555426D01*
X1541227Y555960D01*
X1540827Y556893D01*
X1540627Y557960D01*
X1540827Y559026D01*
X1541227Y559960D01*
X1541827Y560493D01*
X1542427Y560626D01*
X1543027Y560493D01*
X1543627Y559960D01*
X1544027Y559026D01*
X1544127Y557960D01*
X1544027Y556893D01*
X1543627Y555960D01*
X1543027Y555426D01*
X1542427Y555293D01*
G01X1548727D02*
Y560626D01*
G01Y559293D02*
X1549127Y559960D01*
X1549727Y560493D01*
X1550527Y560626D01*
X1551227Y560493D01*
X1551827Y559960D01*
X1552127Y559026D01*
Y555293D01*
G01X1556727D02*
Y560626D01*
G01Y559293D02*
X1557127Y559960D01*
X1557727Y560493D01*
X1558527Y560626D01*
X1559227Y560493D01*
X1559827Y559960D01*
X1560127Y559026D01*
Y555293D01*
G01X1564927Y558893D02*
X1568127D01*
X1567827Y559826D01*
X1567327Y560360D01*
X1566627Y560626D01*
X1565927Y560493D01*
X1565327Y560093D01*
X1564927Y559160D01*
X1564727Y558359D01*
Y557560D01*
X1564927Y556760D01*
X1565427Y555960D01*
X1566027Y555426D01*
X1566727Y555293D01*
X1567427Y555560D01*
X1568127Y556359D01*
G01X1576027Y559960D02*
X1575327Y560493D01*
X1574727Y560626D01*
X1573927Y560360D01*
X1573327Y559826D01*
X1572927Y558893D01*
X1572827Y557960D01*
X1572927Y557026D01*
X1573327Y556226D01*
X1573927Y555560D01*
X1574727Y555293D01*
X1575427Y555560D01*
X1576027Y556093D01*
G01X1582427Y563293D02*
Y555293D01*
G01X1581027Y560626D02*
X1583827D01*
G01X1590427Y555293D02*
X1589827Y555426D01*
X1589227Y555960D01*
X1588827Y556893D01*
X1588627Y557960D01*
X1588827Y559026D01*
X1589227Y559960D01*
X1589827Y560493D01*
X1590427Y560626D01*
X1591027Y560493D01*
X1591627Y559960D01*
X1592027Y559026D01*
X1592127Y557960D01*
X1592027Y556893D01*
X1591627Y555960D01*
X1591027Y555426D01*
X1590427Y555293D01*
G01X1597027D02*
Y560626D01*
G01Y559560D02*
X1597527Y560093D01*
X1598027Y560493D01*
X1598727Y560626D01*
X1599227Y560493D01*
X1599827Y560093D01*
G01X1508777Y308793D02*
Y315093D01*
X1507837Y313833D01*
G01Y308793D02*
X1509717D01*
G01X1515077Y308583D02*
X1514920Y308688D01*
Y308898D01*
X1515077Y309003D01*
X1515234Y308898D01*
Y308688D01*
X1515077Y308583D01*
G01X1519889Y311418D02*
X1520437Y312153D01*
X1520907Y312573D01*
X1521534Y312783D01*
X1522082Y312573D01*
X1522474Y312153D01*
X1522787Y311523D01*
X1522865Y310788D01*
X1522787Y310158D01*
X1522474Y309528D01*
X1522004Y309003D01*
X1521455Y308793D01*
X1520829Y309003D01*
X1520280Y309633D01*
X1519967Y310578D01*
X1519889Y311628D01*
X1520045Y312993D01*
X1520280Y313728D01*
X1520672Y314463D01*
X1521220Y314988D01*
X1521769Y315093D01*
X1522317Y314883D01*
X1522709Y314358D01*
G01X1527677Y315093D02*
X1527050Y314883D01*
X1526580Y314358D01*
X1526267Y313728D01*
X1526032Y312888D01*
X1525954Y311943D01*
X1526032Y310998D01*
X1526267Y310158D01*
X1526580Y309528D01*
X1527050Y309003D01*
X1527677Y308793D01*
X1528304Y309003D01*
X1528774Y309528D01*
X1529087Y310158D01*
X1529322Y310998D01*
X1529400Y311943D01*
X1529322Y312888D01*
X1529087Y313728D01*
X1528774Y314358D01*
X1528304Y314883D01*
X1527677Y315093D01*
G01X1531627Y308793D02*
Y312993D01*
G01Y311838D02*
X1531862Y312363D01*
X1532254Y312783D01*
X1532802Y312993D01*
X1533350Y312783D01*
X1533742Y312363D01*
X1533977Y311838D01*
Y308793D01*
G01Y311838D02*
X1534212Y312363D01*
X1534604Y312783D01*
X1535152Y312993D01*
X1535700Y312783D01*
X1536092Y312363D01*
X1536327Y311733D01*
Y308793D01*
G01X1537927D02*
Y312993D01*
G01Y311838D02*
X1538162Y312363D01*
X1538554Y312783D01*
X1539102Y312993D01*
X1539650Y312783D01*
X1540042Y312363D01*
X1540277Y311838D01*
Y308793D01*
G01Y311838D02*
X1540512Y312363D01*
X1540904Y312783D01*
X1541452Y312993D01*
X1542000Y312783D01*
X1542392Y312363D01*
X1542627Y311733D01*
Y308793D01*
G01X1559177D02*
Y315093D01*
X1558237Y313833D01*
G01Y308793D02*
X1560117D01*
G01X1565477Y315093D02*
X1564850Y314883D01*
X1564380Y314358D01*
X1564067Y313728D01*
X1563832Y312888D01*
X1563754Y311943D01*
X1563832Y310998D01*
X1564067Y310158D01*
X1564380Y309528D01*
X1564850Y309003D01*
X1565477Y308793D01*
X1566104Y309003D01*
X1566574Y309528D01*
X1566887Y310158D01*
X1567122Y310998D01*
X1567200Y311943D01*
X1567122Y312888D01*
X1566887Y313728D01*
X1566574Y314358D01*
X1566104Y314883D01*
X1565477Y315093D01*
G01X1570367Y308583D02*
X1573187Y315093D01*
G01X1570367D02*
X1569897Y314883D01*
X1569662Y314568D01*
X1569505Y313938D01*
X1569662Y313308D01*
X1569897Y312993D01*
X1570367Y312783D01*
X1570837Y312993D01*
X1571072Y313308D01*
X1571229Y313938D01*
X1571072Y314568D01*
X1570837Y314883D01*
X1570367Y315093D01*
G01X1573187Y310893D02*
X1572717Y310683D01*
X1572482Y310368D01*
X1572325Y309738D01*
X1572482Y309108D01*
X1572717Y308793D01*
X1573187Y308583D01*
X1573657Y308793D01*
X1573892Y309108D01*
X1574049Y309738D01*
X1573892Y310368D01*
X1573657Y310683D01*
X1573187Y310893D01*
G01X1531427Y326293D02*
X1516427D01*
G01X1531427Y369293D02*
Y321293D01*
G01Y326293D02*
X1526427Y327793D01*
Y324793D01*
X1531427Y326293D01*
G01Y535293D02*
Y375293D01*
X1536427Y355293D01*
X1546427D01*
X1551427Y375293D01*
Y535293D01*
X1546427Y525293D01*
X1531427Y535293D01*
G01X1548927Y308793D02*
X1553927D01*
G01X1548927Y312793D02*
X1553927D01*
G01X1548427Y355293D02*
X1595427D01*
G01X1551427Y315293D02*
Y310293D01*
G01Y369293D02*
Y321293D01*
G01Y326293D02*
X1556427Y327793D01*
Y324793D01*
X1551427Y326293D01*
G01X1566427D02*
X1551427D01*
G01X1553427Y375293D02*
X1595427D01*
G01X1594074Y545881D02*
X1552503Y379597D01*
G01X1551427Y517793D02*
X1556427Y516293D01*
Y519293D01*
X1551427Y517793D01*
G01X1599427Y498693D02*
G03X1552127Y517854I-47300J-48801D01*
G01X1569277Y399793D02*
Y406093D01*
X1568337Y404833D01*
G01Y399793D02*
X1570217D01*
G01X1575577Y399583D02*
X1575420Y399688D01*
Y399898D01*
X1575577Y400003D01*
X1575734Y399898D01*
Y399688D01*
X1575577Y399583D01*
G01X1582817Y399793D02*
Y406093D01*
X1579919Y401578D01*
X1583835D01*
G01X1588177Y406093D02*
X1587550Y405883D01*
X1587080Y405358D01*
X1586767Y404728D01*
X1586532Y403888D01*
X1586454Y402943D01*
X1586532Y401998D01*
X1586767Y401158D01*
X1587080Y400528D01*
X1587550Y400003D01*
X1588177Y399793D01*
X1588804Y400003D01*
X1589274Y400528D01*
X1589587Y401158D01*
X1589822Y401998D01*
X1589900Y402943D01*
X1589822Y403888D01*
X1589587Y404728D01*
X1589274Y405358D01*
X1588804Y405883D01*
X1588177Y406093D01*
G01X1592127Y399793D02*
Y403993D01*
G01Y402838D02*
X1592362Y403363D01*
X1592754Y403783D01*
X1593302Y403993D01*
X1593850Y403783D01*
X1594242Y403363D01*
X1594477Y402838D01*
Y399793D01*
G01Y402838D02*
X1594712Y403363D01*
X1595104Y403783D01*
X1595652Y403993D01*
X1596200Y403783D01*
X1596592Y403363D01*
X1596827Y402733D01*
Y399793D01*
G01X1598427D02*
Y403993D01*
G01Y402838D02*
X1598662Y403363D01*
X1599054Y403783D01*
X1599602Y403993D01*
X1600150Y403783D01*
X1600542Y403363D01*
X1600777Y402838D01*
Y399793D01*
G01Y402838D02*
X1601012Y403363D01*
X1601404Y403783D01*
X1601952Y403993D01*
X1602500Y403783D01*
X1602892Y403363D01*
X1603127Y402733D01*
Y399793D01*
G01X1619677Y406093D02*
X1619050Y405883D01*
X1618580Y405358D01*
X1618267Y404728D01*
X1618032Y403888D01*
X1617954Y402943D01*
X1618032Y401998D01*
X1618267Y401158D01*
X1618580Y400528D01*
X1619050Y400003D01*
X1619677Y399793D01*
X1620304Y400003D01*
X1620774Y400528D01*
X1621087Y401158D01*
X1621322Y401998D01*
X1621400Y402943D01*
X1621322Y403888D01*
X1621087Y404728D01*
X1620774Y405358D01*
X1620304Y405883D01*
X1619677Y406093D01*
G01X1625977Y399583D02*
X1625820Y399688D01*
Y399898D01*
X1625977Y400003D01*
X1626134Y399898D01*
Y399688D01*
X1625977Y399583D01*
G01X1632277Y399793D02*
Y406093D01*
X1631337Y404833D01*
G01Y399793D02*
X1633217D01*
G01X1636854Y400738D02*
X1637324Y400213D01*
X1637872Y399898D01*
X1638577Y399793D01*
X1639282Y400003D01*
X1639830Y400423D01*
X1640222Y401158D01*
X1640300Y401998D01*
X1640144Y402838D01*
X1639752Y403363D01*
X1639204Y403783D01*
X1638655Y403888D01*
X1638107Y403783D01*
X1637402Y403363D01*
X1637637Y406093D01*
X1639752D01*
G01X1584927Y509293D02*
X1579927Y510293D01*
X1581427Y512793D01*
X1584927Y509293D01*
G01X1585427Y355293D02*
X1583927Y360293D01*
X1586927D01*
X1585427Y355293D01*
G01Y395293D02*
Y355293D01*
G01Y375293D02*
X1583927Y370293D01*
X1586927D01*
X1585427Y375293D01*
G01X1587289Y491543D02*
X1587759Y492173D01*
X1588307Y492488D01*
X1588934Y492593D01*
X1589717Y492383D01*
X1590265Y491858D01*
X1590422Y491228D01*
X1590344Y490598D01*
X1590030Y490073D01*
X1588464Y489023D01*
X1587759Y488288D01*
X1587289Y487238D01*
X1587132Y486293D01*
X1590422D01*
G01X1595077Y492593D02*
X1594450Y492383D01*
X1593980Y491858D01*
X1593667Y491228D01*
X1593432Y490388D01*
X1593354Y489443D01*
X1593432Y488498D01*
X1593667Y487658D01*
X1593980Y487028D01*
X1594450Y486503D01*
X1595077Y486293D01*
X1595704Y486503D01*
X1596174Y487028D01*
X1596487Y487658D01*
X1596722Y488498D01*
X1596800Y489443D01*
X1596722Y490388D01*
X1596487Y491228D01*
X1596174Y491858D01*
X1595704Y492383D01*
X1595077Y492593D01*
G01X1612489Y491543D02*
X1612959Y492173D01*
X1613507Y492488D01*
X1614134Y492593D01*
X1614917Y492383D01*
X1615465Y491858D01*
X1615622Y491228D01*
X1615544Y490598D01*
X1615230Y490073D01*
X1613664Y489023D01*
X1612959Y488288D01*
X1612489Y487238D01*
X1612332Y486293D01*
X1615622D01*
G01X1599545Y494293D02*
G03I-1118J0D01*
G01X1611927Y406293D02*
Y401293D01*
G01X1609427Y399793D02*
X1614427D01*
G01X1609427Y403793D02*
X1614427D01*
G01X1603927Y486293D02*
X1608927D01*
G01X1606427Y492793D02*
Y487793D01*
G01X1603927Y490293D02*
X1608927D01*
G01X1618545Y494293D02*
G03I-1118J0D01*
G54D22*
X98426Y105512D03*
Y719685D03*
X1088471Y122395D03*
G54D13*
X-32872Y130713D03*
X-35872D03*
X-38872D03*
X-32872Y238033D03*
X-35872D03*
X-38872D03*
X-32872D03*
X-35872D03*
X-38872D03*
Y748993D03*
X-35872D03*
X-32872D03*
X1088471Y825295D03*
G54D31*
X481102Y34528D03*
X1088471Y409945D03*
G54D32*
X507489Y281538D03*
X1088471Y601645D03*
G54D14*
X10859Y109561D03*
X20859D03*
X83740Y20708D03*
X78740Y30708D03*
X73740Y20708D03*
X507489Y360278D03*
X713661Y20708D03*
X708661Y30708D03*
X703661Y20708D03*
X712975Y155655D03*
Y165455D03*
Y173455D03*
Y183255D03*
Y234461D03*
Y244261D03*
Y252261D03*
Y262061D03*
X723275Y155655D03*
Y165455D03*
Y173455D03*
Y183255D03*
Y234461D03*
Y244261D03*
Y252261D03*
Y262061D03*
X1088471Y665545D03*
G54D23*
X102362Y247244D03*
Y349606D03*
X354331Y247244D03*
Y349606D03*
X1088471Y186295D03*
G54D33*
X514780Y28803D03*
X524780D03*
X514780Y38803D03*
X524780D03*
X534780Y28803D03*
X544780D03*
X534780Y38803D03*
X544780D03*
X554780Y28803D03*
Y38803D03*
X577371Y28803D03*
X587371D03*
X577371Y38803D03*
X587371D03*
X597371Y28803D03*
X607371D03*
X597371Y38803D03*
X607371D03*
X617371Y28803D03*
Y38803D03*
X639963Y28803D03*
Y38803D03*
X649963Y28803D03*
Y38803D03*
X659963Y28803D03*
X669963D03*
X659963Y38803D03*
X669963D03*
X679963Y28803D03*
Y38803D03*
X1088471Y569695D03*
G54D24*
X151969Y98622D03*
X1088471Y218245D03*
G54D15*
X25439Y303260D03*
Y356804D03*
X1088471Y154345D03*
G54D16*
X23628Y321764D03*
Y338300D03*
X45282Y321764D03*
Y338300D03*
X1088471Y473845D03*
G54D34*
X546181Y81889D03*
X556181D03*
X1088471Y633595D03*
G54D25*
X159196Y515612D03*
X159179Y521893D03*
X159180Y528227D03*
X162336Y550253D03*
X178094Y531365D03*
X181491Y557436D03*
X227284Y502591D03*
X235307Y566357D03*
X284024Y502595D03*
X290323D03*
X1088471Y921145D03*
G54D17*
X20650Y546243D03*
X20350Y555807D03*
X16200Y566921D03*
X11980Y617956D03*
X15349Y614142D03*
X14550Y628297D03*
X13807Y634826D03*
X9300Y631472D03*
X33841Y9183D03*
X36588Y32278D03*
X34008Y91017D03*
X32260Y96899D03*
X33231Y556346D03*
X30672Y551245D03*
X23610Y568111D03*
X34440Y597285D03*
X28112Y591718D03*
X28185Y612088D03*
X30744Y617898D03*
X24168Y655750D03*
X37920Y651828D03*
X49890Y30392D03*
X51580Y17595D03*
X42205Y21518D03*
X54800Y25547D03*
X44010Y55170D03*
X54981Y59420D03*
X54101Y74252D03*
X51340Y69181D03*
X46570Y73891D03*
X47510Y109421D03*
X47420Y433725D03*
X53769Y513033D03*
X54988Y518683D03*
X49857Y520516D03*
X50630Y529281D03*
X50140Y550572D03*
X39540Y538464D03*
X50870Y564008D03*
X43467Y555938D03*
X49680Y579709D03*
X49620Y574212D03*
X47557Y588971D03*
X44507Y594082D03*
X40908Y589691D03*
X39370Y600956D03*
X42950Y612487D03*
X48540Y624953D03*
X52230Y614907D03*
X47480Y616848D03*
X46890Y633564D03*
X53751Y652029D03*
X44640Y651029D03*
X40980Y656396D03*
X56610Y20553D03*
X64190Y72841D03*
X61760Y107321D03*
X55230Y112521D03*
X63900Y112081D03*
X56190Y170026D03*
X57257Y180712D03*
X67853Y180744D03*
X68690Y175589D03*
X66570Y189983D03*
X68830Y215817D03*
X56287Y242872D03*
X63718Y239030D03*
X61945Y267579D03*
X66818Y297483D03*
X57994Y287655D03*
X61357Y477892D03*
X64480Y501596D03*
X62253Y522589D03*
X67369Y522993D03*
X70696Y527237D03*
X67260Y546688D03*
X65900Y566403D03*
X66262Y553344D03*
X65989Y578115D03*
X57710Y572918D03*
X57070Y580074D03*
X69766Y582525D03*
X57440Y585607D03*
X68630Y599945D03*
X61205Y623870D03*
X63570Y613914D03*
X63610Y618917D03*
X61205Y628870D03*
X56240Y630081D03*
X63650Y646957D03*
X61600Y653611D03*
X76030Y156152D03*
X82553Y185431D03*
X82030Y191733D03*
X73870Y205758D03*
X77239Y260814D03*
X81165Y257717D03*
X78373Y276029D03*
X72190Y297395D03*
X77368Y299206D03*
X83084Y389621D03*
X83245Y397913D03*
X85951Y410263D03*
X74291Y486665D03*
X83536Y498308D03*
X81635Y517104D03*
X85346Y512295D03*
X73057Y515286D03*
X72635Y508991D03*
X81491Y533191D03*
X80318Y544311D03*
X75380Y608914D03*
Y603914D03*
X101449Y194368D03*
X101020Y223348D03*
X95951Y376661D03*
X98470Y418834D03*
X91458Y511853D03*
X92422Y531081D03*
X98803Y531597D03*
X97268Y537055D03*
X96200Y616325D03*
X95310Y647481D03*
X97180Y786472D03*
X111220Y160923D03*
X106090Y167615D03*
X112530Y186363D03*
X106760Y175370D03*
X114920Y179082D03*
X108910Y193194D03*
X116960Y394023D03*
X107531D03*
X109972Y509321D03*
X106650Y779581D03*
X102421Y785938D03*
X131068Y76588D03*
X129650Y250414D03*
Y255414D03*
X118124Y510811D03*
X124279Y523691D03*
X120300Y572512D03*
X121070Y670509D03*
X132050Y671817D03*
X133607Y686699D03*
X130260Y679836D03*
X132438Y704733D03*
X133490Y695470D03*
X119900Y754021D03*
X125600Y759000D03*
X125960Y785699D03*
X120090Y780618D03*
X141490Y19267D03*
X137872Y29551D03*
X139931Y40842D03*
X139932Y35310D03*
X135050Y53493D03*
X143857Y51943D03*
X149025Y51720D03*
X135290Y87664D03*
X148330Y258806D03*
X145200Y276468D03*
X138930Y278965D03*
X148350Y281769D03*
X134540Y267786D03*
X145720Y311336D03*
X135224Y323543D03*
X146100D03*
X145580Y316836D03*
X136506Y332193D03*
X145284Y401507D03*
X142239Y422346D03*
X135300Y468444D03*
X146240Y472111D03*
X149050Y588044D03*
X148200Y669205D03*
X140110Y675907D03*
X139158Y686725D03*
X135280Y679212D03*
X138726Y696707D03*
X138198Y712628D03*
X144631Y735955D03*
X135470Y781697D03*
X145570Y780580D03*
X157877Y30674D03*
X152810Y29921D03*
X158165Y21300D03*
X159861Y36134D03*
X157010Y58963D03*
X164550Y61239D03*
X156440Y74863D03*
X151618Y83343D03*
X164280Y101810D03*
X164490Y127110D03*
X159190Y127781D03*
X152990Y248096D03*
X157690Y249918D03*
X154546Y256986D03*
X152634Y276809D03*
X149721Y292987D03*
X152733Y288517D03*
X158076Y290635D03*
X154581Y308767D03*
X151230Y330164D03*
X150918Y318134D03*
X150510Y336306D03*
X156448Y336629D03*
X162071Y336947D03*
X161563Y432521D03*
X154370Y449930D03*
X150547Y459363D03*
X162335Y512456D03*
X154126Y524411D03*
X154475Y530422D03*
X162335Y543954D03*
X159185Y537654D03*
X164259Y557273D03*
X161280Y581585D03*
X156480Y583315D03*
X150380Y602885D03*
X157963Y633735D03*
X161981Y730784D03*
X163138Y778565D03*
X155170Y780656D03*
X160320Y786346D03*
X168961Y27073D03*
X180159Y40661D03*
X165336Y46126D03*
X167383Y93147D03*
X168850Y99251D03*
X169510Y106579D03*
X174710Y105699D03*
X177763Y121057D03*
X168170Y123367D03*
X173170D03*
X178040Y228978D03*
X167483Y239914D03*
X177891Y249324D03*
X175756Y257668D03*
X178025Y279018D03*
X178810Y287263D03*
X174148Y289289D03*
X168110Y350642D03*
X180430Y392969D03*
X180440Y398056D03*
X167527Y420268D03*
X179562Y424001D03*
X170683Y436834D03*
X170361Y428595D03*
X169728Y487664D03*
X168189Y514331D03*
X178085Y512456D03*
X173252Y515693D03*
X165707Y506156D03*
X172087Y510536D03*
X169615Y519216D03*
X166297Y532416D03*
X169491Y529702D03*
X166837Y523486D03*
X174395Y527975D03*
X168243Y542706D03*
X174930Y547106D03*
X169157Y548676D03*
X173163Y551903D03*
X169444Y558757D03*
X167105Y552882D03*
X178083Y553402D03*
X172889Y562710D03*
X175330Y578535D03*
X166930Y578435D03*
X166786Y569056D03*
X172430Y584035D03*
X177830Y583535D03*
X166570Y583874D03*
X179120Y639615D03*
X169930Y635329D03*
X172510Y639771D03*
X167810Y668131D03*
X171180Y683815D03*
X180820Y717914D03*
X175463Y720245D03*
X174954Y728404D03*
X167568Y743335D03*
X177224Y777765D03*
X169860Y782086D03*
X191596Y27620D03*
X184928Y91847D03*
X189928D03*
X196653Y91837D03*
X196493Y105637D03*
X188203Y104567D03*
X194463Y122631D03*
X184050Y230139D03*
X184296Y241098D03*
X181176Y257643D03*
X183440Y269816D03*
X183198Y278034D03*
X192298Y286183D03*
X183254Y310663D03*
X183228Y317023D03*
X191159Y317171D03*
X190557Y325701D03*
X192040Y333606D03*
X195420Y372406D03*
X192681Y377554D03*
X193590Y383383D03*
X196273Y403152D03*
X190700Y418325D03*
X192527Y429049D03*
X189077Y438281D03*
X184843Y533995D03*
X191457Y531553D03*
X193466Y546886D03*
X186841Y545372D03*
X193080Y581235D03*
X182480Y566819D03*
X196740Y589735D03*
X192130Y632235D03*
X184748Y639687D03*
X182480Y634585D03*
X191480Y639135D03*
X185993Y682670D03*
X191542Y691925D03*
X181950Y698191D03*
X188566Y722353D03*
X183566D03*
X193566Y722333D03*
X192949Y771020D03*
X182500Y780786D03*
X189770Y778082D03*
X204978Y10605D03*
X204003Y91247D03*
X208908Y96975D03*
X205903Y101477D03*
X210623Y121267D03*
X207154Y175212D03*
X207070Y188978D03*
X205535Y234497D03*
Y228682D03*
X211935Y230585D03*
X205271Y240209D03*
X198685Y237385D03*
Y244085D03*
X210305Y259330D03*
X200977Y256305D03*
X208000Y325200D03*
X206973Y361900D03*
X201267Y403294D03*
X204584Y462478D03*
X197161Y465628D03*
X211609Y516553D03*
X205257Y528822D03*
X211287Y528547D03*
X212342Y536729D03*
X199539Y537112D03*
X204309Y539953D03*
X205286Y551130D03*
X211240Y572893D03*
X201510Y576885D03*
X197730Y572893D03*
X197709Y567464D03*
X210790Y566926D03*
X209940Y584893D03*
X204024Y604135D03*
Y609135D03*
X208904Y611515D03*
X200380Y629085D03*
X199786Y618893D03*
X202510Y624005D03*
X208904Y616515D03*
X197480Y639815D03*
X203065Y638700D03*
X205221Y630886D03*
X205410Y661200D03*
X211560Y670575D03*
X199590Y682868D03*
X199350Y692724D03*
X198566Y722353D03*
X209017Y722344D03*
X203611Y722303D03*
X199760Y763929D03*
X202050Y784919D03*
X206210Y771577D03*
X212350Y773283D03*
X215773Y90147D03*
X220200Y93561D03*
X226620Y89385D03*
X214320Y101978D03*
X220983Y106174D03*
X213908Y96975D03*
X219510Y101338D03*
X228138Y125802D03*
X226010Y233542D03*
X217135Y230585D03*
Y240785D03*
X216512Y258490D03*
X214657Y356205D03*
X214007Y362701D03*
X222225Y364031D03*
X227745Y368007D03*
X214786Y388603D03*
X218090Y390891D03*
X215120Y399654D03*
X214406Y395539D03*
X223085Y401702D03*
X222419Y479933D03*
X218040Y473853D03*
X226255Y472579D03*
X224209Y491853D03*
X217609Y516353D03*
X219328Y528823D03*
X223376Y523322D03*
X215946Y544202D03*
X218950Y565589D03*
X227100Y580916D03*
X219960Y596373D03*
Y601373D03*
X215699Y625977D03*
X216107Y637977D03*
X228290Y629893D03*
X218240Y674433D03*
X217530Y715305D03*
X221320Y720698D03*
X213310Y719064D03*
X222710Y713706D03*
X216820Y723301D03*
X218270Y785657D03*
X220960Y778561D03*
X226670Y773299D03*
X243373Y88767D03*
X239563Y92077D03*
X233083Y94817D03*
X242913Y106157D03*
X233138Y125802D03*
X232948Y234047D03*
X236710Y244042D03*
X242460Y237591D03*
X237654Y249719D03*
X231710Y240242D03*
X240925Y306257D03*
X228419Y356855D03*
X233635Y357082D03*
X230010Y373300D03*
X237578Y369584D03*
X233136Y367070D03*
X243078Y368384D03*
X231257Y362218D03*
X236430Y393470D03*
X231461Y462591D03*
X243471Y460292D03*
X238430Y460338D03*
X234209Y480953D03*
X228604Y479682D03*
X229269Y597682D03*
X242830Y597415D03*
X234370Y593242D03*
X242796Y589749D03*
X236780Y628738D03*
X229199Y642180D03*
X243693Y632254D03*
X238420Y642148D03*
X229584Y652668D03*
X237451Y652761D03*
X243596Y671772D03*
X229895Y671672D03*
X237275Y679609D03*
X242680Y712337D03*
X234960Y714064D03*
X234910Y720816D03*
X236180Y786517D03*
X242230Y774803D03*
X234011Y772902D03*
X258300Y22289D03*
X252683Y105867D03*
X253558Y95038D03*
X256133Y99347D03*
X248558Y95038D03*
X249453Y114307D03*
X254221Y230582D03*
X256492Y222466D03*
X254418Y240407D03*
X251491Y357134D03*
X244595Y363535D03*
X254813Y427018D03*
X246465Y464893D03*
X251780Y460883D03*
X257568Y461513D03*
X259678Y581553D03*
X249462Y648383D03*
X257271Y671772D03*
X244780Y682521D03*
X259170Y705138D03*
X258570Y722981D03*
X256650Y778342D03*
X247900Y778823D03*
X252470Y785797D03*
X271421Y7319D03*
X262955Y12663D03*
X266111Y29229D03*
X265789Y20990D03*
X268809Y16400D03*
X274990Y16396D03*
X272245Y89585D03*
X263703Y93847D03*
X262473Y106937D03*
X264980Y121886D03*
X260108Y240376D03*
X267118Y245587D03*
X270260Y237037D03*
X273521Y265849D03*
X263774Y256464D03*
X272464Y259964D03*
X261463Y296111D03*
X270444Y286183D03*
X261915Y302033D03*
X262700Y325494D03*
X263173Y331794D03*
X269886Y358753D03*
X260536Y374216D03*
X270293Y363972D03*
X270796Y386643D03*
X263419Y393450D03*
X265162Y401391D03*
X272220Y401343D03*
X274180Y424966D03*
X266822Y443297D03*
X263807Y461234D03*
X263924Y491754D03*
X269609Y576413D03*
X274309Y574653D03*
X261175Y569054D03*
X263792Y574203D03*
X268009Y570953D03*
X273480Y589201D03*
X269428Y622966D03*
X266610Y654171D03*
X261890Y664761D03*
X265550Y668415D03*
X274360Y673831D03*
X267240Y682519D03*
X269420Y677062D03*
X267124Y707892D03*
X273510Y699749D03*
X266170Y694826D03*
X260680Y712988D03*
X271210Y718000D03*
X264600Y723086D03*
X263430Y770417D03*
X264340Y778780D03*
X272175Y783074D03*
X284505Y30676D03*
X287766Y21289D03*
X276603Y92119D03*
X287423Y91857D03*
X279161Y237817D03*
X276904Y252550D03*
X282166Y262922D03*
X278811Y259135D03*
X281767Y277742D03*
X290363Y286082D03*
X281818Y290787D03*
X281205Y340997D03*
X289191Y341348D03*
X277040Y376172D03*
X286550Y374402D03*
X281450Y373151D03*
X285390Y390550D03*
X287067Y402358D03*
X276626Y442913D03*
X276347Y459741D03*
X279658Y574443D03*
X285530Y573002D03*
X283650Y589044D03*
X287997Y649064D03*
X280880Y650295D03*
X278699Y656491D03*
X289365Y673719D03*
X279843Y675688D03*
X275710Y681593D03*
X289248Y680521D03*
X286798Y704143D03*
X278370Y705093D03*
X277475Y695723D03*
X285130Y714433D03*
X275880Y722141D03*
X285880Y722268D03*
X280210Y734805D03*
X288390Y734796D03*
X284532Y747493D03*
X275627Y777692D03*
X281930Y773190D03*
X286722Y785929D03*
X301870Y92072D03*
X296870D03*
X291927Y102991D03*
X296927D03*
X302930Y132994D03*
X299776Y248010D03*
X301511Y262204D03*
X296210Y253187D03*
X292710Y266542D03*
X297810Y280709D03*
X294382Y291966D03*
X305880Y339046D03*
X299410Y331201D03*
X295527Y359812D03*
X293290Y389737D03*
X299533Y394056D03*
X300040Y459733D03*
X297370Y498563D03*
X305708Y503043D03*
X304410Y572782D03*
X301796Y603917D03*
X298303Y613184D03*
X293843Y642536D03*
X297394Y657033D03*
X302772Y659604D03*
X300880Y664296D03*
X295890Y662662D03*
X295950Y689520D03*
X293068Y677108D03*
X296858Y702544D03*
X297300Y697221D03*
X293300Y718944D03*
X298590Y733669D03*
X293480Y725080D03*
X293440Y748380D03*
X291340Y771217D03*
X295100Y786269D03*
X299249Y771403D03*
X304740Y777277D03*
X311553Y92347D03*
X310850Y99620D03*
X320740Y98599D03*
X311290Y247249D03*
X311740Y325839D03*
X314550Y331564D03*
X318480Y335039D03*
X319288Y350376D03*
X307410Y348380D03*
X313222Y374229D03*
X321297Y367739D03*
X310484Y383312D03*
X317140Y421775D03*
X321910Y410139D03*
X320080Y512736D03*
X320094Y604114D03*
X320512Y613603D03*
X308741Y623871D03*
X311311Y618197D03*
X316184Y662630D03*
Y687630D03*
X316165Y693404D03*
X319620Y716403D03*
X321930Y724895D03*
X314930Y724533D03*
X307146Y769416D03*
X315020Y780559D03*
X320657Y779595D03*
X320440Y771967D03*
X335668Y92822D03*
X330668D03*
X325360Y92517D03*
X325970Y98817D03*
X327190Y103818D03*
X337630Y106304D03*
X334720Y102184D03*
X331583Y128717D03*
X336720Y310846D03*
X337293Y316660D03*
X327058Y358376D03*
X336850Y380332D03*
X331090Y424304D03*
X331900Y419317D03*
X336740Y417069D03*
X335162Y502791D03*
X326740Y495763D03*
X329672Y502057D03*
X326170Y518386D03*
X335860Y516486D03*
X329348Y533403D03*
X332408Y544097D03*
X336057Y575657D03*
X323931Y589733D03*
X323346Y621930D03*
X337070Y639759D03*
X326350Y638968D03*
X324120Y703114D03*
X325560Y713391D03*
X338460Y724585D03*
X326280Y775980D03*
X337800Y774677D03*
X349490Y57698D03*
X352578Y74292D03*
X339750Y73383D03*
X353713Y93057D03*
X344873Y94847D03*
X340450Y101914D03*
X343743Y120967D03*
X351503Y127972D03*
X341693Y286010D03*
X340792Y307107D03*
X351650Y420270D03*
X345270Y452745D03*
X339506Y482841D03*
X348220Y486484D03*
X348870Y501571D03*
X343420Y497966D03*
X340902Y503742D03*
X341512Y512429D03*
X350902Y512520D03*
X346350Y517286D03*
X351964Y599332D03*
X348480Y638558D03*
X351730Y649206D03*
Y663450D03*
X351720Y670018D03*
X339300Y716800D03*
X342230Y720936D03*
X344710Y785782D03*
X350450Y784982D03*
X363025Y12926D03*
X366159Y21822D03*
X361930Y60031D03*
X367300Y60442D03*
X367776Y91746D03*
X358343Y90948D03*
X361470Y101757D03*
X367350Y123927D03*
X356835Y313894D03*
X367220Y303202D03*
X369934Y322946D03*
X364580Y391273D03*
X365850Y414874D03*
X354565Y451562D03*
X354750Y445325D03*
X368825Y539776D03*
X361473Y620588D03*
X365990Y645272D03*
X367870Y650239D03*
X364980Y655266D03*
X363340Y650512D03*
X365620Y663069D03*
X365380Y668972D03*
X364765Y687963D03*
X365090Y676923D03*
X364115Y692990D03*
X367520Y701710D03*
X357830Y718682D03*
X364750Y727821D03*
X364090Y748565D03*
X357610Y748302D03*
X354870Y771388D03*
X360160Y775523D03*
X363300Y781303D03*
X367904Y778327D03*
X381907Y21507D03*
X383280Y59940D03*
X376006Y60991D03*
X372776Y91746D03*
X380483Y99047D03*
X378733Y105987D03*
X384863Y95437D03*
X378183Y124904D03*
X372080Y330574D03*
X382190Y388077D03*
X371260Y412879D03*
X371950Y430527D03*
X375190Y463996D03*
X381239Y467171D03*
X376540Y498385D03*
X383617Y517862D03*
X376528Y520138D03*
X379733Y549392D03*
X370309Y550322D03*
X382333Y540414D03*
X385573Y629998D03*
X373218Y634217D03*
X382580Y637413D03*
X379492Y650239D03*
X376089Y646156D03*
X373680Y662417D03*
X376087Y670156D03*
X379461Y675246D03*
X379462Y666156D03*
X377681Y694244D03*
X377679Y701168D03*
X377669Y706237D03*
X376770Y734898D03*
X373500Y748457D03*
X397655Y21336D03*
X397790Y61360D03*
X390355Y75775D03*
X392493Y92647D03*
X400163Y99177D03*
X391310Y99570D03*
X398088Y128455D03*
X393088D03*
X399598Y260251D03*
X398258Y252341D03*
X394378Y260501D03*
X393458Y282931D03*
X392508Y275581D03*
X398038Y292571D03*
X390080Y331575D03*
X395740Y407528D03*
X392076Y470970D03*
X388982Y496939D03*
X396558Y522251D03*
X396470Y527847D03*
X396590Y549310D03*
X399590Y553502D03*
X393596Y567630D03*
X391447Y611973D03*
X394389Y604053D03*
X399223Y644930D03*
X394380Y643389D03*
X389856Y645705D03*
X400730Y721954D03*
X410713Y76187D03*
X404738Y260421D03*
X403148Y270191D03*
X403628Y292201D03*
X406352Y471405D03*
X410607Y485620D03*
X413138Y504813D03*
X407865Y516627D03*
X412088Y521721D03*
X407776Y527426D03*
X405954Y532502D03*
X404336Y545280D03*
X408486Y537333D03*
X408736Y551529D03*
X413342Y556219D03*
X412783Y605500D03*
X416454Y621319D03*
X413105Y613739D03*
X403904Y618333D03*
X403970Y642364D03*
X406100Y631851D03*
X413535Y646804D03*
X411982Y660285D03*
X413718Y655267D03*
X415218Y664203D03*
X411675Y672654D03*
X411065Y667516D03*
X414183Y686151D03*
X413643Y680004D03*
X414318Y700979D03*
X414080Y721334D03*
X409010Y726147D03*
X415780Y747078D03*
X421893Y123537D03*
X421640Y223403D03*
X428405Y245194D03*
X424961Y241203D03*
X418905Y245694D03*
X426992Y250016D03*
X422528Y253531D03*
X426335Y267062D03*
X420858Y261331D03*
X427817Y258829D03*
X421728Y279141D03*
X428748Y275222D03*
X418588Y286681D03*
X421128Y292601D03*
X423178Y284601D03*
X427909Y286759D03*
X427468Y292287D03*
X428747Y463314D03*
Y468770D03*
X422050Y517028D03*
X428039Y548119D03*
X421461Y547703D03*
X420883Y556729D03*
X431145Y556608D03*
X429340Y596874D03*
X431520Y607039D03*
X432180Y647458D03*
X425334Y656419D03*
X421080Y665945D03*
X427230Y707377D03*
X429240Y721014D03*
X421690Y779548D03*
X417880Y786361D03*
X428250Y772054D03*
X426900Y779752D03*
X446920Y78358D03*
X447715Y97926D03*
X444550Y184057D03*
X441580Y250730D03*
X443212Y240957D03*
X441792Y259473D03*
X445890Y283317D03*
X443240Y401984D03*
X437887Y471073D03*
X444920Y485259D03*
X437716Y476295D03*
X445199Y494590D03*
X439749Y506523D03*
X439762Y515540D03*
Y523757D03*
X434605Y521488D03*
X445838Y538085D03*
X441063Y540563D03*
X437832Y556374D03*
X442240Y553337D03*
X435319Y600123D03*
X437120Y612933D03*
X448460Y625960D03*
X437509Y648996D03*
X444700Y651900D03*
X447210Y665143D03*
X447161Y673564D03*
X444458Y669350D03*
X440688Y684438D03*
Y689438D03*
X440690Y702386D03*
X440688Y694438D03*
X440660Y712065D03*
X444370Y770152D03*
X434540Y778500D03*
X441006Y785297D03*
X458120Y44721D03*
X464170Y56436D03*
X461594Y99342D03*
X449538Y105144D03*
X453940Y98586D03*
X461880Y150596D03*
X462790Y183489D03*
X450650Y203785D03*
X450576Y234431D03*
X453620Y245162D03*
X451790Y300129D03*
X451504Y529734D03*
X450540Y521331D03*
X463991Y531504D03*
X456722Y529536D03*
X463031Y543563D03*
X453917Y550069D03*
X450367Y540720D03*
X453700Y545047D03*
X453854Y555069D03*
X462270Y612911D03*
X464050Y633877D03*
X458903Y644884D03*
X463178Y647483D03*
X460587Y669424D03*
X457138Y663251D03*
X449060Y721761D03*
X461565Y785806D03*
X463750Y780452D03*
X454120Y785923D03*
X475030Y63879D03*
X470324Y133424D03*
X474813Y162220D03*
X467473Y159766D03*
X473951Y157235D03*
X473950Y172124D03*
X475770Y186451D03*
X471300Y201900D03*
X466200Y207300D03*
X464810Y311253D03*
X480118Y479107D03*
Y474107D03*
X471804Y561085D03*
Y556085D03*
X468740Y585897D03*
X469890Y596580D03*
X476320Y629280D03*
X469229Y638135D03*
X475820Y635422D03*
X468810Y652180D03*
X479512Y649436D03*
X466980Y667059D03*
X479354Y677054D03*
X471780Y786300D03*
X486810Y60785D03*
X488438Y109623D03*
X494355Y108674D03*
X484350Y112811D03*
X487857Y152147D03*
X492424Y142234D03*
X494467Y148867D03*
X490130Y163086D03*
X493670Y171871D03*
X489040Y169483D03*
X482980Y181071D03*
X488850Y175419D03*
X487839Y194142D03*
X488017Y203716D03*
X486370Y189279D03*
X492700Y223800D03*
X484169Y272867D03*
X486300Y422150D03*
X481300D03*
X482880Y467935D03*
Y462935D03*
X490334Y497342D03*
X483209Y545250D03*
Y550250D03*
X490661Y547148D03*
X489962Y540849D03*
X483838Y566194D03*
Y556148D03*
Y561148D03*
Y571194D03*
X485738Y587125D03*
X490738D03*
X481340Y593296D03*
X494238Y600441D03*
X490600Y608136D03*
X489800Y600200D03*
X487832Y624429D03*
X480310Y642224D03*
X481253Y654837D03*
X484700Y660355D03*
X482398Y673087D03*
X482544Y668042D03*
X490120Y662703D03*
X481227Y685366D03*
Y691366D03*
X490900Y706145D03*
X481227Y696366D03*
X495560Y694781D03*
X488180Y719244D03*
X490890Y714898D03*
X488090Y710545D03*
X480770Y778125D03*
X485870Y776087D03*
X491720Y776713D03*
X495110Y771733D03*
X502900Y57670D03*
X500310Y109211D03*
X497430Y124024D03*
X504750Y111749D03*
X509691Y112938D03*
X509710Y127269D03*
X500215Y136449D03*
X502183Y156709D03*
X496360Y167221D03*
X498940Y179744D03*
X510000Y173500D03*
X509100Y191900D03*
X499225Y205296D03*
X506234Y207368D03*
X498867Y227773D03*
X504160Y255584D03*
X497111Y388567D03*
X502111D03*
X505819Y417473D03*
X498238Y417825D03*
X499551Y429636D03*
X502494Y436725D03*
X509486Y433829D03*
X506456Y446928D03*
X502938Y463823D03*
X498119Y470011D03*
X511230Y499059D03*
X506230D03*
X504613Y525200D03*
X503338Y549825D03*
Y544825D03*
X500538Y588525D03*
Y600925D03*
X508400Y617803D03*
X502080Y622999D03*
X505690Y654419D03*
X508061Y645381D03*
X504295Y649612D03*
X504114Y670830D03*
X496453Y670876D03*
X501914Y675624D03*
X504241Y665809D03*
X497320Y665216D03*
X496577Y684553D03*
X505580Y679105D03*
X496277Y678185D03*
X501540Y681970D03*
X506409Y691373D03*
X497350Y699767D03*
X506092Y697575D03*
X501604Y733003D03*
X501890Y746663D03*
X507935Y785704D03*
X511770Y779940D03*
X499270Y776431D03*
X504440Y772548D03*
X513120Y72069D03*
X512878Y108635D03*
X519625Y108543D03*
X526835Y108314D03*
X516146Y113121D03*
X522111Y113310D03*
X518640Y125539D03*
X515600Y172800D03*
X521320Y178184D03*
X516100Y178100D03*
X526621Y177079D03*
X515231Y191334D03*
X520015Y194584D03*
X523593Y198171D03*
X512200Y196000D03*
X520068Y207142D03*
X516551Y214987D03*
X517670Y247527D03*
X515675Y254098D03*
X525480Y268959D03*
X527438Y340353D03*
X517617Y422944D03*
X514820Y417617D03*
X526440Y422428D03*
X527300Y417368D03*
X517929Y439676D03*
X512867Y443679D03*
X525638Y484023D03*
X514058Y605055D03*
X526300Y623621D03*
X518920Y615387D03*
X514320Y641085D03*
X525692Y654862D03*
X517328Y655529D03*
X521516Y650576D03*
X517222Y673917D03*
X518800Y665776D03*
X515541Y661845D03*
X526430Y664730D03*
X515429Y692278D03*
X526600Y679117D03*
X517888Y687901D03*
X527111Y686052D03*
X515429Y697278D03*
X512548Y722093D03*
X512610Y747115D03*
X525110Y774395D03*
X519440Y772861D03*
X539510Y108742D03*
X536955Y100257D03*
X535960Y112850D03*
X527613Y113373D03*
X539500Y196500D03*
X536232Y192086D03*
X529592Y192999D03*
X533474Y196500D03*
X541657Y207645D03*
X532320Y209470D03*
X534208Y227832D03*
X528105Y230594D03*
X535772Y250076D03*
X539267Y267102D03*
X530119Y280101D03*
X541650Y422280D03*
X529968Y440216D03*
X529028Y430469D03*
X535352Y440414D03*
X540141Y442994D03*
X529408Y603485D03*
X542848Y602975D03*
X535048Y602885D03*
X532420Y615484D03*
X542424Y654821D03*
X536557Y655498D03*
X529525Y669349D03*
X529899Y661020D03*
X539734Y675020D03*
X539577Y721891D03*
X540062Y708779D03*
X539650Y780942D03*
X529300Y771341D03*
X533600Y778780D03*
X557995Y110244D03*
X550490Y112989D03*
X552173Y138528D03*
X550599Y132596D03*
X550550Y151682D03*
X558059Y154254D03*
X558348Y142511D03*
X551464Y143862D03*
X550604Y168072D03*
X550370Y157461D03*
X557668Y176534D03*
X551395Y174172D03*
X544500Y197500D03*
X546000Y192000D03*
X557909Y207537D03*
X547148Y220220D03*
X545703Y245725D03*
X545981Y236287D03*
X545116Y266847D03*
X547929Y258102D03*
X545223Y276895D03*
X557207Y280328D03*
X555072Y289563D03*
X552090Y388953D03*
X553230Y407251D03*
X549574Y432582D03*
X546384Y445107D03*
X547488Y452373D03*
X554550Y469674D03*
X545513Y469740D03*
X547638Y462356D03*
X546038Y457523D03*
X546250Y490302D03*
X554860Y531701D03*
X549920Y527242D03*
X550149Y604639D03*
X543400Y625963D03*
X552350Y614028D03*
X558281Y637840D03*
X551030Y637200D03*
X543400Y635615D03*
X549314Y647594D03*
X551230Y652844D03*
X551283Y670800D03*
Y699243D03*
X544934Y720820D03*
X550535Y721903D03*
X555551Y722342D03*
X557488Y713709D03*
X553725Y717251D03*
X550004Y709559D03*
X555062Y708679D03*
X545062D03*
X557978Y734053D03*
X545300Y783152D03*
X550940Y771858D03*
X554870Y779438D03*
X569559Y103123D03*
X564076Y145372D03*
X563410Y165289D03*
X562195Y159015D03*
X563129Y178369D03*
X569682Y195199D03*
X564274Y279395D03*
X561525Y298192D03*
X560865Y285434D03*
X565953Y301635D03*
X565310Y412700D03*
X572440Y464323D03*
Y469323D03*
X562340Y484252D03*
X567791Y528325D03*
X562308Y536895D03*
X566298Y548465D03*
X563188Y541925D03*
X566338Y554235D03*
X561174Y564471D03*
X574738Y579525D03*
X565858Y576195D03*
X561198Y581793D03*
X566378Y567725D03*
X561608Y571775D03*
X574537Y591325D03*
X565398Y584765D03*
X568163Y595115D03*
X561568Y589355D03*
X574071Y606204D03*
X568930Y607754D03*
X574730Y625521D03*
X565647Y637705D03*
X565556Y632431D03*
X571790Y646799D03*
X559440Y650767D03*
X566950Y659439D03*
X565168Y664614D03*
Y674614D03*
Y669614D03*
Y684614D03*
Y679614D03*
Y689614D03*
Y694614D03*
Y699614D03*
X560544Y718091D03*
X569604Y721248D03*
X574190Y717805D03*
X564319Y721587D03*
X562540Y713454D03*
X560062Y708679D03*
X570614Y713237D03*
X565062Y708679D03*
X566798Y734023D03*
X569680Y771106D03*
X560150Y781347D03*
X562700Y772391D03*
X572720Y777184D03*
X578938Y103123D03*
X580501Y138336D03*
X583829Y132232D03*
X587968Y138765D03*
X581565Y154969D03*
X579897Y161355D03*
X582792Y167632D03*
X581915Y179955D03*
X588692Y192809D03*
X585580Y210516D03*
X579707Y229395D03*
X585579Y230095D03*
X588607Y305034D03*
X576650Y311446D03*
X581650D03*
X585984Y323246D03*
X589070Y423525D03*
X578830Y448192D03*
X585013Y547959D03*
X576208Y542405D03*
X575838Y548935D03*
X577778Y556355D03*
X588780Y611056D03*
X586810Y603344D03*
X588780Y616056D03*
X583930Y652439D03*
X577217Y652002D03*
X576987Y660180D03*
X580637Y663629D03*
X584312Y710716D03*
X583440Y724927D03*
X577570Y734118D03*
X587170Y773768D03*
X579240Y775147D03*
X605070Y123991D03*
X600118Y112568D03*
X592938Y117657D03*
Y140689D03*
Y133232D03*
X594938Y127893D03*
X591707Y230162D03*
X595374Y236795D03*
X594374Y271395D03*
X596574Y276393D03*
X593607Y305034D03*
X590984Y323246D03*
X604338Y338285D03*
X597440Y391690D03*
X590720Y456076D03*
X591100Y450128D03*
X605800Y463167D03*
X603819Y485332D03*
X605798Y501238D03*
X596751Y532108D03*
X603010Y527908D03*
X604820Y555040D03*
X592437Y566543D03*
X601043Y567781D03*
X605396Y590552D03*
X605286Y584152D03*
X593867Y595695D03*
X602314Y607641D03*
Y602641D03*
X593867Y600695D03*
X591279Y656223D03*
X596998Y658008D03*
X600736Y668425D03*
X600719Y675156D03*
X597300Y663128D03*
X600690Y691896D03*
X600727Y681876D03*
Y686876D03*
X604220Y703774D03*
X592960Y703291D03*
X601856Y711479D03*
X595950Y708997D03*
X594170Y719290D03*
X603938Y753623D03*
X606270Y774615D03*
X597530Y780191D03*
X592480Y771514D03*
X610543Y107678D03*
X617925Y114064D03*
X613432Y153528D03*
X610415Y237441D03*
X617778Y238873D03*
X613640Y336986D03*
X607671Y344818D03*
X611848Y359784D03*
X607855Y352341D03*
X618581Y354818D03*
X620238Y364369D03*
X609078Y388557D03*
Y393557D03*
X612641Y397478D03*
Y402478D03*
X611050Y423087D03*
X616258Y422211D03*
X610580Y448662D03*
X610010Y456581D03*
X617980Y460408D03*
X621760Y526967D03*
X613470Y537495D03*
X610070Y557588D03*
X610821Y566494D03*
X621937Y567143D03*
X609026Y579132D03*
X617270Y580443D03*
X611520Y596594D03*
X611254Y617943D03*
X615690Y625536D03*
X616730Y633290D03*
X611572Y629894D03*
X613796Y648705D03*
X612950Y656140D03*
X613200Y661577D03*
X620160Y670594D03*
X615940Y666862D03*
X612670Y681438D03*
X612811Y688422D03*
X607380Y699671D03*
X617930Y703520D03*
X620480Y693827D03*
X609070Y721917D03*
X613730Y717663D03*
X620670Y722216D03*
X619080Y772610D03*
X619030Y778682D03*
X612260Y783106D03*
X609347Y778624D03*
X628838Y120216D03*
X628738Y133012D03*
X624800Y184953D03*
Y179953D03*
X634962Y200121D03*
Y195121D03*
X634212Y281670D03*
X624383Y292591D03*
X631672Y301066D03*
X633773Y310439D03*
X628141Y344818D03*
X634511Y389156D03*
X630691Y405007D03*
Y410007D03*
X636586Y410910D03*
X635840Y449890D03*
X634945Y461888D03*
X628250Y471142D03*
X630420Y491511D03*
X636170Y493028D03*
X622600Y488753D03*
X622199Y506535D03*
X632157Y511230D03*
X625130Y534199D03*
X634530Y521565D03*
X634190Y538267D03*
X636890Y571351D03*
X624870Y573143D03*
X627084Y578257D03*
X634921Y580163D03*
X623940Y628720D03*
X636890Y627095D03*
X629781Y628559D03*
X622510Y635544D03*
X634137Y631342D03*
X627146Y638932D03*
X633970Y723033D03*
X628160Y722343D03*
X636170Y729335D03*
X632300Y749755D03*
X636910Y745815D03*
X624010Y746351D03*
X629912Y769200D03*
X625010Y778281D03*
X639200Y170100D03*
X639350Y250123D03*
X649995Y296433D03*
X640647Y339854D03*
X639838Y349818D03*
X648425Y373474D03*
X652139Y377125D03*
X641236Y381616D03*
X645236Y377858D03*
X650822Y425295D03*
X647280Y446851D03*
X651080Y455238D03*
X652110Y465238D03*
X646600Y463571D03*
X648956Y469323D03*
X650521Y482930D03*
X647921Y475778D03*
X646105Y492010D03*
X650790Y497730D03*
X646906Y505210D03*
X646460Y512967D03*
X652690Y531693D03*
X645040Y524444D03*
X639673Y576888D03*
X651437Y578943D03*
X644636Y627257D03*
X646940Y643448D03*
X641263Y631393D03*
X649173Y629876D03*
X647870Y649784D03*
X646580Y654775D03*
X652660Y749000D03*
X646680Y755009D03*
X646500Y746300D03*
X638470Y762212D03*
X647410Y767053D03*
X651690Y778099D03*
X640010Y778215D03*
X655947Y53677D03*
X655642Y144915D03*
Y149915D03*
X655695Y159567D03*
Y164567D03*
X655030Y228744D03*
Y223744D03*
X657838Y243407D03*
Y238407D03*
X660899Y311515D03*
X654962Y307698D03*
X668925Y364887D03*
X663632Y366698D03*
X669215Y377488D03*
X655812Y424106D03*
X664450Y435739D03*
X664528Y463432D03*
X660458Y470932D03*
X659828Y465162D03*
X667774Y477992D03*
X661158Y486152D03*
X667070Y483608D03*
X662780Y477039D03*
X660518Y492862D03*
X654240Y511568D03*
X653800Y505331D03*
X659933Y513927D03*
X668573Y514155D03*
X659740Y536019D03*
X667050Y535324D03*
X658980Y610043D03*
X663560Y625019D03*
X654221Y631425D03*
X657550Y655072D03*
X659978Y666274D03*
X657340Y690286D03*
X659300Y734119D03*
X657500Y761500D03*
X669987Y53672D03*
X679590Y352829D03*
X677083Y375124D03*
X673368Y416621D03*
X671056Y426300D03*
X673740Y449887D03*
X682764Y444832D03*
X677070Y444820D03*
X679299Y491473D03*
X674156Y503662D03*
X677160Y529422D03*
X675044Y524581D03*
X678386Y668420D03*
X673386D03*
X681480Y777388D03*
X681164Y783461D03*
X669810Y786721D03*
X672500Y779579D03*
X687546Y154228D03*
X689480Y194615D03*
X687869Y386780D03*
X688118Y381043D03*
X685859Y403970D03*
X691037Y401739D03*
X689017Y497282D03*
X694823Y498932D03*
X689729Y509580D03*
X696891Y507279D03*
X686770Y543325D03*
X691532Y563789D03*
Y575789D03*
Y583789D03*
X685640Y634154D03*
X698386Y667241D03*
X693386D03*
X699600Y776000D03*
X689700Y774500D03*
X711676Y51019D03*
X712239Y452293D03*
X704550Y444407D03*
X704766Y498880D03*
X713978Y498075D03*
X716021Y516945D03*
X700829Y504041D03*
X707920Y505575D03*
X706361Y532632D03*
X716260Y525295D03*
X712740Y593101D03*
X713742Y634373D03*
X708386Y669774D03*
X703386D03*
X713445Y677641D03*
X704000Y770800D03*
X731566Y442136D03*
X726580Y455637D03*
X731570Y464043D03*
X726830Y460815D03*
X727940Y469943D03*
X720140Y478333D03*
X719761Y532432D03*
X727830Y641829D03*
X728690Y649829D03*
X718445Y677641D03*
X736310Y450774D03*
X737350Y464330D03*
X734575Y492575D03*
X745500Y492500D03*
X744020Y566143D03*
X743951Y578833D03*
X744050Y571834D03*
X744000Y647919D03*
X733210Y645829D03*
X732540Y653829D03*
X758223Y446532D03*
X748723Y455332D03*
X752960Y653967D03*
X771110Y578643D03*
X770850Y587025D03*
X1088471Y857245D03*
G54D26*
X354348Y38554D03*
X393718D03*
X1088471Y377995D03*
G54D35*
X590999Y69167D03*
Y77041D03*
Y84915D03*
Y92789D03*
X615657Y69167D03*
Y77041D03*
Y84915D03*
Y92789D03*
X1088471Y697495D03*
G54D36*
X605796Y165160D03*
X609733Y215672D03*
X1088471Y505795D03*
G54D18*
X36024Y187233D03*
Y181225D03*
Y205257D03*
Y199249D03*
Y193241D03*
Y217272D03*
Y211264D03*
X41930Y184229D03*
Y178221D03*
Y202253D03*
Y196245D03*
Y190237D03*
Y220276D03*
Y214268D03*
Y208260D03*
X1088471Y729445D03*
G54D27*
X399606Y377165D03*
X413386Y363385D03*
X403543Y367322D03*
Y387008D03*
X413386Y390945D03*
X427166Y377165D03*
X423229Y367322D03*
Y387008D03*
X1088471Y793345D03*
G54D28*
X414961Y98622D03*
X1088471Y346045D03*
G54D19*
X40749Y150808D03*
Y249194D03*
X1088471Y26545D03*
G54D37*
X605796Y174845D03*
Y189845D03*
Y204845D03*
X611702Y185690D03*
Y178997D03*
Y200690D03*
Y193997D03*
X1088471Y761395D03*
G54D29*
X413386Y377165D03*
X1088471Y58495D03*
G54D38*
X688977Y105315D03*
Y719488D03*
X1088471Y90445D03*
G54D39*
X711575Y143555D03*
Y195355D03*
Y222361D03*
Y274161D03*
X733975Y143555D03*
Y195355D03*
Y222361D03*
Y274161D03*
X1088471Y441895D03*
M02*
